G04 ================== begin FILE IDENTIFICATION RECORD ==================*
G04 Layout Name:  D:/<user>/Wistron_project/16317-1/gbr/16317-1.brd*
G04 Film Name:    DRILL*
G04 File Format:  Gerber RS274X*
G04 File Origin:  Cadence Allegro 16.5-S056*
G04 Origin Date:  Fri Jun 09 15:52:50 2017*
G04 *
G04 Layer:  MANUFACTURING/NCLEGEND-1-8*
G04 Layer:  MANUFACTURING/DRILL SIZE*
G04 Layer:  DRAWING FORMAT/LAYER_PCB_STORY*
G04 Layer:  DRAWING FORMAT/LAYER_DRILL*
G04 Layer:  BOARD GEOMETRY/PANEL_OUTLINE*
G04 *
G04 Offset:    (0.00 0.00)*
G04 Mirror:    No*
G04 Mode:      Positive*
G04 Rotation:  0*
G04 FullContactRelief:  No*
G04 UndefLineWidth:     6.00*
G04 ================== end FILE IDENTIFICATION RECORD ====================*
%FSLAX35Y35*MOIN*%
%IR0*IPPOS*OFA0.00000B0.00000*MIA0B0*SFA1.00000B1.00000*%
%AMMACRO14*
1,1,.006,.005,.005*
20,1,.006,.005,.005,.005,-.005,0.0*
1,1,.006,.005,-.005*
20,1,.006,.005,-.005,-.005,-.005,0.0*
1,1,.006,-.005,-.005*
20,1,.006,-.005,-.005,-.005,.005,0.0*
1,1,.006,-.005,.005*
20,1,.006,-.005,.005,.005,.005,0.0*
1,1,.006,.005,.005*
1,1,.006,-.00158,.00167*
20,1,.006,-.00158,.00167,-.00108,.00217,0.0*
1,1,.006,-.00108,.00217*
20,1,.006,-.00108,.00217,-.0005,.00242,0.0*
1,1,.006,-.0005,.00242*
20,1,.006,-.0005,.00242,.00017,.0025,0.0*
1,1,.006,.00017,.0025*
20,1,.006,.00017,.0025,.001,.00233,0.0*
1,1,.006,.001,.00233*
20,1,.006,.001,.00233,.00158,.00192,0.0*
1,1,.006,.00158,.00192*
20,1,.006,.00158,.00192,.00175,.00142,0.0*
1,1,.006,.00175,.00142*
20,1,.006,.00175,.00142,.00167,.00092,0.0*
1,1,.006,.00167,.00092*
20,1,.006,.00167,.00092,.00133,.0005,0.0*
1,1,.006,.00133,.0005*
20,1,.006,.00133,.0005,-.00033,-.00033,0.0*
1,1,.006,-.00033,-.00033*
20,1,.006,-.00033,-.00033,-.00108,-.00092,0.0*
1,1,.006,-.00108,-.00092*
20,1,.006,-.00108,-.00092,-.00158,-.00175,0.0*
1,1,.006,-.00158,-.00175*
20,1,.006,-.00158,-.00175,-.00175,-.0025,0.0*
1,1,.006,-.00175,-.0025*
20,1,.006,-.00175,-.0025,.00175,-.0025,0.0*
1,1,.006,.00175,-.0025*
%
%ADD14MACRO14*%
%AMMACRO19*
1,1,.006,.0005,0.0*
20,1,.006,.0005,0.0,-.0005,0.0,0.0*
1,1,.006,-.0005,0.0*
1,1,.006,0.0,.0005*
20,1,.006,0.0,.0005,0.0,-.0005,0.0*
1,1,.006,0.0,-.0005*
1,1,.006,.00025,0.0*
20,1,.006,.00025,0.0,.00025,.0005,0.0*
1,1,.006,.00025,.0005*
20,1,.006,.00025,.0005,.00015,.0004,0.0*
1,1,.006,.00015,.0004*
1,1,.006,.00015,0.0*
20,1,.006,.00015,0.0,.00035,0.0,0.0*
1,1,.006,.00035,0.0*
%
%ADD19MACRO19*%
%AMMACRO16*
1,1,.006,-.05834,-.07*
20,1,.006,-.05834,-.07,0.0,.07,0.0*
1,1,.006,0.0,.07*
20,1,.006,0.0,.07,.05834,-.07,0.0*
1,1,.006,.05834,-.07*
1,1,.006,.03733,-.021*
20,1,.006,.03733,-.021,-.03734,-.021,0.0*
1,1,.006,-.03734,-.021*
%
%ADD16MACRO16*%
%AMMACRO18*
1,1,.006,-.03515,-.0555*
20,1,.006,-.03515,-.0555,-.03515,.0555,0.0*
1,1,.006,-.03515,.0555*
20,1,.006,-.03515,.0555,.03515,.0555,0.0*
1,1,.006,.03515,.0555*
1,1,.006,.00925,.00185*
20,1,.006,.00925,.00185,-.03515,.00185,0.0*
1,1,.006,-.03515,.00185*
%
%ADD18MACRO18*%
%AMMACRO12*
1,1,.006,.008,0.0*
20,1,.006,.008,0.0,0.0,-.008,0.0*
1,1,.006,0.0,-.008*
20,1,.006,0.0,-.008,-.008,0.0,0.0*
1,1,.006,-.008,0.0*
20,1,.006,-.008,0.0,0.0,.008,0.0*
1,1,.006,0.0,.008*
20,1,.006,0.0,.008,.008,0.0,0.0*
1,1,.006,.008,0.0*
1,1,.006,-.00253,-.00067*
20,1,.006,-.00253,-.00067,-.0016,.00027,0.0*
1,1,.006,-.0016,.00027*
20,1,.006,-.0016,.00027,-.0008,.0008,0.0*
1,1,.006,-.0008,.0008*
20,1,.006,-.0008,.0008,.00027,.00107,0.0*
1,1,.006,.00027,.00107*
20,1,.006,.00027,.00107,.0012,.0008,0.0*
1,1,.006,.0012,.0008*
20,1,.006,.0012,.0008,.00187,.00027,0.0*
1,1,.006,.00187,.00027*
20,1,.006,.00187,.00027,.0024,-.00053,0.0*
1,1,.006,.0024,-.00053*
20,1,.006,.0024,-.00053,.00253,-.00147,0.0*
1,1,.006,.00253,-.00147*
20,1,.006,.00253,-.00147,.0024,-.00227,0.0*
1,1,.006,.0024,-.00227*
20,1,.006,.0024,-.00227,.00187,-.00307,0.0*
1,1,.006,.00187,-.00307*
20,1,.006,.00187,-.00307,.00107,-.00373,0.0*
1,1,.006,.00107,-.00373*
20,1,.006,.00107,-.00373,.00013,-.004,0.0*
1,1,.006,.00013,-.004*
20,1,.006,.00013,-.004,-.00093,-.00373,0.0*
1,1,.006,-.00093,-.00373*
20,1,.006,-.00093,-.00373,-.00187,-.00293,0.0*
1,1,.006,-.00187,-.00293*
20,1,.006,-.00187,-.00293,-.0024,-.00173,0.0*
1,1,.006,-.0024,-.00173*
20,1,.006,-.0024,-.00173,-.00253,-.0004,0.0*
1,1,.006,-.00253,-.0004*
20,1,.006,-.00253,-.0004,-.00227,.00133,0.0*
1,1,.006,-.00227,.00133*
20,1,.006,-.00227,.00133,-.00187,.00227,0.0*
1,1,.006,-.00187,.00227*
20,1,.006,-.00187,.00227,-.0012,.0032,0.0*
1,1,.006,-.0012,.0032*
20,1,.006,-.0012,.0032,-.00027,.00387,0.0*
1,1,.006,-.00027,.00387*
20,1,.006,-.00027,.00387,.00067,.004,0.0*
1,1,.006,.00067,.004*
20,1,.006,.00067,.004,.0016,.00373,0.0*
1,1,.006,.0016,.00373*
20,1,.006,.0016,.00373,.00227,.00307,0.0*
1,1,.006,.00227,.00307*
%
%ADD12MACRO12*%
%AMMACRO27*
1,1,.006,.002935,-.007085*
20,1,.006,.002935,-.007085,-.002935,-.007085,0.0*
1,1,.006,-.002935,-.007085*
20,1,.006,-.002935,-.007085,-.007085,-.002935,0.0*
1,1,.006,-.007085,-.002935*
20,1,.006,-.007085,-.002935,-.007085,.002935,0.0*
1,1,.006,-.007085,.002935*
20,1,.006,-.007085,.002935,-.002935,.007085,0.0*
1,1,.006,-.002935,.007085*
20,1,.006,-.002935,.007085,.002935,.007085,0.0*
1,1,.006,.002935,.007085*
20,1,.006,.002935,.007085,.007085,.002935,0.0*
1,1,.006,.007085,.002935*
20,1,.006,.007085,.002935,.007085,-.002935,0.0*
1,1,.006,.007085,-.002935*
20,1,.006,.007085,-.002935,.002935,-.007085,0.0*
1,1,.006,.002935,-.007085*
1,1,.006,-.0026,-.00248*
20,1,.006,-.0026,-.00248,-.00189,-.00307,0.0*
1,1,.006,-.00189,-.00307*
20,1,.006,-.00189,-.00307,-.00106,-.00342,0.0*
1,1,.006,-.00106,-.00342*
20,1,.006,-.00106,-.00342,0.0,-.00354,0.0*
1,1,.006,0.0,-.00354*
20,1,.006,0.0,-.00354,.00106,-.0033,0.0*
1,1,.006,.00106,-.0033*
20,1,.006,.00106,-.0033,.00189,-.00283,0.0*
1,1,.006,.00189,-.00283*
20,1,.006,.00189,-.00283,.00248,-.00201,0.0*
1,1,.006,.00248,-.00201*
20,1,.006,.00248,-.00201,.0026,-.00106,0.0*
1,1,.006,.0026,-.00106*
20,1,.006,.0026,-.00106,.00236,-.00012,0.0*
1,1,.006,.00236,-.00012*
20,1,.006,.00236,-.00012,.00177,.00047,0.0*
1,1,.006,.00177,.00047*
20,1,.006,.00177,.00047,.00094,.00094,0.0*
1,1,.006,.00094,.00094*
20,1,.006,.00094,.00094,.00012,.00106,0.0*
1,1,.006,.00012,.00106*
20,1,.006,.00012,.00106,-.00071,.00094,0.0*
1,1,.006,-.00071,.00094*
20,1,.006,-.00071,.00094,-.00177,.00047,0.0*
1,1,.006,-.00177,.00047*
20,1,.006,-.00177,.00047,-.00142,.00354,0.0*
1,1,.006,-.00142,.00354*
20,1,.006,-.00142,.00354,.00177,.00354,0.0*
1,1,.006,.00177,.00354*
%
%ADD27MACRO27*%
%AMMACRO17*
1,1,.006,.01943,.02208*
20,1,.006,.01943,.02208,.01413,.02473,0.0*
1,1,.006,.01413,.02473*
20,1,.006,.01413,.02473,.00795,.0265,0.0*
1,1,.006,.00795,.0265*
20,1,.006,.00795,.0265,.00088,.0265,0.0*
1,1,.006,.00088,.0265*
20,1,.006,.00088,.0265,-.00707,.02385,0.0*
1,1,.006,-.00707,.02385*
20,1,.006,-.00707,.02385,-.01325,.01943,0.0*
1,1,.006,-.01325,.01943*
20,1,.006,-.01325,.01943,-.01767,.01413,0.0*
1,1,.006,-.01767,.01413*
20,1,.006,-.01767,.01413,-.0212,.0053,0.0*
1,1,.006,-.0212,.0053*
20,1,.006,-.0212,.0053,-.02208,-.00265,0.0*
1,1,.006,-.02208,-.00265*
20,1,.006,-.02208,-.00265,-.02032,-.0106,0.0*
1,1,.006,-.02032,-.0106*
20,1,.006,-.02032,-.0106,-.01767,-.0159,0.0*
1,1,.006,-.01767,-.0159*
20,1,.006,-.01767,-.0159,-.01237,-.0212,0.0*
1,1,.006,-.01237,-.0212*
20,1,.006,-.01237,-.0212,-.00618,-.02473,0.0*
1,1,.006,-.00618,-.02473*
20,1,.006,-.00618,-.02473,0.0,-.0265,0.0*
1,1,.006,0.0,-.0265*
20,1,.006,0.0,-.0265,.00618,-.0265,0.0*
1,1,.006,.00618,-.0265*
20,1,.006,.00618,-.0265,.01237,-.02473,0.0*
1,1,.006,.01237,-.02473*
20,1,.006,.01237,-.02473,.01767,-.02208,0.0*
1,1,.006,.01767,-.02208*
20,1,.006,.01767,-.02208,.02208,-.01855,0.0*
1,1,.006,.02208,-.01855*
%
%ADD17MACRO17*%
%AMMACRO26*
1,1,.006,-.13467,-.1212*
20,1,.006,-.13467,-.1212,-.101,-.16161,0.0*
1,1,.006,-.101,-.16161*
20,1,.006,-.101,-.16161,-.06061,-.18854,0.0*
1,1,.006,-.06061,-.18854*
20,1,.006,-.06061,-.18854,-.01347,-.202,0.0*
1,1,.006,-.01347,-.202*
20,1,.006,-.01347,-.202,.0404,-.18854,0.0*
1,1,.006,.0404,-.18854*
20,1,.006,.0404,-.18854,.0808,-.16161,0.0*
1,1,.006,.0808,-.16161*
20,1,.006,.0808,-.16161,.1212,-.1212,0.0*
1,1,.006,.1212,-.1212*
20,1,.006,.1212,-.1212,.13467,-.06734,0.0*
1,1,.006,.13467,-.06734*
20,1,.006,.13467,-.06734,.13467,.202,0.0*
1,1,.006,.13467,.202*
%
%ADD26MACRO26*%
%AMMACRO22*
1,1,.006,-.0441,-.063*
20,1,.006,-.0441,-.063,-.0441,.063,0.0*
1,1,.006,-.0441,.063*
1,1,.006,.0441,.063*
20,1,.006,.0441,.063,.0441,-.063,0.0*
1,1,.006,.0441,-.063*
1,1,.006,.0441,0.0*
20,1,.006,.0441,0.0,-.0441,0.0,0.0*
1,1,.006,-.0441,0.0*
%
%ADD22MACRO22*%
%AMMACRO15*
1,1,.006,.00493,.00123*
20,1,.006,.00493,.00123,.0074,.00308,0.0*
1,1,.006,.0074,.00308*
20,1,.006,.0074,.00308,.00925,.00617,0.0*
1,1,.006,.00925,.00617*
20,1,.006,.00925,.00617,.01048,.01048,0.0*
1,1,.006,.01048,.01048*
20,1,.006,.01048,.01048,.00925,.01418,0.0*
1,1,.006,.00925,.01418*
20,1,.006,.00925,.01418,.00678,.01665,0.0*
1,1,.006,.00678,.01665*
20,1,.006,.00678,.01665,.00247,.0185,0.0*
1,1,.006,.00247,.0185*
20,1,.006,.00247,.0185,-.01418,.0185,0.0*
1,1,.006,-.01418,.0185*
20,1,.006,-.01418,.0185,-.01418,-.0185,0.0*
1,1,.006,-.01418,-.0185*
20,1,.006,-.01418,-.0185,.00617,-.0185,0.0*
1,1,.006,.00617,-.0185*
20,1,.006,.00617,-.0185,.01048,-.01603,0.0*
1,1,.006,.01048,-.01603*
20,1,.006,.01048,-.01603,.01295,-.01233,0.0*
1,1,.006,.01295,-.01233*
20,1,.006,.01295,-.01233,.01418,-.00802,0.0*
1,1,.006,.01418,-.00802*
20,1,.006,.01418,-.00802,.01295,-.0037,0.0*
1,1,.006,.01295,-.0037*
20,1,.006,.01295,-.0037,.00925,0.0,0.0*
1,1,.006,.00925,0.0*
20,1,.006,.00925,0.0,.00493,.00123,0.0*
1,1,.006,.00493,.00123*
20,1,.006,.00493,.00123,-.01418,.00123,0.0*
1,1,.006,-.01418,.00123*
%
%ADD15MACRO15*%
%AMMACRO21*
1,1,.006,.0119,0.0*
20,1,.006,.0119,0.0,.05157,0.0,0.0*
1,1,.006,.05157,0.0*
20,1,.006,.05157,0.0,.05157,-.0357,0.0*
1,1,.006,.05157,-.0357*
20,1,.006,.05157,-.0357,.03967,-.0476,0.0*
1,1,.006,.03967,-.0476*
20,1,.006,.03967,-.0476,.02578,-.05553,0.0*
1,1,.006,.02578,-.05553*
20,1,.006,.02578,-.05553,.00595,-.0595,0.0*
1,1,.006,.00595,-.0595*
20,1,.006,.00595,-.0595,-.01388,-.05553,0.0*
1,1,.006,-.01388,-.05553*
20,1,.006,-.01388,-.05553,-.02777,-.0476,0.0*
1,1,.006,-.02777,-.0476*
20,1,.006,-.02777,-.0476,-.03967,-.0357,0.0*
1,1,.006,-.03967,-.0357*
20,1,.006,-.03967,-.0357,-.0476,-.02182,0.0*
1,1,.006,-.0476,-.02182*
20,1,.006,-.0476,-.02182,-.05157,-.00595,0.0*
1,1,.006,-.05157,-.00595*
20,1,.006,-.05157,-.00595,-.05157,.00793,0.0*
1,1,.006,-.05157,.00793*
20,1,.006,-.05157,.00793,-.0476,.01983,0.0*
1,1,.006,-.0476,.01983*
20,1,.006,-.0476,.01983,-.03967,.03372,0.0*
1,1,.006,-.03967,.03372*
20,1,.006,-.03967,.03372,-.02777,.04562,0.0*
1,1,.006,-.02777,.04562*
20,1,.006,-.02777,.04562,-.01587,.05355,0.0*
1,1,.006,-.01587,.05355*
20,1,.006,-.01587,.05355,0.0,.0595,0.0*
1,1,.006,0.0,.0595*
20,1,.006,0.0,.0595,.01388,.0595,0.0*
1,1,.006,.01388,.0595*
20,1,.006,.01388,.0595,.02975,.05553,0.0*
1,1,.006,.02975,.05553*
20,1,.006,.02975,.05553,.04165,.0476,0.0*
1,1,.006,.04165,.0476*
%
%ADD21MACRO21*%
%AMMACRO30*
1,1,.006,-.0276,.069*
20,1,.006,-.0276,.069,.0276,.069,0.0*
1,1,.006,.0276,.069*
1,1,.006,0.0,.069*
20,1,.006,0.0,.069,0.0,-.069,0.0*
1,1,.006,0.0,-.069*
1,1,.006,-.0276,-.069*
20,1,.006,-.0276,-.069,.0276,-.069,0.0*
1,1,.006,.0276,-.069*
%
%ADD30MACRO30*%
%AMMACRO10*
1,1,.006,-.03153,-.043*
20,1,.006,-.03153,-.043,-.03153,.043,0.0*
1,1,.006,-.03153,.043*
20,1,.006,-.03153,.043,-.00287,.043,0.0*
1,1,.006,-.00287,.043*
20,1,.006,-.00287,.043,.0086,.0387,0.0*
1,1,.006,.0086,.0387*
20,1,.006,.0086,.0387,.0172,.03297,0.0*
1,1,.006,.0172,.03297*
20,1,.006,.0172,.03297,.02437,.02437,0.0*
1,1,.006,.02437,.02437*
20,1,.006,.02437,.02437,.0301,.01433,0.0*
1,1,.006,.0301,.01433*
20,1,.006,.0301,.01433,.03153,0.0,0.0*
1,1,.006,.03153,0.0*
20,1,.006,.03153,0.0,.0301,-.01433,0.0*
1,1,.006,.0301,-.01433*
20,1,.006,.0301,-.01433,.02437,-.02437,0.0*
1,1,.006,.02437,-.02437*
20,1,.006,.02437,-.02437,.0172,-.03297,0.0*
1,1,.006,.0172,-.03297*
20,1,.006,.0172,-.03297,.0086,-.0387,0.0*
1,1,.006,.0086,-.0387*
20,1,.006,.0086,-.0387,-.00287,-.043,0.0*
1,1,.006,-.00287,-.043*
20,1,.006,-.00287,-.043,-.03153,-.043,0.0*
1,1,.006,-.03153,-.043*
%
%ADD10MACRO10*%
%AMMACRO23*
1,1,.006,.033,-.0495*
20,1,.006,.033,-.0495,-.033,-.0495,0.0*
1,1,.006,-.033,-.0495*
20,1,.006,-.033,-.0495,-.033,.0495,0.0*
1,1,.006,-.033,.0495*
20,1,.006,-.033,.0495,.033,.0495,0.0*
1,1,.006,.033,.0495*
1,1,.006,.0066,.00165*
20,1,.006,.0066,.00165,-.033,.00165,0.0*
1,1,.006,-.033,.00165*
%
%ADD23MACRO23*%
%AMMACRO11*
1,1,.006,.006,0.0*
20,1,.006,.006,0.0,.003,.005196,0.0*
1,1,.006,.003,.005196*
20,1,.006,.003,.005196,-.003,.005196,0.0*
1,1,.006,-.003,.005196*
20,1,.006,-.003,.005196,-.006,0.0,0.0*
1,1,.006,-.006,0.0*
20,1,.006,-.006,0.0,-.003,-.005196,0.0*
1,1,.006,-.003,-.005196*
20,1,.006,-.003,-.005196,.003,-.005196,0.0*
1,1,.006,.003,-.005196*
20,1,.006,.003,-.005196,.006,0.0,0.0*
1,1,.006,.006,0.0*
1,1,.006,-.0022,-.0018*
20,1,.006,-.0022,-.0018,-.0016,-.0025,0.0*
1,1,.006,-.0016,-.0025*
20,1,.006,-.0016,-.0025,-.0008,-.0029,0.0*
1,1,.006,-.0008,-.0029*
20,1,.006,-.0008,-.0029,.0001,-.003,0.0*
1,1,.006,.0001,-.003*
20,1,.006,.0001,-.003,.0009,-.0029,0.0*
1,1,.006,.0009,-.0029*
20,1,.006,.0009,-.0029,.0017,-.0024,0.0*
1,1,.006,.0017,-.0024*
20,1,.006,.0017,-.0024,.0022,-.0018,0.0*
1,1,.006,.0022,-.0018*
20,1,.006,.0022,-.0018,.0023,-.0012,0.0*
1,1,.006,.0023,-.0012*
20,1,.006,.0023,-.0012,.0021,-.0005,0.0*
1,1,.006,.0021,-.0005*
20,1,.006,.0021,-.0005,.0014,0.0,0.0*
1,1,.006,.0014,0.0*
20,1,.006,.0014,0.0,.0007,.0002,0.0*
1,1,.006,.0007,.0002*
20,1,.006,.0007,.0002,-.0002,.0002,0.0*
1,1,.006,-.0002,.0002*
1,1,.006,.0007,.0002*
20,1,.006,.0007,.0002,.0013,.0005,0.0*
1,1,.006,.0013,.0005*
20,1,.006,.0013,.0005,.0018,.001,0.0*
1,1,.006,.0018,.001*
20,1,.006,.0018,.001,.002,.0016,0.0*
1,1,.006,.002,.0016*
20,1,.006,.002,.0016,.0018,.0022,0.0*
1,1,.006,.0018,.0022*
20,1,.006,.0018,.0022,.0013,.0027,0.0*
1,1,.006,.0013,.0027*
20,1,.006,.0013,.0027,.0004,.003,0.0*
1,1,.006,.0004,.003*
20,1,.006,.0004,.003,-.0005,.0029,0.0*
1,1,.006,-.0005,.0029*
20,1,.006,-.0005,.0029,-.0014,.0025,0.0*
1,1,.006,-.0014,.0025*
%
%ADD11MACRO11*%
%AMMACRO25*
1,1,.006,0.0,.01*
20,1,.006,0.0,.01,.01,-.01,0.0*
1,1,.006,.01,-.01*
20,1,.006,.01,-.01,-.01,-.01,0.0*
1,1,.006,-.01,-.01*
20,1,.006,-.01,-.01,0.0,.01,0.0*
1,1,.006,0.0,.01*
1,1,.006,-.00033,-.005*
20,1,.006,-.00033,-.005,0.0,-.00283,0.0*
1,1,.006,0.0,-.00283*
20,1,.006,0.0,-.00283,.0005,-.001,0.0*
1,1,.006,.0005,-.001*
20,1,.006,.0005,-.001,.00117,.00067,0.0*
1,1,.006,.00117,.00067*
20,1,.006,.00117,.00067,.002,.0025,0.0*
1,1,.006,.002,.0025*
20,1,.006,.002,.0025,.00333,.005,0.0*
1,1,.006,.00333,.005*
20,1,.006,.00333,.005,-.00333,.005,0.0*
1,1,.006,-.00333,.005*
%
%ADD25MACRO25*%
%AMMACRO20*
1,1,.006,.0355,0.0*
20,1,.006,.0355,0.0,.034961,-.006165,0.0*
1,1,.006,.034961,-.006165*
20,1,.006,.034961,-.006165,.033359,-.012142,0.0*
1,1,.006,.033359,-.012142*
20,1,.006,.033359,-.012142,.030744,-.01775,0.0*
1,1,.006,.030744,-.01775*
20,1,.006,.030744,-.01775,.027195,-.022819,0.0*
1,1,.006,.027195,-.022819*
20,1,.006,.027195,-.022819,.022819,-.027195,0.0*
1,1,.006,.022819,-.027195*
20,1,.006,.022819,-.027195,.01775,-.030744,0.0*
1,1,.006,.01775,-.030744*
20,1,.006,.01775,-.030744,.012142,-.033359,0.0*
1,1,.006,.012142,-.033359*
20,1,.006,.012142,-.033359,.006165,-.034961,0.0*
1,1,.006,.006165,-.034961*
20,1,.006,.006165,-.034961,0.0,-.0355,0.0*
1,1,.006,0.0,-.0355*
20,1,.006,0.0,-.0355,-.006165,-.034961,0.0*
1,1,.006,-.006165,-.034961*
20,1,.006,-.006165,-.034961,-.012142,-.033359,0.0*
1,1,.006,-.012142,-.033359*
20,1,.006,-.012142,-.033359,-.01775,-.030744,0.0*
1,1,.006,-.01775,-.030744*
20,1,.006,-.01775,-.030744,-.022819,-.027195,0.0*
1,1,.006,-.022819,-.027195*
20,1,.006,-.022819,-.027195,-.027195,-.022819,0.0*
1,1,.006,-.027195,-.022819*
20,1,.006,-.027195,-.022819,-.030744,-.01775,0.0*
1,1,.006,-.030744,-.01775*
20,1,.006,-.030744,-.01775,-.033359,-.012142,0.0*
1,1,.006,-.033359,-.012142*
20,1,.006,-.033359,-.012142,-.034961,-.006165,0.0*
1,1,.006,-.034961,-.006165*
20,1,.006,-.034961,-.006165,-.0355,0.0,0.0*
1,1,.006,-.0355,0.0*
20,1,.006,-.0355,0.0,-.034961,.006165,0.0*
1,1,.006,-.034961,.006165*
20,1,.006,-.034961,.006165,-.033359,.012142,0.0*
1,1,.006,-.033359,.012142*
20,1,.006,-.033359,.012142,-.030744,.01775,0.0*
1,1,.006,-.030744,.01775*
20,1,.006,-.030744,.01775,-.027195,.022819,0.0*
1,1,.006,-.027195,.022819*
20,1,.006,-.027195,.022819,-.022819,.027195,0.0*
1,1,.006,-.022819,.027195*
20,1,.006,-.022819,.027195,-.01775,.030744,0.0*
1,1,.006,-.01775,.030744*
20,1,.006,-.01775,.030744,-.012142,.033359,0.0*
1,1,.006,-.012142,.033359*
20,1,.006,-.012142,.033359,-.006165,.034961,0.0*
1,1,.006,-.006165,.034961*
20,1,.006,-.006165,.034961,0.0,.0355,0.0*
1,1,.006,0.0,.0355*
20,1,.006,0.0,.0355,.006165,.034961,0.0*
1,1,.006,.006165,.034961*
20,1,.006,.006165,.034961,.012142,.033359,0.0*
1,1,.006,.012142,.033359*
20,1,.006,.012142,.033359,.01775,.030744,0.0*
1,1,.006,.01775,.030744*
20,1,.006,.01775,.030744,.022819,.027195,0.0*
1,1,.006,.022819,.027195*
20,1,.006,.022819,.027195,.027195,.022819,0.0*
1,1,.006,.027195,.022819*
20,1,.006,.027195,.022819,.030744,.01775,0.0*
1,1,.006,.030744,.01775*
20,1,.006,.030744,.01775,.033359,.012142,0.0*
1,1,.006,.033359,.012142*
20,1,.006,.033359,.012142,.034961,.006165,0.0*
1,1,.006,.034961,.006165*
20,1,.006,.034961,.006165,.0355,0.0,0.0*
1,1,.006,.0355,0.0*
1,1,.006,-.01775,-.01775*
20,1,.006,-.01775,-.01775,-.01775,.01775,0.0*
1,1,.006,-.01775,.01775*
20,1,.006,-.01775,.01775,-.02485,.01065,0.0*
1,1,.006,-.02485,.01065*
1,1,.006,-.02485,-.01775*
20,1,.006,-.02485,-.01775,-.01065,-.01775,0.0*
1,1,.006,-.01065,-.01775*
1,1,.006,.01776,-.01775*
20,1,.006,.01776,-.01775,.01776,.01775,0.0*
1,1,.006,.01776,.01775*
20,1,.006,.01776,.01775,.01066,.01065,0.0*
1,1,.006,.01066,.01065*
1,1,.006,.01066,-.01775*
20,1,.006,.01066,-.01775,.02486,-.01775,0.0*
1,1,.006,.02486,-.01775*
%
%ADD20MACRO20*%
%AMMACRO28*
1,1,.006,0.0,.007*
20,1,.006,0.0,.007,-.006062,.0035,0.0*
1,1,.006,-.006062,.0035*
20,1,.006,-.006062,.0035,-.006062,-.0035,0.0*
1,1,.006,-.006062,-.0035*
20,1,.006,-.006062,-.0035,0.0,-.007,0.0*
1,1,.006,0.0,-.007*
20,1,.006,0.0,-.007,.006062,-.0035,0.0*
1,1,.006,.006062,-.0035*
20,1,.006,.006062,-.0035,.006062,.0035,0.0*
1,1,.006,.006062,.0035*
20,1,.006,.006062,.0035,0.0,.007,0.0*
1,1,.006,0.0,.007*
1,1,.006,.0014,-.0035*
20,1,.006,.0014,-.0035,.0014,.0035,0.0*
1,1,.006,.0014,.0035*
20,1,.006,.0014,.0035,-.00292,-.00152,0.0*
1,1,.006,-.00292,-.00152*
20,1,.006,-.00292,-.00152,.00292,-.00152,0.0*
1,1,.006,.00292,-.00152*
%
%ADD28MACRO28*%
%AMMACRO24*
1,1,.006,.020075,.015055*
20,1,.006,.020075,.015055,.020075,-.015055,0.0*
1,1,.006,.020075,-.015055*
20,1,.006,.020075,-.015055,-.020075,-.015055,0.0*
1,1,.006,-.020075,-.015055*
20,1,.006,-.020075,-.015055,-.020075,.015055,0.0*
1,1,.006,-.020075,.015055*
20,1,.006,-.020075,.015055,.020075,.015055,0.0*
1,1,.006,.020075,.015055*
1,1,.006,-.00753,-.00752*
20,1,.006,-.00753,-.00752,-.00753,.00753,0.0*
1,1,.006,-.00753,.00753*
20,1,.006,-.00753,.00753,-.01054,.00452,0.0*
1,1,.006,-.01054,.00452*
1,1,.006,-.01054,-.00752*
20,1,.006,-.01054,-.00752,-.00452,-.00752,0.0*
1,1,.006,-.00452,-.00752*
1,1,.006,.00753,.00753*
20,1,.006,.00753,.00753,.00553,.00703,0.0*
1,1,.006,.00553,.00703*
20,1,.006,.00553,.00703,.00402,.00577,0.0*
1,1,.006,.00402,.00577*
20,1,.006,.00402,.00577,.00302,.00427,0.0*
1,1,.006,.00302,.00427*
20,1,.006,.00302,.00427,.00227,.00226,0.0*
1,1,.006,.00227,.00226*
20,1,.006,.00227,.00226,.00202,0.0,0.0*
1,1,.006,.00202,0.0*
20,1,.006,.00202,0.0,.00227,-.00225,0.0*
1,1,.006,.00227,-.00225*
20,1,.006,.00227,-.00225,.00302,-.00426,0.0*
1,1,.006,.00302,-.00426*
20,1,.006,.00302,-.00426,.00402,-.00576,0.0*
1,1,.006,.00402,-.00576*
20,1,.006,.00402,-.00576,.00553,-.00702,0.0*
1,1,.006,.00553,-.00702*
20,1,.006,.00553,-.00702,.00753,-.00752,0.0*
1,1,.006,.00753,-.00752*
20,1,.006,.00753,-.00752,.00954,-.00702,0.0*
1,1,.006,.00954,-.00702*
20,1,.006,.00954,-.00702,.01105,-.00576,0.0*
1,1,.006,.01105,-.00576*
20,1,.006,.01105,-.00576,.01205,-.00426,0.0*
1,1,.006,.01205,-.00426*
20,1,.006,.01205,-.00426,.0128,-.00225,0.0*
1,1,.006,.0128,-.00225*
20,1,.006,.0128,-.00225,.01305,0.0,0.0*
1,1,.006,.01305,0.0*
20,1,.006,.01305,0.0,.0128,.00226,0.0*
1,1,.006,.0128,.00226*
20,1,.006,.0128,.00226,.01205,.00427,0.0*
1,1,.006,.01205,.00427*
20,1,.006,.01205,.00427,.01105,.00577,0.0*
1,1,.006,.01105,.00577*
20,1,.006,.01105,.00577,.00954,.00703,0.0*
1,1,.006,.00954,.00703*
20,1,.006,.00954,.00703,.00753,.00753,0.0*
1,1,.006,.00753,.00753*
%
%ADD24MACRO24*%
%AMMACRO13*
1,1,.006,-.013125,.004375*
20,1,.006,-.013125,.004375,-.012926,.006654,0.0*
1,1,.006,-.012926,.006654*
20,1,.006,-.012926,.006654,-.012333,.008864,0.0*
1,1,.006,-.012333,.008864*
20,1,.006,-.012333,.008864,-.011367,.010937,0.0*
1,1,.006,-.011367,.010937*
20,1,.006,-.011367,.010937,-.010054,.012812,0.0*
1,1,.006,-.010054,.012812*
20,1,.006,-.010054,.012812,-.008437,.014429,0.0*
1,1,.006,-.008437,.014429*
20,1,.006,-.008437,.014429,-.006563,.015742,0.0*
1,1,.006,-.006563,.015742*
20,1,.006,-.006563,.015742,-.004489,.016708,0.0*
1,1,.006,-.004489,.016708*
20,1,.006,-.004489,.016708,-.002279,.017301,0.0*
1,1,.006,-.002279,.017301*
20,1,.006,-.002279,.017301,0.0,.0175,0.0*
1,1,.006,0.0,.0175*
20,1,.006,0.0,.0175,.002279,.017301,0.0*
1,1,.006,.002279,.017301*
20,1,.006,.002279,.017301,.004489,.016708,0.0*
1,1,.006,.004489,.016708*
20,1,.006,.004489,.016708,.006562,.015742,0.0*
1,1,.006,.006562,.015742*
20,1,.006,.006562,.015742,.008437,.014429,0.0*
1,1,.006,.008437,.014429*
20,1,.006,.008437,.014429,.010054,.012812,0.0*
1,1,.006,.010054,.012812*
20,1,.006,.010054,.012812,.011367,.010938,0.0*
1,1,.006,.011367,.010938*
20,1,.006,.011367,.010938,.012333,.008864,0.0*
1,1,.006,.012333,.008864*
20,1,.006,.012333,.008864,.012926,.006654,0.0*
1,1,.006,.012926,.006654*
20,1,.006,.012926,.006654,.013125,.004375,0.0*
1,1,.006,.013125,.004375*
20,1,.006,.013125,.004375,.013125,-.004375,0.0*
1,1,.006,.013125,-.004375*
20,1,.006,.013125,-.004375,.012926,-.006654,0.0*
1,1,.006,.012926,-.006654*
20,1,.006,.012926,-.006654,.012333,-.008864,0.0*
1,1,.006,.012333,-.008864*
20,1,.006,.012333,-.008864,.011367,-.010937,0.0*
1,1,.006,.011367,-.010937*
20,1,.006,.011367,-.010937,.010054,-.012812,0.0*
1,1,.006,.010054,-.012812*
20,1,.006,.010054,-.012812,.008437,-.014429,0.0*
1,1,.006,.008437,-.014429*
20,1,.006,.008437,-.014429,.006563,-.015742,0.0*
1,1,.006,.006563,-.015742*
20,1,.006,.006563,-.015742,.004489,-.016708,0.0*
1,1,.006,.004489,-.016708*
20,1,.006,.004489,-.016708,.002279,-.017301,0.0*
1,1,.006,.002279,-.017301*
20,1,.006,.002279,-.017301,0.0,-.0175,0.0*
1,1,.006,0.0,-.0175*
20,1,.006,0.0,-.0175,-.002279,-.017301,0.0*
1,1,.006,-.002279,-.017301*
20,1,.006,-.002279,-.017301,-.004489,-.016708,0.0*
1,1,.006,-.004489,-.016708*
20,1,.006,-.004489,-.016708,-.006562,-.015742,0.0*
1,1,.006,-.006562,-.015742*
20,1,.006,-.006562,-.015742,-.008437,-.014429,0.0*
1,1,.006,-.008437,-.014429*
20,1,.006,-.008437,-.014429,-.010054,-.012812,0.0*
1,1,.006,-.010054,-.012812*
20,1,.006,-.010054,-.012812,-.011367,-.010938,0.0*
1,1,.006,-.011367,-.010938*
20,1,.006,-.011367,-.010938,-.012333,-.008864,0.0*
1,1,.006,-.012333,-.008864*
20,1,.006,-.012333,-.008864,-.012926,-.006654,0.0*
1,1,.006,-.012926,-.006654*
20,1,.006,-.012926,-.006654,-.013125,-.004375,0.0*
1,1,.006,-.013125,-.004375*
20,1,.006,-.013125,-.004375,-.013125,.004375,0.0*
1,1,.006,-.013125,.004375*
1,1,.006,-.00372,-.00503*
20,1,.006,-.00372,-.00503,-.00219,-.00612,0.0*
1,1,.006,-.00219,-.00612*
20,1,.006,-.00219,-.00612,-.00044,-.00656,0.0*
1,1,.006,-.00044,-.00656*
20,1,.006,-.00044,-.00656,.00131,-.00612,0.0*
1,1,.006,.00131,-.00612*
20,1,.006,.00131,-.00612,.00284,-.00481,0.0*
1,1,.006,.00284,-.00481*
20,1,.006,.00284,-.00481,.00394,-.00284,0.0*
1,1,.006,.00394,-.00284*
20,1,.006,.00394,-.00284,.00437,-.00087,0.0*
1,1,.006,.00437,-.00087*
20,1,.006,.00437,-.00087,.00437,.00153,0.0*
1,1,.006,.00437,.00153*
20,1,.006,.00437,.00153,.00394,.0035,0.0*
1,1,.006,.00394,.0035*
20,1,.006,.00394,.0035,.00284,.00525,0.0*
1,1,.006,.00284,.00525*
20,1,.006,.00284,.00525,.00153,.00612,0.0*
1,1,.006,.00153,.00612*
20,1,.006,.00153,.00612,0.0,.00656,0.0*
1,1,.006,0.0,.00656*
20,1,.006,0.0,.00656,-.00175,.00612,0.0*
1,1,.006,-.00175,.00612*
20,1,.006,-.00175,.00612,-.00306,.00525,0.0*
1,1,.006,-.00306,.00525*
20,1,.006,-.00306,.00525,-.00394,.00394,0.0*
1,1,.006,-.00394,.00394*
20,1,.006,-.00394,.00394,-.00437,.00219,0.0*
1,1,.006,-.00437,.00219*
20,1,.006,-.00437,.00219,-.00394,.00066,0.0*
1,1,.006,-.00394,.00066*
20,1,.006,-.00394,.00066,-.00284,-.00087,0.0*
1,1,.006,-.00284,-.00087*
20,1,.006,-.00284,-.00087,-.00153,-.00175,0.0*
1,1,.006,-.00153,-.00175*
20,1,.006,-.00153,-.00175,0.0,-.00197,0.0*
1,1,.006,0.0,-.00197*
20,1,.006,0.0,-.00197,.00175,-.00153,0.0*
1,1,.006,.00175,-.00153*
20,1,.006,.00175,-.00153,.00306,-.00044,0.0*
1,1,.006,.00306,-.00044*
20,1,.006,.00306,-.00044,.00437,.00153,0.0*
1,1,.006,.00437,.00153*
%
%ADD13MACRO13*%
%AMMACRO29*
1,1,.006,-.00364,.010925*
20,1,.006,-.00364,.010925,.00364,.010925,0.0*
1,1,.006,.00364,.010925*
20,1,.006,.00364,.010925,.005537,.010759,0.0*
1,1,.006,.005537,.010759*
20,1,.006,.005537,.010759,.007377,.010266,0.0*
1,1,.006,.007377,.010266*
20,1,.006,.007377,.010266,.009102,.009461,0.0*
1,1,.006,.009102,.009461*
20,1,.006,.009102,.009461,.010662,.008369,0.0*
1,1,.006,.010662,.008369*
20,1,.006,.010662,.008369,.012009,.007022,0.0*
1,1,.006,.012009,.007022*
20,1,.006,.012009,.007022,.013101,.005463,0.0*
1,1,.006,.013101,.005463*
20,1,.006,.013101,.005463,.013906,.003737,0.0*
1,1,.006,.013906,.003737*
20,1,.006,.013906,.003737,.014399,.001897,0.0*
1,1,.006,.014399,.001897*
20,1,.006,.014399,.001897,.014565,0.0,0.0*
1,1,.006,.014565,0.0*
20,1,.006,.014565,0.0,.014399,-.001897,0.0*
1,1,.006,.014399,-.001897*
20,1,.006,.014399,-.001897,.013906,-.003737,0.0*
1,1,.006,.013906,-.003737*
20,1,.006,.013906,-.003737,.013101,-.005462,0.0*
1,1,.006,.013101,-.005462*
20,1,.006,.013101,-.005462,.012009,-.007022,0.0*
1,1,.006,.012009,-.007022*
20,1,.006,.012009,-.007022,.010662,-.008369,0.0*
1,1,.006,.010662,-.008369*
20,1,.006,.010662,-.008369,.009103,-.009461,0.0*
1,1,.006,.009103,-.009461*
20,1,.006,.009103,-.009461,.007377,-.010266,0.0*
1,1,.006,.007377,-.010266*
20,1,.006,.007377,-.010266,.005537,-.010759,0.0*
1,1,.006,.005537,-.010759*
20,1,.006,.005537,-.010759,.00364,-.010925,0.0*
1,1,.006,.00364,-.010925*
20,1,.006,.00364,-.010925,-.00364,-.010925,0.0*
1,1,.006,-.00364,-.010925*
20,1,.006,-.00364,-.010925,-.005537,-.010759,0.0*
1,1,.006,-.005537,-.010759*
20,1,.006,-.005537,-.010759,-.007377,-.010266,0.0*
1,1,.006,-.007377,-.010266*
20,1,.006,-.007377,-.010266,-.009102,-.009461,0.0*
1,1,.006,-.009102,-.009461*
20,1,.006,-.009102,-.009461,-.010662,-.008369,0.0*
1,1,.006,-.010662,-.008369*
20,1,.006,-.010662,-.008369,-.012009,-.007022,0.0*
1,1,.006,-.012009,-.007022*
20,1,.006,-.012009,-.007022,-.013101,-.005463,0.0*
1,1,.006,-.013101,-.005463*
20,1,.006,-.013101,-.005463,-.013906,-.003737,0.0*
1,1,.006,-.013906,-.003737*
20,1,.006,-.013906,-.003737,-.014399,-.001897,0.0*
1,1,.006,-.014399,-.001897*
20,1,.006,-.014399,-.001897,-.014565,0.0,0.0*
1,1,.006,-.014565,0.0*
20,1,.006,-.014565,0.0,-.014399,.001897,0.0*
1,1,.006,-.014399,.001897*
20,1,.006,-.014399,.001897,-.013906,.003737,0.0*
1,1,.006,-.013906,.003737*
20,1,.006,-.013906,.003737,-.013101,.005462,0.0*
1,1,.006,-.013101,.005462*
20,1,.006,-.013101,.005462,-.012009,.007022,0.0*
1,1,.006,-.012009,.007022*
20,1,.006,-.012009,.007022,-.010662,.008369,0.0*
1,1,.006,-.010662,.008369*
20,1,.006,-.010662,.008369,-.009103,.009461,0.0*
1,1,.006,-.009103,.009461*
20,1,.006,-.009103,.009461,-.007377,.010266,0.0*
1,1,.006,-.007377,.010266*
20,1,.006,-.007377,.010266,-.005537,.010759,0.0*
1,1,.006,-.005537,.010759*
20,1,.006,-.005537,.010759,-.00364,.010925,0.0*
1,1,.006,-.00364,.010925*
1,1,.006,0.0,-.00546*
20,1,.006,0.0,-.00546,.00127,-.00528,0.0*
1,1,.006,.00127,-.00528*
20,1,.006,.00127,-.00528,.00273,-.00473,0.0*
1,1,.006,.00273,-.00473*
20,1,.006,.00273,-.00473,.00364,-.00382,0.0*
1,1,.006,.00364,-.00382*
20,1,.006,.00364,-.00382,.004,-.00255,0.0*
1,1,.006,.004,-.00255*
20,1,.006,.004,-.00255,.00364,-.00127,0.0*
1,1,.006,.00364,-.00127*
20,1,.006,.00364,-.00127,.00255,-.00018,0.0*
1,1,.006,.00255,-.00018*
20,1,.006,.00255,-.00018,.00091,.00036,0.0*
1,1,.006,.00091,.00036*
20,1,.006,.00091,.00036,-.00091,.00036,0.0*
1,1,.006,-.00091,.00036*
20,1,.006,-.00091,.00036,-.002,.00073,0.0*
1,1,.006,-.002,.00073*
20,1,.006,-.002,.00073,-.00291,.00164,0.0*
1,1,.006,-.00291,.00164*
20,1,.006,-.00291,.00164,-.00328,.00291,0.0*
1,1,.006,-.00328,.00291*
20,1,.006,-.00328,.00291,-.00273,.00419,0.0*
1,1,.006,-.00273,.00419*
20,1,.006,-.00273,.00419,-.00146,.0051,0.0*
1,1,.006,-.00146,.0051*
20,1,.006,-.00146,.0051,0.0,.00546,0.0*
1,1,.006,0.0,.00546*
20,1,.006,0.0,.00546,.00146,.0051,0.0*
1,1,.006,.00146,.0051*
20,1,.006,.00146,.0051,.00273,.00419,0.0*
1,1,.006,.00273,.00419*
20,1,.006,.00273,.00419,.00328,.00291,0.0*
1,1,.006,.00328,.00291*
20,1,.006,.00328,.00291,.00291,.00164,0.0*
1,1,.006,.00291,.00164*
20,1,.006,.00291,.00164,.002,.00073,0.0*
1,1,.006,.002,.00073*
20,1,.006,.002,.00073,.00091,.00036,0.0*
1,1,.006,.00091,.00036*
20,1,.006,.00091,.00036,-.00091,.00036,0.0*
1,1,.006,-.00091,.00036*
20,1,.006,-.00091,.00036,-.00255,-.00018,0.0*
1,1,.006,-.00255,-.00018*
20,1,.006,-.00255,-.00018,-.00364,-.00127,0.0*
1,1,.006,-.00364,-.00127*
20,1,.006,-.00364,-.00127,-.004,-.00255,0.0*
1,1,.006,-.004,-.00255*
20,1,.006,-.004,-.00255,-.00364,-.00382,0.0*
1,1,.006,-.00364,-.00382*
20,1,.006,-.00364,-.00382,-.00273,-.00473,0.0*
1,1,.006,-.00273,-.00473*
20,1,.006,-.00273,-.00473,-.00127,-.00528,0.0*
1,1,.006,-.00127,-.00528*
20,1,.006,-.00127,-.00528,0.0,-.00546,0.0*
1,1,.006,0.0,-.00546*
%
%ADD29MACRO29*%
%ADD31C,.02*%
%ADD32C,.006*%
G75*
%LPD*%
G75*
G54D10*
X59400Y32600D03*
X63374Y1454500D03*
X390757Y1511515D03*
X812347Y17406D03*
X885639Y1511515D03*
X1187163Y158305D03*
X1538001Y1511515D03*
X1869500Y1461500D03*
X2261450Y498100D03*
G54D20*
X184252Y1445275D03*
Y1466929D03*
X167716Y1445275D03*
Y1466929D03*
X233858Y1445275D03*
Y1466929D03*
X217322Y1445275D03*
Y1466929D03*
X200787Y1445275D03*
Y1466929D03*
X581102Y1445275D03*
Y1466929D03*
X564567Y1445275D03*
Y1466929D03*
X548031Y1445275D03*
Y1466929D03*
X614173Y1445275D03*
Y1466929D03*
X597637Y1445275D03*
Y1466929D03*
X1331496Y1445275D03*
Y1466929D03*
X1314960Y1445275D03*
Y1466929D03*
X1381102Y1445275D03*
Y1466929D03*
X1364566Y1445275D03*
Y1466929D03*
X1348031Y1445275D03*
Y1466929D03*
X1711811Y1445275D03*
Y1466929D03*
X1695275Y1445275D03*
Y1466929D03*
X1761417Y1445275D03*
Y1466929D03*
X1744881Y1445275D03*
Y1466929D03*
X1728346Y1445275D03*
Y1466929D03*
X2261450Y740500D03*
G54D11*
X78000Y44000D03*
X38000Y86000D03*
X86700Y80700D03*
X92250Y80500D03*
X75000Y73300D03*
X92500Y62800D03*
X56750Y62000D03*
X64250Y87500D03*
X95800Y71800D03*
X30500Y67000D03*
X74000Y87500D03*
X89000D03*
X84000D03*
X79000D03*
X81500Y105000D03*
X48000Y160000D03*
X95500Y186000D03*
X89000Y162700D03*
X49500Y140500D03*
X64250Y98500D03*
X73500Y120500D03*
X72900Y133000D03*
X50000Y105500D03*
X54500D03*
X59000D03*
X88000Y204000D03*
X76000Y232000D03*
X50000Y200000D03*
X38000Y348000D03*
X55209Y379278D03*
X58709Y372346D03*
X38000Y418000D03*
Y452000D03*
X69942Y406555D03*
X65692Y392187D03*
X58728Y393206D03*
X84581Y397946D03*
X79581D03*
X88000Y498000D03*
Y478000D03*
X38000Y544000D03*
X81500Y557500D03*
X64250Y551000D03*
X86700Y533200D03*
X75000Y525800D03*
X92250Y533000D03*
X93800Y516800D03*
X64250Y540000D03*
X50000Y558000D03*
X54500D03*
X59000D03*
X53250Y518000D03*
X95500Y525500D03*
X79000Y540000D03*
X84000D03*
X89000D03*
X74000D03*
X40000Y614000D03*
X76000Y642000D03*
X38000Y660000D03*
X95500Y638500D03*
X89000Y615200D03*
X73500Y573000D03*
X72800Y585500D03*
X49500Y593000D03*
X92000Y758000D03*
X34000Y792000D03*
X100000Y800000D03*
X57675Y851609D03*
X53425Y853600D03*
X46461Y853382D03*
X42942Y831932D03*
X46442Y825000D03*
X73526Y850100D03*
X68526D03*
X26000Y908000D03*
Y940000D03*
X88000Y946000D03*
X91114Y909791D03*
X85000Y885500D03*
X89000D03*
Y881500D03*
X85000D03*
X89000Y877500D03*
X85000D03*
X89000Y889500D03*
X85000D03*
X89000Y893500D03*
X85000D03*
X81166Y892754D03*
Y888754D03*
X41263Y887025D03*
X48763D03*
X55763D03*
X51263Y894525D03*
X46763Y891525D03*
X83300Y908900D03*
X100310Y899557D03*
X68900Y897700D03*
X77263Y898225D03*
X83500Y898662D03*
X73430Y898509D03*
X70603Y887495D03*
X66263Y879525D03*
X67763Y883525D03*
X81500Y1010500D03*
X38000Y996000D03*
X73500Y1026000D03*
X72600Y1038400D03*
X49500Y1046000D03*
X86700Y986200D03*
X75000Y978800D03*
X64250Y1004000D03*
X92250Y986000D03*
X95500Y968000D03*
X59000Y1011000D03*
X54500D03*
X50000D03*
X64250Y993000D03*
X53250Y971000D03*
X95500Y972500D03*
X74000Y993000D03*
X89000D03*
X84000D03*
X79000D03*
X50000Y1100000D03*
X95500Y1091500D03*
X89000Y1068200D03*
X50000Y1150000D03*
Y1200000D03*
X100000Y1250000D03*
X50000D03*
Y1300000D03*
X100000D03*
X50000Y1350000D03*
X100000D03*
Y1400000D03*
X50000D03*
X86000Y1444000D03*
X144000Y88000D03*
X111437Y81319D03*
Y66319D03*
X106937Y84370D03*
Y93819D03*
X111437Y51319D03*
X118437Y27697D03*
X148050Y20971D03*
X126900Y39500D03*
X150700Y33100D03*
X157900Y17900D03*
X157600Y24500D03*
X157400Y35800D03*
X183500Y75450D03*
Y80250D03*
X178500Y80000D03*
X185551Y21529D03*
X151200Y48500D03*
Y44400D03*
X145864Y33216D03*
X175650Y28600D03*
X158000Y152000D03*
X154000Y106000D03*
X111437Y161319D03*
Y151319D03*
X173500Y140500D03*
X111437Y131319D03*
Y121319D03*
X127600Y119300D03*
X106937Y103268D03*
X131600Y119100D03*
X174000Y236000D03*
X118437Y199941D03*
X112000Y316000D03*
X162000Y310000D03*
X150000Y350000D03*
X189342Y378932D03*
X192842Y372000D03*
X102000Y440000D03*
X174000Y410000D03*
X178993Y455018D03*
Y451018D03*
X192861Y400482D03*
X182827Y447764D03*
Y455764D03*
X186827D03*
X182827Y451764D03*
X186827D03*
X182827Y439764D03*
Y443764D03*
X188941Y472055D03*
X153590Y449289D03*
X146590D03*
X149090Y456789D03*
X144590Y453789D03*
X139090Y449289D03*
X181127Y471164D03*
X166727Y459964D03*
X175090Y460489D03*
X181327Y460926D03*
X171257Y460773D03*
X168430Y449759D03*
X165590Y445789D03*
X164127Y442264D03*
X156000Y544000D03*
X130000Y560000D03*
X144000Y550000D03*
X152000Y492000D03*
X160000Y508000D03*
X188250Y550951D03*
X106937Y556024D03*
Y537126D03*
Y546575D03*
X111437Y534075D03*
Y519075D03*
Y504075D03*
X118437Y480453D03*
X188250Y540000D03*
X176439Y524992D03*
X182300Y558600D03*
X173600Y554400D03*
Y558600D03*
X178100D03*
X176506Y539295D03*
X180500Y576000D03*
X162000Y614000D03*
X118437Y652697D03*
X111437Y614075D03*
Y604075D03*
Y584075D03*
Y574075D03*
X173500Y593000D03*
X140750Y575500D03*
X143000Y587000D03*
X174000Y686000D03*
X156000Y768000D03*
X150000Y800000D03*
X168937Y850845D03*
X163740Y846722D03*
X159740D03*
X154737Y854845D03*
Y850845D03*
X168937Y854845D03*
X176425Y853700D03*
X180400Y852300D03*
X176558Y831000D03*
X172318Y844782D03*
X169442Y824700D03*
X191026Y850100D03*
X196026D03*
X136000Y912000D03*
X140000Y938000D03*
X188000Y932000D03*
X159860Y924548D03*
X163860D03*
X168863Y916425D03*
Y920425D03*
X118437Y933209D03*
X154663Y916425D03*
Y920425D03*
X173763Y907525D03*
X189763D03*
X185763D03*
X181763D03*
X177763D03*
X193763D03*
X102263Y919025D03*
X114563Y904041D03*
X113763Y865025D03*
X106263Y900025D03*
X106363Y893425D03*
X102207Y890524D03*
X180500Y1028500D03*
X160000Y982000D03*
X142000Y1008000D03*
X140750Y1028500D03*
X174000Y1046000D03*
X111437Y1036831D03*
Y1026831D03*
X188750Y1004000D03*
X111437Y956831D03*
Y986831D03*
Y971831D03*
X106937Y1008780D03*
Y989882D03*
Y999331D03*
X183500Y1011000D03*
X179000D03*
X174500D03*
X188750Y993000D03*
X178200Y977700D03*
X140750Y1039250D03*
X125500Y992500D03*
X136500Y1111500D03*
X164000Y1068000D03*
X118437Y1105453D03*
X111437Y1066831D03*
Y1056831D03*
X158484Y1416000D03*
X139774Y1420600D03*
X131143Y1427661D03*
X130601Y1411700D03*
X136774Y1411000D03*
X188274Y1416600D03*
X165774Y1422700D03*
X157574Y1453500D03*
X145374Y1452500D03*
X145274Y1434685D03*
X156674Y1435085D03*
X167499Y1434000D03*
X104074Y1462500D03*
X114874Y1476700D03*
X118574Y1465900D03*
X121274Y1447400D03*
X124874Y1442600D03*
X151874Y1449800D03*
X149955Y1431573D03*
X135374Y1464000D03*
Y1445500D03*
X105774Y1491000D03*
X120474Y1482800D03*
X132674Y1484200D03*
X137624Y1469000D03*
X175249Y1434075D03*
X156374Y1430500D03*
X130322Y1434014D03*
X135174Y1452400D03*
X104184Y1457200D03*
X139374Y1486100D03*
X124074Y1437200D03*
X113314Y1441700D03*
X262000Y30000D03*
X280000Y90000D03*
X264000Y94000D03*
X202500Y82500D03*
X231000Y82000D03*
X231149Y93819D03*
X235649Y81319D03*
Y66319D03*
X203300Y71700D03*
X215100Y62940D03*
X207000Y80500D03*
X235649Y51319D03*
X242649Y27697D03*
X220000Y80500D03*
X200819Y74819D03*
X217000Y38250D03*
X198800Y34000D03*
X203078Y33972D03*
X215500Y80500D03*
X203000Y87500D03*
X213000D03*
X208000D03*
X197500D03*
X284000Y160000D03*
X256000Y142000D03*
X235649Y161319D03*
Y151319D03*
X219500Y186000D03*
X213500Y162700D03*
X235649Y131319D03*
Y121319D03*
X231149Y103268D03*
X250900Y119500D03*
X197000Y133000D03*
X197500Y120500D03*
X254900Y119600D03*
X198000Y198000D03*
X212000Y236000D03*
X288000Y242000D03*
X250000Y250000D03*
X242649Y199941D03*
X214000Y328000D03*
X250000Y350000D03*
Y300000D03*
X291042Y379232D03*
X286000Y422000D03*
X257567Y409386D03*
X261567D03*
X266764Y417509D03*
Y413509D03*
X252564D03*
Y417509D03*
X199825Y400700D03*
X204075Y398609D03*
X271590Y469789D03*
X275590D03*
X279590D03*
X283590D03*
X287590D03*
X291590D03*
X218214Y397600D03*
X213214D03*
X212390Y466305D03*
X198137Y461821D03*
X204090Y462289D03*
X204190Y455689D03*
X200022Y452941D03*
X212500Y557500D03*
X216000Y498000D03*
X286000Y490000D03*
Y506000D03*
X268000Y544000D03*
X278000Y554000D03*
X266690Y479089D03*
Y483089D03*
X252490D03*
Y479089D03*
X257687Y487212D03*
X261687D03*
X231149Y556024D03*
X232433Y537126D03*
X231149Y546575D03*
X235649Y534075D03*
Y519075D03*
Y504075D03*
X242649Y480453D03*
X210700Y533200D03*
X199000Y525800D03*
X216250Y533000D03*
X218000Y516600D03*
X200090Y481289D03*
X220000Y524000D03*
X203000Y540000D03*
X208000D03*
X213000D03*
X198000D03*
X286000Y612000D03*
X200000Y646000D03*
X242649Y652697D03*
X235649Y614075D03*
X213500Y615200D03*
X219500Y638500D03*
X235649Y604075D03*
Y584075D03*
Y574075D03*
X268187Y578998D03*
X197200Y585500D03*
X197500Y573000D03*
X264750Y586250D03*
X250000Y700000D03*
Y750000D03*
Y850000D03*
Y800000D03*
X291042Y831932D03*
X252000Y906000D03*
X212000Y916000D03*
X213500Y951500D03*
X263500Y939500D03*
X242649Y933209D03*
X197263Y901025D03*
X284500Y982000D03*
X265000Y1008500D03*
X206000Y1010500D03*
X198000Y1026000D03*
X197300Y1038500D03*
X264250Y1028500D03*
X235649Y1036831D03*
Y1026831D03*
X252100Y959100D03*
X211200Y986200D03*
X199500Y978800D03*
X216750Y986000D03*
X231149Y1008780D03*
Y989882D03*
Y999331D03*
X235649Y986831D03*
Y971831D03*
X218100Y969700D03*
X264450Y1039250D03*
X252000Y992500D03*
X220000Y978200D03*
X198500Y993000D03*
X213500D03*
X208500D03*
X203500D03*
X288000Y1068000D03*
X200000Y1100000D03*
X242649Y1105453D03*
X220000Y1091500D03*
X213500Y1068200D03*
X235649Y1066831D03*
Y1056831D03*
X200000Y1200000D03*
X250000D03*
Y1150000D03*
X200000D03*
X227500Y1303000D03*
X250000Y1350000D03*
X209374Y1416300D03*
X259500Y1494000D03*
X256000Y1466000D03*
X386000Y28000D03*
X338000Y30000D03*
Y44000D03*
X355362Y84370D03*
Y93819D03*
X359862Y81319D03*
Y66319D03*
X323500Y73300D03*
X340750Y80500D03*
X335200Y80700D03*
X359862Y51319D03*
X366862Y27697D03*
X341800Y63700D03*
X311800Y83700D03*
X301750Y65500D03*
X340650Y69300D03*
X327500Y87500D03*
X332500D03*
X337500D03*
X322500D03*
X359862Y161319D03*
Y151319D03*
X344000Y186000D03*
X337500Y162700D03*
X298000Y140500D03*
X359862Y131319D03*
X357506Y123493D03*
X355362Y103268D03*
X375500Y119400D03*
X312750Y98500D03*
X322000Y120500D03*
X321500Y133000D03*
X293700Y105500D03*
X298500D03*
X302999Y105501D03*
X379500Y119500D03*
X324000Y196000D03*
X366862Y199941D03*
X358000Y318000D03*
X294542Y372300D03*
X320000Y422000D03*
X336000Y466000D03*
X384000Y468000D03*
X305775Y398909D03*
X301525Y400900D03*
X294561Y400682D03*
X320514Y397600D03*
X315514D03*
X295090Y463289D03*
X338000Y498000D03*
X355362Y556024D03*
Y537126D03*
Y546575D03*
X312750Y551000D03*
X359862Y534075D03*
Y519075D03*
Y504075D03*
X366862Y480453D03*
X335200Y533200D03*
X323500Y525800D03*
X340750Y533000D03*
X341800Y516800D03*
X312750Y536300D03*
X299104Y556943D03*
X303604D03*
X308104D03*
X301750Y518000D03*
X344000Y525300D03*
X322500Y540000D03*
X337500D03*
X332500D03*
X327500D03*
X324000Y650000D03*
X359862Y614075D03*
X366862Y652697D03*
X344000Y638500D03*
X337500Y615200D03*
X359862Y604075D03*
Y584075D03*
X374261Y572963D03*
X322000Y573000D03*
X323380Y589452D03*
X298000Y593000D03*
X334000Y686000D03*
X342000Y758000D03*
X350000Y850000D03*
Y800000D03*
X301525Y853600D03*
X305775Y851609D03*
X294561Y853382D03*
X294542Y825000D03*
X320526Y850100D03*
X315526D03*
X337500Y946500D03*
X359500Y925400D03*
X330000Y1010500D03*
X304500Y1028500D03*
X359862Y1036831D03*
Y1026831D03*
X322000Y1026000D03*
X321200Y1038500D03*
X298000Y1046000D03*
X358800Y955900D03*
X355362Y1008780D03*
Y989882D03*
Y999331D03*
X359862Y986831D03*
Y971831D03*
X335200Y986200D03*
X323500Y978800D03*
X312750Y1004000D03*
X340750Y986000D03*
X341900Y969400D03*
X307500Y1011000D03*
X303000D03*
X298500D03*
X312750Y993000D03*
X302100Y978200D03*
X376000Y993000D03*
X344200Y978200D03*
X322500Y993000D03*
X337500D03*
X332500D03*
X327500D03*
X318000Y1058000D03*
X326000Y1106000D03*
X366862Y1105453D03*
X359862Y1066831D03*
Y1056831D03*
X344000Y1091500D03*
X337500Y1068200D03*
X300000Y1200000D03*
Y1150000D03*
X373492Y1317441D03*
Y1322441D03*
Y1327441D03*
Y1332441D03*
X343688Y1317736D03*
Y1322736D03*
Y1327736D03*
Y1332736D03*
X313688D03*
Y1327736D03*
Y1322736D03*
Y1317736D03*
Y1312736D03*
X369086Y1313208D03*
X374086D03*
X379086D03*
X384086D03*
X324086D03*
X329086D03*
X334086D03*
X339086D03*
X344086D03*
X349086D03*
X354086D03*
X359086D03*
X364086D03*
X294086D03*
X299086D03*
X304086D03*
X309086D03*
X319086D03*
X350000Y1400000D03*
X373492Y1337441D03*
Y1342441D03*
Y1347441D03*
Y1352441D03*
X343688Y1337736D03*
Y1342736D03*
Y1347736D03*
Y1352736D03*
X313688D03*
Y1347736D03*
Y1342736D03*
Y1337736D03*
X323688Y1357736D03*
X328688D03*
X333688D03*
X338688D03*
X343688D03*
X348688D03*
X353688D03*
X358688D03*
X363688D03*
X368688D03*
X373688D03*
X378688D03*
X383688D03*
X298688D03*
X303688D03*
X308688D03*
X313688D03*
X318688D03*
X293688D03*
X300000Y1400000D03*
X410679Y31098D03*
X414000Y58000D03*
X402000Y64000D03*
X454000Y83800D03*
X479574Y84370D03*
Y93819D03*
X462100Y62940D03*
X450300Y71700D03*
X425500Y72600D03*
X435500D03*
X430500D03*
X440500D03*
X468500Y80500D03*
X465500Y38250D03*
X425500Y41250D03*
X430500D03*
X434804Y41242D03*
X444663Y32417D03*
X440400Y32400D03*
X464000Y80500D03*
X446400Y91100D03*
X456900D03*
X461900D03*
X451900D03*
X467500Y116000D03*
X394000Y164000D03*
Y174000D03*
X462000Y162700D03*
X468000Y186000D03*
X422000Y140500D03*
X479574Y103268D03*
X441300Y126000D03*
X445500Y133000D03*
X440849Y111648D03*
X437500Y134500D03*
X441500D03*
X433500D03*
X430083Y122357D03*
X388000Y196000D03*
X416000D03*
X400000Y350000D03*
X415542Y378932D03*
X419042Y372000D03*
X428000Y430000D03*
X460000Y468000D03*
X426025Y400700D03*
X419061Y400382D03*
X430275Y399351D03*
X445014Y397600D03*
X440014D03*
X402000Y560000D03*
X388000Y548000D03*
X410000Y544000D03*
X392000Y490000D03*
X460000Y496000D03*
X479574Y556024D03*
Y537126D03*
Y546575D03*
X436750Y551000D03*
X459200Y533200D03*
X446993Y527868D03*
X464750Y533000D03*
X466000Y516900D03*
X436750Y538400D03*
X422500Y558000D03*
X427000D03*
X431500D03*
X429210Y512992D03*
X464801Y521156D03*
X446500Y540000D03*
X461500D03*
X456500D03*
X451500D03*
X410000Y616000D03*
X468000Y638500D03*
X467029Y610775D03*
X441641Y574141D03*
X445546Y586021D03*
X421820Y593641D03*
X389250Y575500D03*
X390632Y588624D03*
X422000Y684000D03*
X454000Y686000D03*
X466000Y762000D03*
X400000Y800000D03*
X425725Y853400D03*
X429975Y851409D03*
X418761Y853082D03*
X415242Y831882D03*
X418742Y824444D03*
X440026Y850100D03*
X445026D03*
X387500Y939000D03*
X462000Y947000D03*
X428500Y1028500D03*
X454000Y1010500D03*
X407000Y984000D03*
X389500Y1009000D03*
X446000Y1026000D03*
X445100Y1038500D03*
X389250Y1028500D03*
X422000Y1046000D03*
X459200Y986200D03*
X447500Y978800D03*
X436750Y1004000D03*
X464750Y986000D03*
X479574Y1008780D03*
Y989882D03*
Y999331D03*
X466100Y969200D03*
X431500Y1011000D03*
X427000D03*
X422500D03*
X436750Y993000D03*
X426300Y976800D03*
X389250Y1039250D03*
X468300Y978000D03*
X446500Y993000D03*
X461500D03*
X456500D03*
X451500D03*
X448000Y1106000D03*
X410000Y1068000D03*
X468000Y1091500D03*
X462000Y1068200D03*
X450000Y1150000D03*
Y1200000D03*
X389086Y1313208D03*
X394086D03*
X390500Y1386000D03*
X388688Y1357736D03*
X393688D03*
X532000Y90000D03*
X534000Y58000D03*
X512000Y28000D03*
X572000Y73300D03*
X484074Y81319D03*
Y66319D03*
Y51319D03*
X491074Y27697D03*
X561250Y87500D03*
X550250Y65500D03*
X576000Y87500D03*
X571000D03*
X556000Y156000D03*
X568000Y190000D03*
X544000Y160000D03*
X502500Y139500D03*
X512000Y104000D03*
X546500Y140500D03*
X484074Y161319D03*
Y151319D03*
X561250Y98500D03*
X570500Y120500D03*
X569900Y133000D03*
X499900Y119400D03*
X484074Y131319D03*
Y121319D03*
X547000Y105500D03*
X551500D03*
X556000D03*
X503900Y119500D03*
X534000Y222500D03*
X493000Y218500D03*
X491074Y199941D03*
X539742Y379232D03*
X543242Y372300D03*
Y400682D03*
X550225Y400900D03*
X554475Y399651D03*
X569014Y397600D03*
X564014D03*
X516000Y488000D03*
X574000D03*
X524000Y560000D03*
X561250Y551000D03*
X572000Y525800D03*
X484074Y504075D03*
X491074Y480453D03*
X483513Y535912D03*
X484074Y519075D03*
X561250Y540000D03*
X550250Y518000D03*
X571000Y540000D03*
X576000D03*
X536000Y644000D03*
X510000Y656000D03*
X491074Y652697D03*
X484074Y614075D03*
X565279Y578552D03*
X569900Y585500D03*
X551276Y597925D03*
X483265Y606243D03*
X484074Y584075D03*
Y574075D03*
X513250Y574252D03*
X516000Y637413D03*
X546500Y572000D03*
X551044Y572149D03*
X555321Y572375D03*
X517999Y583015D03*
X552000Y686000D03*
X542000Y764000D03*
X500000Y800000D03*
Y850000D03*
X564026Y850100D03*
X569026D03*
X512000Y939000D03*
X483549Y925564D03*
X513500Y1009000D03*
X532000Y983000D03*
X553000Y1028500D03*
X570500Y1026000D03*
X569900Y1038500D03*
X546500Y1046000D03*
X513250Y1028500D03*
X484074Y1036831D03*
Y1026831D03*
X572000Y978800D03*
X561250Y1004000D03*
X499800Y956831D03*
X484074Y986831D03*
Y971831D03*
X556000Y1011000D03*
X551500D03*
X547000D03*
X561250Y993000D03*
X550700Y979500D03*
X513250Y1039250D03*
X500000Y992000D03*
X571000Y993000D03*
X576000D03*
X534000Y1068000D03*
X550000Y1100000D03*
X491074Y1105453D03*
X484074Y1066831D03*
Y1056831D03*
X500000Y1150000D03*
X550000D03*
Y1200000D03*
X500000D03*
X522000Y1294000D03*
X505224Y1424156D03*
X523455Y1416564D03*
X524236Y1463672D03*
X542066Y1440238D03*
X537466D03*
X532866D03*
X528798Y1437733D03*
X524722Y1436362D03*
X528500Y1444600D03*
X507250Y1478000D03*
X535200Y1466100D03*
X523500Y1455400D03*
X503001Y1454922D03*
X513624Y1458624D03*
X504000Y1470500D03*
X503035Y1444331D03*
X528250Y1470900D03*
X496500Y1476000D03*
X508867Y1497771D03*
X585500Y45000D03*
X650000Y84000D03*
X578000Y52000D03*
X592500Y28000D03*
X603787Y84370D03*
Y93819D03*
X608287Y81319D03*
Y66319D03*
X589250Y80500D03*
X583700Y80700D03*
X608287Y51319D03*
X615287Y27697D03*
X590600Y64300D03*
X670500Y80000D03*
X589150Y69500D03*
X581000Y87500D03*
X586000D03*
X638000Y104000D03*
X654000Y162500D03*
X664500Y97000D03*
X579000Y105000D03*
X670500Y140500D03*
X608287Y161319D03*
Y151319D03*
X592500Y186000D03*
X586000Y162700D03*
X608287Y131319D03*
Y121319D03*
X603787Y103268D03*
X624000Y119400D03*
X626000Y140000D03*
X628000Y119500D03*
X652000Y214000D03*
X582500Y266000D03*
X615287Y199941D03*
X586500Y292000D03*
X643000Y317500D03*
X614500Y318500D03*
X639000Y354500D03*
X602500Y365000D03*
X650742Y378932D03*
X654242Y372000D03*
X661225Y400738D03*
X654261Y400382D03*
X665475Y399378D03*
X638000Y488000D03*
X644000Y558000D03*
X603787Y556024D03*
Y537126D03*
Y546575D03*
X608287Y534075D03*
Y519075D03*
Y504075D03*
X615287Y480453D03*
X589250Y533000D03*
X583700Y533200D03*
X583550Y504600D03*
X672018Y557014D03*
X592500Y525300D03*
X586000Y540000D03*
X581000D03*
X664651Y513000D03*
X671000Y648000D03*
X672500Y615500D03*
X615287Y652697D03*
X622687Y614091D03*
X592500Y638500D03*
X586043Y615962D03*
X670500Y593000D03*
X622703Y604103D03*
X623005Y584047D03*
X608287Y574075D03*
X637750Y575500D03*
X666900Y665400D03*
X637750Y586250D03*
X590000Y680000D03*
X646680Y679430D03*
X600000Y770000D03*
X650000D03*
X624000Y846000D03*
X579148Y832411D03*
X666625Y853400D03*
X670875Y851409D03*
X589805Y854600D03*
X594055Y852609D03*
X659661Y853082D03*
X582667Y853605D03*
X656142Y831632D03*
X582648Y825223D03*
X659642Y824700D03*
X585000Y948000D03*
X636000Y939000D03*
X615287Y933209D03*
X585904Y900960D03*
X589904D03*
X593904D03*
X597904D03*
X601904D03*
X673000Y885500D03*
X578000Y1010500D03*
X652500Y984500D03*
X625000Y1014500D03*
X653500Y997500D03*
X670500Y1046000D03*
X637750Y1028500D03*
X608287Y1036831D03*
Y1026831D03*
X601800Y955500D03*
X589250Y986000D03*
X603787Y1008780D03*
Y989882D03*
Y999331D03*
X608287Y986831D03*
Y971831D03*
X583700Y986200D03*
X590200Y969500D03*
X671000Y1011000D03*
X624500Y993000D03*
X592800Y978100D03*
X586000Y993000D03*
X581000D03*
X599000Y1115500D03*
X631500Y1112500D03*
X660000Y1068000D03*
X615287Y1105453D03*
X592500Y1091500D03*
X608287Y1066831D03*
Y1056831D03*
X586000Y1068200D03*
X672000Y1146000D03*
X670000Y1196000D03*
X646102Y1321750D03*
X641102D03*
X668000Y1418900D03*
X672000Y1419000D03*
X646200Y1420576D03*
X641200D03*
X637971Y1425400D03*
X657836Y1433318D03*
X658000Y1449200D03*
X653000Y1488500D03*
X665700Y1463500D03*
Y1468500D03*
X650000Y1464052D03*
Y1467948D03*
Y1457448D03*
Y1453552D03*
X636250Y1468500D03*
X628500D03*
X637972Y1441419D03*
X658000Y1444000D03*
X665700Y1458000D03*
Y1453000D03*
X624750Y1461250D03*
X729201Y87285D03*
X727636Y93834D03*
X732500Y81319D03*
Y66319D03*
X704000Y80500D03*
X699500Y82500D03*
X700300Y71700D03*
X712000Y62940D03*
X732500Y51319D03*
X739500Y27697D03*
X712214Y82500D03*
X680500Y80250D03*
X675500Y80000D03*
X697787Y74488D03*
X714000Y38250D03*
X695600Y34000D03*
X699932Y34034D03*
X709000Y79500D03*
X700000Y87500D03*
X705000D03*
X710000D03*
X694500D03*
X711352Y26875D03*
X715205Y27012D03*
X705171Y16254D03*
X681000Y171500D03*
X732500Y161319D03*
Y151319D03*
X716500Y186000D03*
X710300Y162700D03*
X747290Y118820D03*
X732500Y131319D03*
Y121319D03*
X728000Y103268D03*
X694500Y120500D03*
X694200Y133000D03*
X753473Y138459D03*
X714000Y240000D03*
X700000Y200000D03*
X732087Y207847D03*
X756000Y326000D03*
X718000Y332000D03*
X704500Y408500D03*
X685514Y397600D03*
X680514D03*
X716000Y568500D03*
X688000Y496000D03*
X728000Y556024D03*
Y537126D03*
Y546575D03*
X688298Y551625D03*
X732500Y504075D03*
X707700Y533200D03*
X696000Y525800D03*
X732500Y519075D03*
X713250Y533000D03*
X732500Y534075D03*
X724600Y487100D03*
X698600Y511100D03*
X685250Y540000D03*
X680902Y557860D03*
X676402D03*
X674250Y518000D03*
X714600Y498100D03*
X716400Y525200D03*
X695000Y540000D03*
X700000D03*
X705000D03*
X710000D03*
X747843Y612115D03*
X739500Y652697D03*
X710300Y635400D03*
Y615200D03*
X748200Y572200D03*
X732500Y574075D03*
X694200Y585500D03*
X732500Y584075D03*
X694500Y573000D03*
X746356Y604075D03*
X752200Y572300D03*
X710000Y760500D03*
X726500Y681500D03*
X693500Y680000D03*
X712000Y720000D03*
X709871Y686246D03*
X718100Y738500D03*
X718200Y744000D03*
X723000Y739200D03*
X723300Y743700D03*
X728175Y741300D03*
X728100Y745500D03*
X680526Y850100D03*
X685526D03*
X710000Y950500D03*
X739500Y933209D03*
X701700Y872700D03*
X714500Y870100D03*
X723600Y872400D03*
X712760Y915137D03*
X727600Y872300D03*
X733895Y901054D03*
X754000Y884524D03*
X757600Y884400D03*
X677000Y885500D03*
Y1028500D03*
X702500Y1010500D03*
X753050Y1028500D03*
X694500Y1026000D03*
X694000Y1038500D03*
X732500Y1036831D03*
Y1026831D03*
X730900Y955800D03*
X707700Y986200D03*
X696000Y978800D03*
X685250Y1004000D03*
X713250Y986000D03*
X728000Y1008780D03*
Y989882D03*
Y999331D03*
X732500Y986831D03*
Y971831D03*
X714400Y969600D03*
X680000Y1011000D03*
X675500D03*
X685250Y993000D03*
X675400Y980500D03*
X755200Y992400D03*
X716800Y978300D03*
X700000Y993000D03*
X705000D03*
X710000D03*
X695000D03*
X759249Y1008800D03*
X750000Y1084000D03*
X698000Y1102000D03*
X739500Y1105453D03*
X716500Y1091500D03*
X710300Y1068200D03*
X732500Y1066831D03*
Y1056831D03*
X759700Y1138600D03*
X759762Y1135000D03*
X738000Y1152000D03*
X740000Y1202000D03*
X748000Y1170000D03*
X746000Y1218000D03*
X700000Y1150000D03*
X698500Y1418900D03*
X693000Y1418800D03*
X689000Y1419000D03*
X681000Y1419100D03*
X685000Y1418900D03*
X703500Y1426000D03*
X676500Y1419500D03*
X742880Y1422632D03*
X739532Y1425934D03*
X720455Y1438500D03*
X684000Y1482000D03*
X699500Y1476000D03*
X685000Y1453500D03*
X690000Y1448500D03*
X695000Y1453500D03*
X690000Y1458500D03*
Y1453500D03*
X724248Y1465560D03*
X730500Y1451500D03*
X685850Y1468600D03*
X724000Y1439700D03*
X717600Y1449700D03*
X746832Y1451034D03*
X735232Y1439334D03*
X739332Y1462234D03*
X750867Y1438001D03*
X722200Y1476900D03*
X680900Y1469200D03*
X680200Y1465500D03*
X675550Y1458721D03*
Y1452216D03*
X692000Y1471156D03*
X689250Y1433500D03*
X681250D03*
X745000Y1463000D03*
X730341Y1446725D03*
X756332Y1465934D03*
X745032Y1468534D03*
X732232Y1477094D03*
X718900Y1472800D03*
X679800Y1483500D03*
X708600Y1469900D03*
X724066Y1461018D03*
X724255Y1457253D03*
X735232Y1451210D03*
X771500Y251000D03*
X802000Y263500D03*
X804500Y379000D03*
X769500Y431500D03*
X807500Y473700D03*
X835165Y470414D03*
X787971Y466121D03*
X791971D03*
X787971Y461921D03*
X791971D03*
X787971Y457721D03*
X791971D03*
X848799Y457202D03*
X849539Y453596D03*
X827313Y464805D03*
X827361Y459317D03*
X860519Y428234D03*
X860716Y417600D03*
X850947Y417592D03*
X832417Y459017D03*
X812282Y448094D03*
X815255Y451343D03*
X808395Y454315D03*
X834000Y499000D03*
X858740Y486430D03*
X846950Y645820D03*
Y640820D03*
X822841Y662242D03*
X794883Y639984D03*
X798475Y640227D03*
X863430Y618590D03*
X788160Y666220D03*
X814320Y651120D03*
X813980Y647430D03*
X860360Y605900D03*
X836862Y637500D03*
X815148Y654937D03*
X824618Y614617D03*
X827750Y611798D03*
X791530Y614700D03*
X791680Y619050D03*
X799900Y636300D03*
X807440Y629910D03*
X802900Y634000D03*
X839400Y744920D03*
X859664Y683428D03*
X837709Y681095D03*
X789442Y681063D03*
X796200Y682400D03*
X791243Y668081D03*
X778627Y735644D03*
X778683Y745049D03*
X853900Y839200D03*
X833300Y856920D03*
X841309Y796644D03*
X841800Y804499D03*
X854973Y780437D03*
X810700Y776500D03*
X818162Y819005D03*
X810659Y767500D03*
X778735Y839888D03*
X791500Y764500D03*
X795300Y764900D03*
X826000Y857400D03*
X815469Y811029D03*
X815330Y807050D03*
X818113Y814998D03*
X834200Y796220D03*
X810700Y772000D03*
Y781000D03*
X858500Y845700D03*
X858100Y850000D03*
X848300Y847700D03*
X804200Y798200D03*
X811372Y795900D03*
X808372Y797900D03*
X805372Y801700D03*
X834470Y944430D03*
X842270Y942411D03*
X818434Y919985D03*
X820883Y879428D03*
X820900Y888500D03*
X825900Y862040D03*
X801300Y924300D03*
X799303Y927296D03*
X822463Y920345D03*
X842270Y936402D03*
X861300Y895300D03*
X819000Y896100D03*
X817337Y886075D03*
X815400Y892800D03*
X844800Y895902D03*
X845732Y891713D03*
X826000Y1004000D03*
X846500Y997500D03*
X827000Y985500D03*
X796301Y959795D03*
X822470Y981470D03*
X839970D03*
X834470D03*
X826470D03*
X848400Y974100D03*
X836953Y1023500D03*
X826000Y1062000D03*
X846500Y1055000D03*
X826000Y1094000D03*
Y1128000D03*
X844000Y1092000D03*
Y1128000D03*
X842700Y1071900D03*
X782712Y1211404D03*
Y1206904D03*
X772601Y1223511D03*
Y1219011D03*
Y1214511D03*
X777101Y1223511D03*
X832800Y1147500D03*
X795100Y1150400D03*
X798920Y1150500D03*
X821900Y1173700D03*
X773300Y1159700D03*
X769800Y1156500D03*
X776800Y1169700D03*
X780722Y1166357D03*
X780000Y1162800D03*
X859113Y1283983D03*
X822500Y1331000D03*
Y1298000D03*
Y1294000D03*
X860000Y1410843D03*
X842500Y1411343D03*
X852000Y1402000D03*
Y1406000D03*
X822500Y1373500D03*
Y1369500D03*
X835000Y1402500D03*
Y1398000D03*
X822500Y1335000D03*
X820000Y1448000D03*
X772361Y1451972D03*
X882823Y331182D03*
X909236Y333242D03*
X906486Y330524D03*
X910330Y363490D03*
X908340Y360430D03*
X909423Y354393D03*
X898059Y343029D03*
X902184Y347219D03*
X906616Y351586D03*
X922800Y362400D03*
X922700Y358100D03*
X945408Y378761D03*
X950843Y378827D03*
X871591Y431161D03*
X870400Y454315D03*
X867299Y493300D03*
Y497200D03*
X922525Y519833D03*
X873000Y494100D03*
X929096Y517567D03*
X873200Y487300D03*
X944387Y520100D03*
X941557Y547005D03*
X955000Y540800D03*
X935477Y524023D03*
X938338Y529107D03*
X938579Y551379D03*
X938623Y556600D03*
X956100Y516500D03*
X867299Y508600D03*
Y504700D03*
X935490Y519550D03*
X878740Y655190D03*
Y647190D03*
X884801Y630225D03*
X892400Y633700D03*
X878740Y643190D03*
Y651190D03*
X870200Y631500D03*
X867260Y608600D03*
X883030Y611940D03*
X878600Y615600D03*
X879600Y621600D03*
X878400Y626200D03*
X932986Y752682D03*
X874858Y757002D03*
X874706Y752583D03*
X905100Y777000D03*
X915580Y857420D03*
X942500Y797867D03*
X876255Y818998D03*
X880983Y804420D03*
X874500Y774500D03*
X936543Y762518D03*
X957500Y842400D03*
X944000D03*
X924484Y812558D03*
X921047Y811463D03*
X869989Y818847D03*
X931800Y791500D03*
X870001Y822862D03*
X934800Y795300D03*
X916855Y810934D03*
X909144Y803346D03*
X903700Y803200D03*
X912762Y792801D03*
X903221Y793938D03*
X912030Y787650D03*
X907800Y788700D03*
X913059Y810367D03*
X906166Y812784D03*
X902560Y813313D03*
X876862Y842155D03*
X881702Y838859D03*
X874593Y763800D03*
X874821Y767690D03*
X931380Y821500D03*
X935485Y821400D03*
X903572Y773740D03*
X931206Y845756D03*
X920170Y857430D03*
X903500Y769900D03*
X939500Y842400D03*
X924670Y857430D03*
X953000Y842400D03*
X911080Y857420D03*
X948500Y842400D03*
X881216Y813813D03*
X910807Y766589D03*
X904484Y786109D03*
X876256Y798895D03*
X874500Y779100D03*
X866655Y855100D03*
X870200Y852203D03*
X872600Y798700D03*
X943294Y838833D03*
X903300Y763200D03*
X879205Y873548D03*
X918369Y923258D03*
X914208Y924279D03*
X883072Y886211D03*
X889458Y907846D03*
X877877Y891277D03*
X940750Y886000D03*
X928250Y885250D03*
X934500Y885156D03*
X894317Y865406D03*
X890117D03*
X894317Y861206D03*
X890117D03*
X879667Y877303D03*
X884684Y877406D03*
X927260Y922470D03*
X909760Y925445D03*
X922760Y922470D03*
X958256Y894438D03*
X930310Y858550D03*
X879770Y868369D03*
X895500Y1038000D03*
X891600Y980000D03*
X888000D03*
X886400Y976500D03*
X893600D03*
X897200D03*
X895200Y980000D03*
X890000Y976500D03*
X944500Y1134500D03*
X952500D03*
X951500Y1117500D03*
X947000D03*
X943000D03*
X949500Y1114500D03*
X954500D03*
X956500Y1117500D03*
X948298Y1215500D03*
X943500Y1233000D03*
X951500D03*
X959500D03*
X957000Y1207500D03*
X953100Y1211400D03*
X953000Y1203600D03*
X904000Y1191700D03*
X877400D03*
X928500Y1220700D03*
X890500Y1201200D03*
X885930Y1210537D03*
X892460Y1211340D03*
X887200Y1216460D03*
X893200Y1203660D03*
X888825Y1208263D03*
X889965Y1213936D03*
X884677Y1219029D03*
X947700Y1185500D03*
X947500Y1233000D03*
X955500D03*
X926700Y1199000D03*
X952500Y1193300D03*
X884056Y1283981D03*
X871556D03*
X888000Y1424000D03*
X926000Y1420000D03*
X876500Y1410843D03*
X888776Y1402228D03*
X901435Y1402196D03*
X866500Y1392892D03*
X913935Y1402196D03*
X869937Y1400312D03*
X941559Y1408198D03*
Y1403198D03*
X866000Y1398000D03*
X945415Y1429318D03*
X945414Y1412818D03*
X866000Y1452000D03*
X900000Y1450000D03*
X944019Y1452220D03*
X1033046Y379981D03*
X1035000Y370500D03*
X1032924Y374988D03*
X1038067Y441886D03*
X1021890Y439717D03*
X965700Y519617D03*
X962118Y534117D03*
X988341Y563811D03*
X968200Y547200D03*
X985631Y559671D03*
X984197Y533383D03*
X991538Y522018D03*
X1000051Y547644D03*
X974530Y559550D03*
X974550Y563690D03*
X1003591Y552081D03*
X996998Y539555D03*
X971420Y537950D03*
X975910Y537770D03*
X990200Y544250D03*
X995213Y529837D03*
X998905Y529824D03*
X986638Y519684D03*
X991360Y529780D03*
X963870Y754152D03*
X964200Y855600D03*
X1009600Y851054D03*
X986471Y829716D03*
X1009950Y838000D03*
X1025636Y854819D03*
X962000Y842400D03*
X966861Y772518D03*
X1050774Y815327D03*
X1050650Y825420D03*
X1022838Y829101D03*
X1042545Y832026D03*
X1015950Y838000D03*
X1026932Y841614D03*
X1050082Y843729D03*
X993400Y833250D03*
X969926Y847638D03*
X971197Y775799D03*
X977676Y828513D03*
X1005272Y837091D03*
X1000827Y837072D03*
X973070Y828512D03*
X1012125Y925875D03*
X1025251Y893000D03*
X1025065Y896965D03*
X1028500Y879500D03*
X1014807Y899075D03*
X1015007Y895000D03*
X997083Y895935D03*
X986728Y891100D03*
X974120Y858920D03*
X976242Y884600D03*
X980442Y882900D03*
X993942D03*
X1027524Y948954D03*
X1039500Y891100D03*
X1037110Y859471D03*
X989100Y899600D03*
X972042Y884600D03*
X985542Y882900D03*
X989742D03*
X996938Y901170D03*
X1034200Y945000D03*
X1040200D03*
X1046272Y944928D03*
X1039500Y874700D03*
X1024129Y946152D03*
X1044800Y893750D03*
X1030862Y951946D03*
X1022080Y960728D03*
X1032361Y1114039D03*
X1021970Y1096850D03*
X960500Y1134500D03*
X982500Y1136500D03*
X986500Y1131500D03*
X1013231Y1089300D03*
X1001687Y1111499D03*
X1008739Y1096000D03*
X961000Y1117500D03*
X1029500Y1104900D03*
X1028500Y1118601D03*
X1030178Y1134165D03*
X965500Y1128000D03*
X1012800Y1122100D03*
X1002671Y1124700D03*
X1029000Y1122400D03*
X977643Y1132490D03*
X1007431Y1122900D03*
X1020000Y1230000D03*
X971700Y1193100D03*
X963500Y1233000D03*
X967500D03*
X982500Y1217000D03*
Y1209000D03*
X960900Y1211400D03*
Y1203600D03*
X982500Y1144500D03*
X1026100Y1145996D03*
X1014500Y1153500D03*
X1012000Y1150000D03*
X1017500D03*
X1020000Y1153500D03*
X982500Y1201000D03*
Y1197000D03*
Y1213000D03*
Y1221000D03*
Y1225000D03*
Y1205000D03*
X964550Y1190200D03*
X1054918Y1330439D03*
Y1325739D03*
X1035943Y1424649D03*
X1031443Y1426899D03*
X1040127Y1422500D03*
X1033287Y1410500D03*
X1022818Y1393489D03*
X1024193Y1422899D03*
X1010943Y1413899D03*
X1005943Y1406700D03*
X975443Y1407700D03*
X992443Y1406700D03*
X1000443D03*
X988443D03*
X996443Y1406800D03*
X983943Y1407399D03*
X979443Y1406999D03*
X964810Y1421172D03*
X1037400Y1400600D03*
X1031400Y1399200D03*
X1054918Y1386039D03*
Y1353539D03*
Y1358239D03*
Y1381339D03*
X966985Y1393900D03*
X961857D03*
X996693Y1421399D03*
X988693D03*
X1047000Y1421800D03*
X1039900Y1417000D03*
X1038303Y1441709D03*
X1021818Y1470865D03*
X1021693Y1444649D03*
X993100Y1456550D03*
X1007618Y1477365D03*
X1013418Y1470865D03*
X1027288Y1467441D03*
X1034100Y1500564D03*
X1024175Y1482189D03*
X1002118Y1471365D03*
X998325Y1471434D03*
X992443Y1441399D03*
X1002443D03*
X997443Y1436399D03*
Y1446399D03*
Y1441399D03*
X965443Y1436399D03*
X987576Y1451454D03*
Y1455054D03*
X982343Y1446620D03*
Y1440115D03*
X961877Y1445347D03*
Y1441451D03*
X999443Y1458006D03*
X1049260Y1466691D03*
X1017618Y1470865D03*
X993830Y1471364D03*
X1017618Y1460865D03*
X1043606Y1437906D03*
X962136Y1431831D03*
X1033253Y1444649D03*
X1048553Y1448399D03*
X1035526Y1455899D03*
X1041176Y1455500D03*
X1020500Y1500014D03*
X1037550Y1475814D03*
X1089000Y217500D03*
X1150000Y250000D03*
X1100000D03*
X1098000Y378000D03*
X1136000D03*
X1100000Y350000D03*
Y300000D03*
X1150000D03*
X1144000Y418000D03*
X1136100Y460288D03*
X1147440Y473040D03*
X1143720Y468520D03*
X1143420Y472900D03*
X1139590Y468380D03*
X1139330Y472820D03*
X1135410Y468380D03*
X1135310Y472820D03*
X1130800Y472900D03*
X1131800Y446800D03*
X1136000Y446849D03*
X1092000Y448400D03*
X1088000Y448500D03*
X1103100Y457300D03*
X1095100Y455800D03*
X1113593Y476094D03*
X1093000Y502000D03*
X1149964Y481623D03*
X1102677Y487116D03*
X1119242Y477261D03*
X1083000Y620000D03*
X1095000D03*
X1112298Y618498D03*
X1134600Y618747D03*
X1118505Y658863D03*
X1114905Y658882D03*
X1129500Y619200D03*
X1138900Y584900D03*
X1125025Y621993D03*
X1056116Y697100D03*
X1057826Y680233D03*
X1059927Y688329D03*
X1064216Y683751D03*
X1067554Y694447D03*
X1071179Y682315D03*
X1112682Y681223D03*
X1107674Y677776D03*
X1141230Y673825D03*
X1103770Y675413D03*
X1075706Y941261D03*
X1141370Y905550D03*
X1058800Y893750D03*
X1130000Y994000D03*
X1106000D03*
X1138000Y970000D03*
X1093588Y972000D03*
X1110600Y964200D03*
X1108500Y960600D03*
X1104600Y967800D03*
X1101950Y962900D03*
X1101600Y953700D03*
X1087962Y959252D03*
X1084000Y1092000D03*
X1130000Y1154000D03*
X1078000Y1166000D03*
X1080000Y1230000D03*
X1068569Y1191530D03*
X1072931Y1191482D03*
X1072900Y1204500D03*
X1084571Y1200129D03*
X1072600Y1211400D03*
X1084400Y1204200D03*
X1121346Y1315676D03*
Y1319676D03*
X1100625Y1292025D03*
X1107000Y1323500D03*
X1083100Y1305600D03*
X1082080Y1299375D03*
X1126820Y1288500D03*
X1075030Y1323078D03*
X1078850Y1287900D03*
X1082080Y1309495D03*
X1123000Y1297600D03*
X1096280Y1288150D03*
X1092475Y1287971D03*
X1133480Y1296700D03*
Y1291700D03*
X1121346Y1307385D03*
Y1311385D03*
X1117000Y1332500D03*
Y1328500D03*
X1072120Y1299375D03*
Y1304495D03*
Y1309495D03*
Y1292460D03*
X1114000Y1430000D03*
X1105100Y1351000D03*
Y1355000D03*
X1124612Y1388773D03*
X1130112Y1363273D03*
X1138112D03*
X1132112Y1380773D03*
X1114112Y1363273D03*
X1118112D03*
X1126112D03*
X1099112Y1387273D03*
Y1379273D03*
X1110512Y1403273D03*
X1067712Y1384766D03*
X1099112Y1391273D03*
X1099100Y1375200D03*
X1099112Y1383273D03*
X1099100Y1371200D03*
X1117362Y1406073D03*
X1134112Y1363273D03*
X1122112D03*
X1091000Y1393500D03*
X1086646Y1396419D03*
X1126112Y1401773D03*
X1130873Y1490848D03*
Y1495848D03*
X1238000Y164000D03*
X1236500Y216000D03*
X1200000Y250000D03*
X1218000Y344000D03*
X1225600Y368700D03*
X1200000Y300000D03*
X1190000Y466000D03*
X1184000Y440000D03*
X1206000Y430500D03*
X1160900Y468500D03*
X1156110Y473330D03*
X1152600Y468470D03*
X1245567Y420602D03*
X1243500Y393600D03*
X1201000Y447000D03*
X1200500Y452000D03*
X1169000Y511500D03*
X1150900Y485100D03*
X1177100Y495300D03*
X1167000Y586500D03*
X1232490Y664290D03*
X1236690D03*
X1171700Y603700D03*
X1172500Y599700D03*
X1169125Y581776D03*
X1166550Y579200D03*
X1177350Y597792D03*
X1188000Y753500D03*
X1212587Y740895D03*
Y736695D03*
Y732495D03*
X1232490Y668490D03*
X1212587Y728295D03*
X1236690Y668490D03*
X1212587Y724095D03*
X1232490Y672690D03*
X1212587Y719895D03*
X1236690Y672690D03*
X1206414Y704261D03*
X1209931Y701608D03*
X1207468Y697962D03*
X1210283Y695565D03*
X1212587Y749295D03*
Y745095D03*
X1232490Y685290D03*
X1179129Y672187D03*
X1232490Y681090D03*
X1180000Y832000D03*
Y848000D03*
X1217089Y846182D03*
X1224088Y844900D03*
X1213611Y831932D03*
X1228344Y852351D03*
X1190995Y776395D03*
X1186690Y791440D03*
X1217111Y825000D03*
X1173990Y797760D03*
X1177300Y804960D03*
X1180520Y790880D03*
X1179690Y798020D03*
X1200337Y912300D03*
X1200407Y918060D03*
X1157556Y932754D03*
X1184778Y912848D03*
X1180090Y896524D03*
X1181550Y906100D03*
X1184750Y889200D03*
Y896300D03*
X1240000Y1070000D03*
X1176000D03*
X1200000Y1100000D03*
X1155600Y1074500D03*
X1178000Y1214000D03*
X1200000Y1200000D03*
Y1150000D03*
X1223730Y1285803D03*
X1230600D03*
X1235600D03*
X1216894Y1318783D03*
Y1314783D03*
X1202394Y1285803D03*
X1197394D03*
X1190524D03*
X1183894Y1319783D03*
Y1315783D03*
X1193894Y1292533D03*
X1227100D03*
X1205624D03*
X1238830D03*
X1185324Y1286563D03*
X1220450Y1292533D03*
X1216894Y1304283D03*
Y1308283D03*
X1183894Y1304783D03*
Y1308783D03*
X1196000Y1366000D03*
X1212000D03*
X1242000Y1412000D03*
X1236600Y1346763D03*
X1232100D03*
X1217100D03*
X1183894D03*
X1203394D03*
X1198894D03*
X1178712Y1372573D03*
X1200962Y1413023D03*
X1209819Y1417377D03*
X1188894Y1346763D03*
X1222000Y1346700D03*
X1180614Y1340033D03*
X1213820D03*
X1243768Y1376953D03*
X1208394Y1346763D03*
X1193894D03*
X1227100D03*
X1203312Y1402793D03*
X1241600Y1346763D03*
X1169412Y1396873D03*
X1226000Y1436000D03*
X1238000Y1444000D03*
X1190000Y1494000D03*
X1156000D03*
X1200000Y1450000D03*
X1326000Y92000D03*
X1298655Y59926D03*
X1282106Y81319D03*
Y66319D03*
X1299800Y56000D03*
X1278038Y93821D03*
X1278698Y84340D03*
X1307200Y45000D03*
X1289106Y27697D03*
X1282106Y51319D03*
X1303500Y35000D03*
X1297000Y68500D03*
X1319100Y47400D03*
X1308000Y35000D03*
X1309500Y76500D03*
X1314500D03*
X1299500D03*
X1304500D03*
X1261100Y16600D03*
X1264700Y16400D03*
X1262000Y174000D03*
X1313000Y185500D03*
X1314000Y150500D03*
X1282106Y161319D03*
Y151319D03*
X1302500Y152000D03*
X1305000Y185500D03*
X1298500D03*
X1282106Y131319D03*
Y121319D03*
X1266600Y119500D03*
X1262468Y103268D03*
X1256800Y132400D03*
X1322500Y113500D03*
X1317500D03*
X1327000D03*
X1262600Y119700D03*
X1272500Y213000D03*
X1307500Y205000D03*
X1338000Y225000D03*
X1289106Y199941D03*
X1252000Y358000D03*
X1294500Y331500D03*
X1278500Y313000D03*
X1259445Y379019D03*
X1337824Y379176D03*
X1262945Y377600D03*
X1294624Y358802D03*
X1317500Y435500D03*
X1316000Y419000D03*
X1269926Y400687D03*
X1262964Y400469D03*
X1281693Y473218D03*
X1274396Y407915D03*
X1247949Y423302D03*
X1250648Y425686D03*
X1245959Y435527D03*
X1265295Y421223D03*
X1257000Y434600D03*
X1248500Y393600D03*
X1298500Y562500D03*
X1317500Y533500D03*
X1277606Y546575D03*
Y556024D03*
Y537126D03*
X1307500Y501500D03*
X1299900Y534200D03*
X1311200Y511500D03*
X1282106Y519075D03*
Y534075D03*
Y504075D03*
X1303800Y522500D03*
X1327000Y487000D03*
X1325500Y504750D03*
X1323000Y566500D03*
X1318000D03*
X1328000D03*
X1300100Y530000D03*
X1326500Y514000D03*
X1312000Y501500D03*
X1272182Y571361D03*
X1334500Y549500D03*
Y554500D03*
Y539500D03*
Y544500D03*
X1318000Y660000D03*
X1332000Y646000D03*
X1312973Y643128D03*
X1282106Y614075D03*
X1273979Y652690D03*
X1305000Y638500D03*
X1298000Y638300D03*
X1314000Y603500D03*
X1282106Y574075D03*
Y604075D03*
Y584075D03*
X1302500Y605000D03*
X1272211Y575575D03*
X1254000Y748000D03*
X1312000Y812000D03*
X1278000Y810000D03*
X1250000Y820000D03*
X1337824Y832935D03*
X1247588Y842190D03*
X1310000Y860000D03*
X1270000Y868000D03*
X1274000Y933209D03*
X1325500Y907000D03*
X1298000Y1014000D03*
X1318000Y986000D03*
X1266000Y1046000D03*
X1252000Y1010000D03*
X1266400Y1024700D03*
X1282106Y1036831D03*
Y1026831D03*
X1300600Y986800D03*
X1307500Y954000D03*
X1311200Y964000D03*
X1282106Y956831D03*
X1303800Y975000D03*
X1277606Y1008780D03*
Y999331D03*
Y989882D03*
X1282106Y986831D03*
Y971831D03*
X1325500Y957250D03*
X1323000Y1019000D03*
X1318000D03*
X1328000D03*
X1300900Y981800D03*
X1326500Y966500D03*
X1262400Y1024700D03*
X1312000Y954000D03*
X1260000Y993500D03*
X1334500Y1002000D03*
Y1007000D03*
Y992000D03*
Y997000D03*
X1266000Y1128000D03*
X1264000Y1082000D03*
X1250000Y1100000D03*
X1289106Y1105453D03*
X1314000Y1056000D03*
X1313000Y1091000D03*
X1298500D03*
X1302500Y1057500D03*
X1305000Y1091000D03*
X1282106Y1066831D03*
Y1056831D03*
X1250000Y1200000D03*
Y1150000D03*
X1288000Y1296000D03*
X1274000Y1314000D03*
X1300000Y1388000D03*
X1274000Y1374000D03*
X1318540Y1424331D03*
X1273874Y1423000D03*
X1314375Y1424375D03*
X1327900Y1416500D03*
X1266914Y1394873D03*
X1258187Y1389753D03*
X1281624Y1409209D03*
X1253165Y1384633D03*
X1246949Y1379513D03*
X1263642Y1392313D03*
X1261224Y1387193D03*
X1277624Y1409209D03*
X1250347Y1382073D03*
X1306625Y1434000D03*
X1303874Y1453750D03*
X1292374Y1452500D03*
X1301534Y1431345D03*
X1289124Y1430700D03*
X1253374Y1459300D03*
X1260874Y1481400D03*
X1264774Y1470700D03*
X1266574Y1452300D03*
X1289574Y1483700D03*
X1252674Y1496800D03*
X1266474Y1487500D03*
X1278574Y1488700D03*
X1282374Y1445500D03*
Y1464000D03*
X1296374Y1430700D03*
X1297089Y1450307D03*
X1322000Y1430700D03*
X1284624Y1476400D03*
X1253374Y1470000D03*
X1260574Y1445600D03*
X1256474Y1446000D03*
X1432000Y30000D03*
X1358000Y91000D03*
X1406319Y66319D03*
Y81319D03*
X1401819Y93819D03*
Y84370D03*
X1435200Y58500D03*
X1427800Y69500D03*
X1406319Y51319D03*
X1413319Y27697D03*
X1431500Y48500D03*
X1435750Y73750D03*
X1436000Y48500D03*
X1392500Y173000D03*
X1389000Y148500D03*
X1422000Y98000D03*
X1346000Y179000D03*
X1351500Y144500D03*
X1406319Y151319D03*
Y161319D03*
X1426500Y152000D03*
X1422500Y185500D03*
X1429000D03*
X1406319Y121319D03*
Y131319D03*
X1401819Y103268D03*
X1391200Y119500D03*
X1376700Y136000D03*
X1394200Y113700D03*
X1428000Y238000D03*
X1388500Y230000D03*
X1394000Y249000D03*
X1397937Y199951D03*
X1373000Y234500D03*
X1388000Y378000D03*
X1400000Y350000D03*
X1341324Y372244D03*
X1378000Y430000D03*
X1376000Y414000D03*
X1436500Y430000D03*
X1341343Y400626D03*
X1348305Y400844D03*
X1352557Y399595D03*
X1367514Y397100D03*
X1362514D03*
X1384000Y554000D03*
X1352000Y516000D03*
X1432000Y482000D03*
X1364000Y492000D03*
X1401819Y546575D03*
Y556024D03*
Y537126D03*
X1406319Y534075D03*
Y519075D03*
Y504075D03*
X1413319Y480453D03*
X1424400Y534200D03*
X1431500Y501500D03*
X1435200Y511500D03*
X1427800Y522500D03*
X1424500Y529100D03*
X1436000Y501500D03*
X1345215Y533601D03*
X1382000Y592000D03*
X1384000Y646000D03*
X1358000Y600000D03*
X1413319Y652697D03*
X1406319Y614075D03*
X1422500Y638500D03*
X1429000D03*
X1406319Y604075D03*
Y584075D03*
Y574075D03*
X1394110Y575530D03*
X1426500Y605000D03*
X1383952Y573102D03*
X1430000Y752000D03*
X1346000Y704000D03*
X1382000Y688000D03*
X1384000Y782000D03*
X1400000Y850000D03*
X1348305Y853600D03*
X1341343Y853382D03*
X1352557Y852351D03*
X1341324Y825000D03*
X1367500Y851922D03*
X1362500D03*
X1413319Y933209D03*
X1342000Y976000D03*
X1356000Y998000D03*
X1424100Y987000D03*
X1391000Y1024800D03*
X1406319Y1036831D03*
Y1026831D03*
Y956831D03*
X1431500Y954000D03*
X1435200Y964000D03*
X1427800Y975000D03*
X1401819Y1008780D03*
Y999331D03*
Y989882D03*
X1406319Y986831D03*
Y971831D03*
X1424400Y982000D03*
X1386900Y1024600D03*
X1383200Y992700D03*
X1436000Y954000D03*
X1360000Y1054000D03*
X1350000Y1100000D03*
X1413319Y1105453D03*
X1426500Y1057500D03*
X1422500Y1091000D03*
X1429000D03*
X1406319Y1066831D03*
Y1056831D03*
X1350000Y1150000D03*
X1400000D03*
Y1200000D03*
X1350000D03*
X1366000Y1388000D03*
X1347400Y1416200D03*
X1406000Y1444000D03*
X1474000Y78000D03*
X1508000Y36000D03*
X1468000Y42000D03*
X1482000Y66000D03*
X1530531Y66319D03*
Y81319D03*
X1526031Y93819D03*
Y84370D03*
X1439500Y81000D03*
X1530531Y51319D03*
X1450500Y61000D03*
X1458500Y86500D03*
Y91500D03*
X1508500Y102500D03*
X1441100Y130800D03*
X1494000Y98000D03*
X1484000Y158000D03*
X1530531Y151319D03*
X1526823Y161308D03*
X1437000Y185500D03*
X1438000Y150500D03*
X1530531Y121319D03*
Y131319D03*
X1526031Y103268D03*
X1515400Y119400D03*
X1501300Y136100D03*
X1447000Y113500D03*
X1442000D03*
X1452000D03*
X1511400Y119500D03*
X1458500Y96500D03*
Y101500D03*
X1523100Y193700D03*
X1502000Y196000D03*
X1457500Y289000D03*
X1508500Y292500D03*
X1450000Y350000D03*
X1462036Y379176D03*
X1465536Y372244D03*
X1484000Y432000D03*
X1476769Y399595D03*
X1465555Y400626D03*
X1472517Y400844D03*
X1492014Y397100D03*
X1487014D03*
X1442500Y532000D03*
X1480000Y546000D03*
X1510000Y488000D03*
X1476000Y518000D03*
X1526031Y546575D03*
Y556024D03*
Y537126D03*
X1530531Y534075D03*
Y519075D03*
Y504075D03*
X1449500Y504750D03*
X1447000Y566500D03*
X1442000D03*
X1452000D03*
X1450500Y514000D03*
X1458500Y544500D03*
Y539500D03*
Y554500D03*
Y549500D03*
X1451800Y583800D03*
X1498000Y586000D03*
X1490000Y598000D03*
X1500000Y640000D03*
X1460000Y646000D03*
X1530531Y614075D03*
X1437000Y638500D03*
X1530531Y604075D03*
Y584075D03*
Y574075D03*
X1515200Y572200D03*
X1438000Y603500D03*
X1511200Y572300D03*
X1508000Y748000D03*
X1472517Y853600D03*
X1465555Y853382D03*
X1462036Y831932D03*
X1476769Y852351D03*
X1465536Y825000D03*
X1493500Y853100D03*
X1487000Y851600D03*
X1443992Y904962D03*
X1442500Y984500D03*
X1478000Y976000D03*
X1480000Y1020000D03*
X1515400Y1025000D03*
X1530531Y1036831D03*
Y1026831D03*
Y956831D03*
X1526031Y1008780D03*
Y999331D03*
Y989882D03*
X1530531Y986831D03*
Y971831D03*
X1450100Y959500D03*
X1447000Y1019000D03*
X1442000D03*
X1452000D03*
X1450500Y966500D03*
X1511400Y1024600D03*
X1506000Y993000D03*
X1458500Y1002000D03*
Y1007000D03*
Y992000D03*
Y997000D03*
X1500000Y1100000D03*
X1530531Y1066831D03*
Y1056831D03*
X1437000Y1091000D03*
X1438000Y1056000D03*
X1450000Y1150000D03*
X1500000D03*
Y1200000D03*
X1450000D03*
X1500000Y1300000D03*
X1450000D03*
Y1350000D03*
X1500000D03*
Y1450000D03*
X1450000D03*
X1594000Y56000D03*
X1574000Y26000D03*
X1608000Y62000D03*
Y50000D03*
X1549300Y56000D03*
X1548500Y62900D03*
X1553000Y35000D03*
X1556700Y45000D03*
X1537531Y27697D03*
X1548279Y69309D03*
X1575400Y50750D03*
X1557500Y35000D03*
X1549000Y76500D03*
X1554000D03*
X1564000D03*
X1559000D03*
X1593500Y160500D03*
X1546000Y112000D03*
X1547000Y156222D03*
Y185500D03*
X1562500Y150500D03*
X1561500Y185500D03*
X1553500Y189500D03*
X1625300Y136000D03*
X1596400Y135600D03*
Y131100D03*
Y126100D03*
X1598000Y206000D03*
X1568000Y204000D03*
X1592000Y236000D03*
X1616100Y203786D03*
X1550000Y350000D03*
X1586249Y379176D03*
X1589749Y372244D03*
X1553500Y431500D03*
X1604000Y432500D03*
X1600982Y399595D03*
X1596730Y400844D03*
X1589768Y400626D03*
X1611014Y397100D03*
X1616014D03*
X1566500Y533000D03*
X1604000Y536000D03*
X1594000Y506000D03*
X1558000Y482000D03*
X1559700Y511500D03*
X1556000Y501500D03*
X1548600Y534900D03*
X1552300Y522500D03*
X1537531Y480453D03*
X1574000Y504750D03*
X1571500Y566500D03*
X1566500D03*
X1576500D03*
X1548400Y528800D03*
X1575000Y514000D03*
X1560500Y501500D03*
X1583000Y544500D03*
Y539500D03*
Y554500D03*
Y549500D03*
X1570100Y583800D03*
X1568000Y660000D03*
X1584000Y648000D03*
X1553500Y638500D03*
X1561500Y639860D03*
X1537500Y656000D03*
X1551000Y605000D03*
X1562500Y603500D03*
X1602000Y684000D03*
X1566000Y772000D03*
X1550000Y850000D03*
X1596730Y853600D03*
X1589768Y853382D03*
X1586249Y831932D03*
X1597000Y857500D03*
X1591400Y825000D03*
X1616000Y850100D03*
X1611000D03*
X1599000Y941000D03*
X1579000Y940000D03*
X1564000Y876000D03*
X1537531Y933209D03*
X1572900Y902900D03*
X1604000Y1022000D03*
X1544000Y1004500D03*
X1566500Y985500D03*
X1600500Y975000D03*
X1612000Y980000D03*
X1548900Y987600D03*
X1556000Y954000D03*
X1559700Y964000D03*
X1552300Y975000D03*
X1574000Y957250D03*
X1571500Y1019000D03*
X1566500D03*
X1576500D03*
X1575000Y966500D03*
X1548900Y981500D03*
X1560500Y954000D03*
X1583000Y997000D03*
Y992000D03*
Y1007000D03*
Y1002000D03*
X1561500Y1091000D03*
X1553500D03*
X1600000Y1100000D03*
X1537531Y1105453D03*
X1551000Y1057500D03*
X1547000Y1091000D03*
X1562500Y1056000D03*
X1600000Y1200000D03*
Y1150000D03*
X1550000Y1300000D03*
X1600000D03*
X1550000Y1350000D03*
X1600000D03*
Y1450000D03*
X1550000D03*
X1718000Y66000D03*
X1680000Y26000D03*
X1632000D03*
X1676300Y69500D03*
X1683700Y58500D03*
X1686730Y80991D03*
X1654744Y66319D03*
Y81319D03*
X1650244Y93819D03*
Y84370D03*
X1680000Y48500D03*
X1654744Y51319D03*
X1661744Y27697D03*
X1699000Y61000D03*
X1672900Y76400D03*
X1684500Y48500D03*
X1692200Y86200D03*
Y91200D03*
X1636000Y176000D03*
X1677500Y185500D03*
X1686500Y150500D03*
X1675000Y152000D03*
X1654744Y151319D03*
Y161319D03*
X1685500Y185500D03*
X1654744Y121319D03*
X1653206Y134559D03*
X1650244Y103268D03*
X1639300Y119500D03*
X1690400Y114100D03*
X1695400D03*
X1700400D03*
X1635300Y119600D03*
X1692300Y96100D03*
X1707000Y103500D03*
X1648000Y212000D03*
X1682000Y206000D03*
X1661744Y199941D03*
X1671003Y190635D03*
X1712525Y191268D03*
X1650000Y380000D03*
X1638500Y311500D03*
X1715000Y305500D03*
X1648000Y468000D03*
X1714000Y391000D03*
X1721762Y458436D03*
Y454436D03*
X1696359Y452707D03*
X1689359D03*
X1691859Y460207D03*
X1687359Y457207D03*
X1681859Y452707D03*
X1709496Y463382D03*
X1717859Y463907D03*
X1714026Y464191D03*
X1711199Y453177D03*
X1708359Y449207D03*
X1706859Y445207D03*
X1682000Y484000D03*
X1720000Y506000D03*
X1650244Y546575D03*
Y556024D03*
Y537126D03*
X1654744Y534075D03*
Y519075D03*
Y504075D03*
X1661744Y480453D03*
X1680000Y501500D03*
X1673200Y535100D03*
X1683700Y511500D03*
X1676300Y522500D03*
X1698000Y504750D03*
X1695500Y566500D03*
X1690500D03*
X1700500D03*
X1673200Y529000D03*
X1699000Y514000D03*
X1684500Y501500D03*
X1707083Y543435D03*
Y538435D03*
X1706800Y556300D03*
X1706935Y548158D03*
X1706000Y646000D03*
X1632000Y648000D03*
X1634000Y618000D03*
X1661744Y652697D03*
X1654744Y614075D03*
X1671000Y638500D03*
X1685500D03*
X1677500D03*
X1654744Y604075D03*
Y584075D03*
X1652808Y574040D03*
X1686500Y603500D03*
X1675000Y605000D03*
X1638200Y572200D03*
X1634200D03*
X1700000Y700000D03*
X1650000D03*
Y750000D03*
X1700000D03*
X1650000Y850000D03*
X1720942Y853600D03*
X1713980Y853382D03*
X1710461Y831932D03*
X1713961Y825000D03*
X1690200Y937700D03*
X1718000Y938000D03*
X1716000Y878000D03*
X1661800Y933400D03*
X1709500Y900700D03*
X1668000Y1004000D03*
X1690500Y986000D03*
X1672800Y987300D03*
X1639100Y1024900D03*
X1654744Y1036831D03*
Y1026831D03*
Y956831D03*
X1676300Y975000D03*
X1683700Y964000D03*
X1680000Y954000D03*
X1650244Y1008780D03*
Y999331D03*
Y989882D03*
X1654744Y986831D03*
Y971831D03*
X1698000Y957250D03*
X1695500Y1019000D03*
X1690500D03*
X1700500D03*
X1699000Y966500D03*
X1672800Y981200D03*
X1635100Y1024700D03*
X1631500Y994000D03*
X1684500Y954000D03*
X1707000Y997000D03*
Y992000D03*
Y1007000D03*
Y1002000D03*
X1638000Y1082000D03*
X1696000Y1106000D03*
X1661744Y1105453D03*
X1677500Y1091000D03*
X1686500Y1056000D03*
X1671000Y1091000D03*
X1675000Y1057500D03*
X1685500Y1091000D03*
X1654744Y1066831D03*
Y1056831D03*
X1650000Y1150000D03*
X1700000D03*
Y1200000D03*
X1650000D03*
Y1300000D03*
X1676511Y1292495D03*
X1674000Y1410000D03*
X1650000Y1350000D03*
X1669376Y1429200D03*
X1651906Y1428973D03*
X1719726Y1402700D03*
X1716026Y1416500D03*
X1663906Y1428973D03*
X1659906D03*
X1694751Y1434000D03*
X1683926Y1453750D03*
X1672626Y1452500D03*
X1686226Y1432500D03*
X1656250Y1461250D03*
X1662626Y1464000D03*
Y1445500D03*
X1674926Y1447400D03*
X1676626Y1432000D03*
X1702501Y1434000D03*
X1661626Y1480000D03*
X1756000Y25500D03*
X1730000Y58000D03*
X1811700Y59550D03*
X1808600Y78200D03*
X1803500Y82200D03*
X1778956Y66319D03*
Y81319D03*
X1774456Y93819D03*
Y84370D03*
X1785956Y27697D03*
X1778956Y51319D03*
X1795600Y44900D03*
X1817500Y32700D03*
X1814850Y21500D03*
X1799094Y82033D03*
X1811600Y32800D03*
X1794300Y63400D03*
X1796300Y85600D03*
X1806300D03*
X1811300D03*
X1801300D03*
X1803620Y57000D03*
X1807500Y57400D03*
X1730500Y177500D03*
X1730000Y136000D03*
X1746000Y106000D03*
X1809500Y185500D03*
X1801500D03*
X1811305Y147994D03*
X1799000Y152000D03*
X1795000Y185500D03*
X1778956Y151319D03*
Y161319D03*
Y121319D03*
Y131319D03*
X1774456Y103268D03*
X1763600Y119400D03*
X1749700Y135600D03*
X1759600Y119500D03*
X1804000Y205000D03*
X1724000Y232000D03*
X1754000Y234000D03*
X1750000Y200000D03*
X1785956Y199941D03*
X1768000Y310000D03*
X1781500Y366000D03*
X1801642Y379532D03*
X1805142Y372600D03*
X1724000Y422000D03*
X1745737Y400643D03*
X1800436Y412804D03*
X1804436D03*
X1809633Y420927D03*
Y416927D03*
X1795433D03*
Y420927D03*
X1759904Y400647D03*
X1812123Y401200D03*
X1805142Y400982D03*
X1814359Y473207D03*
X1725596Y447182D03*
X1729596Y443182D03*
X1725596D03*
X1729596Y455182D03*
X1725596D03*
X1729596Y459182D03*
X1725596D03*
Y451182D03*
X1729596Y447182D03*
Y451182D03*
X1731710Y475473D03*
X1749952Y405830D03*
X1764168Y405501D03*
X1816375Y399951D03*
X1723896Y474582D03*
X1753631Y405830D03*
X1735014Y397100D03*
X1740014D03*
X1755159Y469723D03*
X1740906Y465239D03*
X1746859Y465707D03*
X1724096Y464344D03*
X1746959Y459107D03*
X1742758Y456059D03*
X1813700Y548300D03*
X1796000Y566500D03*
X1728000Y554000D03*
X1757200Y558900D03*
X1730000Y568000D03*
X1809559Y482507D03*
Y486507D03*
X1795359D03*
Y482507D03*
X1800556Y490630D03*
X1804556D03*
X1774456Y556024D03*
X1767342Y533721D03*
X1774456Y546575D03*
X1785956Y480453D03*
X1804000Y501500D03*
X1807700Y511500D03*
X1800300Y522500D03*
X1798100Y537973D03*
X1785728Y538736D03*
X1778956Y519075D03*
Y504075D03*
X1814500Y566500D03*
X1797400Y528800D03*
X1742859Y484707D03*
X1808500Y501500D03*
X1818000Y656000D03*
X1762000Y628000D03*
X1756000Y646000D03*
X1785956Y652697D03*
X1795000Y638500D03*
X1801500D03*
X1809500D03*
X1778956Y614075D03*
X1810500Y603500D03*
X1799000Y605000D03*
X1778956Y604075D03*
Y584075D03*
Y574075D03*
X1759750Y576000D03*
Y587000D03*
X1758000Y748000D03*
X1756000Y684000D03*
X1808000Y848000D03*
X1760000Y846000D03*
X1800000Y800000D03*
X1725194Y852351D03*
X1740000Y850100D03*
X1735000D03*
X1778500Y917500D03*
X1738000Y904000D03*
X1796166Y892754D03*
Y888754D03*
X1785956Y933209D03*
X1804000Y885500D03*
Y881500D03*
X1800000Y885500D03*
Y893500D03*
X1804000D03*
X1800000Y889500D03*
X1804000D03*
X1800000Y877500D03*
X1804000D03*
X1800000Y881500D03*
X1806114Y909791D03*
X1770763Y887025D03*
X1763763D03*
X1766263Y894525D03*
X1761763Y891525D03*
X1756263Y887025D03*
X1798300Y908900D03*
X1817263Y919025D03*
X1815310Y899557D03*
X1783900Y897700D03*
X1792263Y898225D03*
X1798500Y898662D03*
X1788430Y898509D03*
X1817739Y889758D03*
X1785603Y887495D03*
X1782763Y883525D03*
X1781263Y879525D03*
X1794500Y1007000D03*
X1814500Y985500D03*
X1724000Y974000D03*
X1728000Y1002000D03*
X1796900Y987200D03*
X1763300Y1024800D03*
X1778956Y1036831D03*
Y1026831D03*
X1800300Y975000D03*
X1804000Y954000D03*
X1807700Y964000D03*
X1778956Y956831D03*
X1774456Y1008780D03*
Y999331D03*
Y989882D03*
X1778956Y986831D03*
Y971831D03*
X1814500Y1019000D03*
X1796900Y981100D03*
X1759300Y1024900D03*
X1808500Y954000D03*
X1756000Y993500D03*
X1730000Y1050000D03*
X1762000Y1080000D03*
X1785956Y1105453D03*
X1809500Y1091000D03*
X1801500D03*
X1810500Y1056000D03*
X1795000Y1091000D03*
X1799000Y1057500D03*
X1778956Y1066831D03*
Y1056831D03*
X1750000Y1150000D03*
Y1200000D03*
X1800000Y1300000D03*
Y1250000D03*
X1760000Y1394000D03*
X1800000Y1350000D03*
X1735126Y1416300D03*
X1790226Y1458600D03*
X1803426Y1452600D03*
X1804326Y1480500D03*
X1794226Y1473300D03*
X1810426Y1476200D03*
X1790226Y1469300D03*
X1800326Y1445800D03*
X1794426Y1446400D03*
X1820200Y70140D03*
X1898669Y93819D03*
Y84370D03*
X1903169Y66319D03*
Y81319D03*
X1885200Y81000D03*
X1871400Y82000D03*
X1903169Y51319D03*
X1910169Y27697D03*
X1887900Y41300D03*
X1878000Y29300D03*
X1884600Y49000D03*
X1821850Y35400D03*
X1824200Y23400D03*
Y19000D03*
X1868600Y68922D03*
X1872900Y49000D03*
X1870607Y75897D03*
X1823300Y88600D03*
X1845900Y77300D03*
X1840900D03*
X1850800Y77200D03*
X1860500Y38100D03*
X1863950Y45400D03*
X1859050Y19000D03*
X1885508Y77413D03*
X1891300Y49400D03*
X1880500Y48900D03*
X1842400Y29500D03*
X1875500Y87000D03*
X1880500D03*
X1865500D03*
X1870500D03*
X1851500Y171500D03*
X1867600Y104300D03*
X1903169Y151319D03*
Y161319D03*
X1881000Y162200D03*
X1883000Y181500D03*
X1841000Y140000D03*
X1903169Y121319D03*
Y131319D03*
X1898669Y103268D03*
X1860817Y120141D03*
X1864800Y132500D03*
X1834018Y169783D03*
X1823500Y113500D03*
X1819134Y109132D03*
X1819000Y113500D03*
X1840500Y237500D03*
X1850000Y200000D03*
X1900000Y250000D03*
X1910169Y199941D03*
X1829500Y311000D03*
X1900000Y300000D03*
Y350000D03*
X1830000Y424000D03*
X1838000Y415500D03*
X1850000Y400000D03*
X1900000D03*
Y450000D03*
X1818359Y473207D03*
X1822359D03*
X1826359D03*
X1830359D03*
X1834359D03*
X1827114Y397900D03*
X1832114D03*
X1836476Y467034D03*
X1884000Y488000D03*
X1854000Y482000D03*
X1875000Y558000D03*
X1898669Y546575D03*
Y556024D03*
Y537126D03*
X1883200Y534600D03*
X1855750Y551000D03*
X1903169Y534075D03*
Y519075D03*
Y504075D03*
X1910169Y480453D03*
X1866700Y512800D03*
X1866500Y507250D03*
X1859300Y524500D03*
X1822000Y504750D03*
X1848500Y504000D03*
X1819500Y566500D03*
X1824500D03*
X1855750Y540000D03*
X1839750Y530250D03*
X1841500Y558000D03*
X1846000D03*
X1850500D03*
X1823000Y514000D03*
X1883300Y530000D03*
X1853000Y504000D03*
X1870500Y540500D03*
X1865500D03*
X1880500D03*
X1875500D03*
X1831000Y544500D03*
Y539500D03*
Y554500D03*
Y549500D03*
X1851400Y623800D03*
X1850000Y650000D03*
X1910169Y652697D03*
X1903169Y614075D03*
X1880500Y615200D03*
X1887000Y638500D03*
X1903169Y604075D03*
Y584075D03*
Y574075D03*
X1865000Y573000D03*
X1864700Y585500D03*
X1841000Y593000D03*
X1846000Y686000D03*
X1900000Y750000D03*
Y700000D03*
Y800000D03*
X1874540Y847322D03*
X1878540D03*
X1883737Y855445D03*
Y851445D03*
X1869537D03*
Y855445D03*
X1849407Y852351D03*
X1845155Y853600D03*
X1838193Y853382D03*
X1834674Y831932D03*
X1838174Y825000D03*
X1859500Y850100D03*
X1864500D03*
X1883663Y917025D03*
Y921025D03*
X1874660Y925148D03*
X1878660D03*
X1869463Y921025D03*
Y917025D03*
X1910169Y933209D03*
X1888763Y907525D03*
X1892763D03*
X1896763D03*
X1900763D03*
X1904763D03*
X1908763D03*
X1820700Y940600D03*
X1848500Y940200D03*
X1829563Y904041D03*
X1828763Y865025D03*
X1821263Y900025D03*
X1821363Y893425D03*
X1872500Y1010500D03*
X1826000Y1036500D03*
X1864500Y1038500D03*
X1865000Y1026000D03*
X1903169Y1036831D03*
Y1026831D03*
X1841000Y1046000D03*
X1903169Y956831D03*
X1859600Y960250D03*
X1883100Y984750D03*
X1870800Y973100D03*
X1898669Y1008780D03*
Y999331D03*
Y989882D03*
X1903169Y986831D03*
Y971831D03*
X1855750Y1004000D03*
X1859300Y977500D03*
X1822000Y957250D03*
X1848500Y957000D03*
X1850500Y1011000D03*
X1846000D03*
X1841500D03*
X1819500Y1019000D03*
X1824500D03*
X1855750Y993000D03*
X1823000Y966500D03*
X1839750Y983000D03*
X1875800Y981000D03*
X1853000Y957000D03*
X1865500Y993000D03*
X1881814Y993136D03*
X1876814D03*
X1871814D03*
X1831000Y1002000D03*
Y1007000D03*
Y992000D03*
Y997000D03*
X1827600Y970700D03*
X1850000Y1078000D03*
X1910169Y1105453D03*
X1887000Y1091500D03*
X1880500Y1068200D03*
X1903169Y1066831D03*
Y1056831D03*
X1850000Y1200000D03*
X1900000D03*
Y1150000D03*
X1850000D03*
X1900000Y1300000D03*
X1850000D03*
X1900000Y1250000D03*
X1850000D03*
X1900000Y1400000D03*
X1850000D03*
Y1350000D03*
X1900000D03*
X1904000Y1504000D03*
X1878000Y1484000D03*
X1822000Y1444000D03*
X1900000Y1450000D03*
X1824826Y1470900D03*
X1822326Y1481600D03*
X1919000Y51000D03*
X1922400Y470400D03*
X1923600Y913525D03*
X1914500Y902000D03*
X1918800Y1112100D03*
X2261450Y1225300D03*
G54D30*
X1104528Y1162257D03*
X2261450Y195100D03*
G54D21*
X167716Y1495669D03*
X233858D03*
X548031D03*
X614173D03*
X1314960D03*
X1381102D03*
X1695275D03*
X1761417D03*
X2261450Y316300D03*
G54D12*
X100412Y6000D03*
X95412D03*
X90412D03*
X85412D03*
X80412D03*
X75412D03*
X70412D03*
X65412D03*
X60412D03*
X55412D03*
X50412D03*
X45412D03*
X40412D03*
X35412D03*
X30412D03*
X25412D03*
X20412D03*
X15412D03*
X10412D03*
X6000Y6588D03*
Y11588D03*
Y16588D03*
Y21588D03*
Y26588D03*
Y31588D03*
Y36588D03*
Y41588D03*
Y46588D03*
Y51588D03*
Y56588D03*
Y61588D03*
Y66588D03*
Y71588D03*
Y76588D03*
Y81588D03*
Y86588D03*
Y91588D03*
Y96588D03*
Y101588D03*
Y106588D03*
Y111588D03*
Y116588D03*
Y121588D03*
Y126588D03*
Y131588D03*
Y136588D03*
Y141588D03*
Y146588D03*
Y151588D03*
Y156588D03*
Y161588D03*
Y166588D03*
Y171588D03*
Y176588D03*
Y181588D03*
Y186588D03*
Y191588D03*
Y196588D03*
Y201588D03*
Y206588D03*
Y211588D03*
Y216588D03*
Y221588D03*
Y226588D03*
Y231588D03*
Y236588D03*
Y241588D03*
Y246588D03*
Y251588D03*
Y256588D03*
Y261588D03*
Y266588D03*
Y271588D03*
Y276588D03*
Y281588D03*
Y286588D03*
Y291588D03*
Y296588D03*
Y301588D03*
Y306588D03*
Y311588D03*
Y316588D03*
Y321588D03*
Y326588D03*
Y331588D03*
Y336588D03*
Y341588D03*
Y346588D03*
Y351588D03*
Y356588D03*
Y361588D03*
Y366588D03*
Y371588D03*
Y376588D03*
Y441588D03*
Y436588D03*
Y431588D03*
Y426588D03*
Y421588D03*
Y416588D03*
Y411588D03*
Y406588D03*
Y386588D03*
Y391588D03*
Y396588D03*
Y401588D03*
Y446588D03*
Y451588D03*
Y456588D03*
Y461588D03*
Y381588D03*
Y466588D03*
Y471588D03*
Y476588D03*
Y481588D03*
Y486588D03*
Y491588D03*
Y496588D03*
Y501588D03*
Y506588D03*
Y511588D03*
Y516588D03*
Y521588D03*
Y526588D03*
Y531588D03*
Y536588D03*
Y541588D03*
Y546588D03*
Y551588D03*
Y556588D03*
Y561588D03*
Y566588D03*
Y571588D03*
Y576588D03*
Y581588D03*
Y586588D03*
Y591588D03*
Y596588D03*
Y601588D03*
Y606588D03*
Y611588D03*
Y616588D03*
Y621588D03*
Y626588D03*
Y631588D03*
Y636588D03*
Y641588D03*
Y646588D03*
Y651588D03*
Y656588D03*
Y661588D03*
Y666588D03*
Y671588D03*
Y676588D03*
Y681588D03*
Y686588D03*
Y691588D03*
Y696588D03*
Y701588D03*
Y706588D03*
Y711588D03*
Y716588D03*
Y721588D03*
Y726588D03*
Y731588D03*
Y736588D03*
Y741588D03*
Y746588D03*
Y751588D03*
Y756588D03*
Y761588D03*
Y766588D03*
Y771588D03*
Y776588D03*
Y781588D03*
Y786588D03*
Y791588D03*
Y796588D03*
Y801588D03*
Y806588D03*
Y811588D03*
Y816588D03*
Y821588D03*
Y826588D03*
Y831588D03*
Y836588D03*
Y841588D03*
Y846588D03*
Y851588D03*
Y856588D03*
Y861588D03*
Y866588D03*
Y871588D03*
Y876588D03*
Y881588D03*
Y886588D03*
Y891588D03*
Y896588D03*
Y901588D03*
Y906588D03*
Y911588D03*
Y916588D03*
Y921588D03*
Y926588D03*
Y931588D03*
Y936588D03*
Y941588D03*
Y946588D03*
Y951588D03*
X26300Y873700D03*
Y864100D03*
Y868900D03*
X21500Y873700D03*
Y864100D03*
Y868900D03*
X6000Y956588D03*
Y961588D03*
Y966588D03*
Y971588D03*
Y976588D03*
Y981588D03*
Y986588D03*
Y991588D03*
Y996588D03*
Y1001588D03*
Y1006588D03*
Y1011588D03*
Y1016588D03*
Y1021588D03*
Y1026588D03*
Y1031588D03*
Y1036588D03*
Y1041588D03*
Y1046588D03*
Y1051588D03*
Y1056588D03*
Y1061588D03*
Y1066588D03*
Y1071588D03*
Y1076588D03*
Y1081588D03*
Y1086588D03*
Y1091588D03*
Y1096588D03*
Y1101588D03*
Y1106588D03*
Y1111588D03*
Y1116588D03*
Y1121588D03*
Y1126588D03*
Y1131588D03*
Y1136588D03*
Y1141588D03*
Y1146588D03*
Y1151588D03*
Y1156588D03*
Y1161588D03*
Y1166588D03*
Y1171588D03*
Y1176588D03*
Y1181588D03*
Y1186588D03*
Y1191588D03*
Y1196588D03*
Y1201588D03*
Y1206588D03*
Y1211588D03*
Y1216588D03*
Y1221588D03*
Y1226588D03*
Y1231588D03*
Y1236588D03*
Y1321588D03*
Y1326588D03*
Y1331588D03*
Y1286588D03*
Y1291588D03*
Y1296588D03*
Y1301588D03*
Y1306588D03*
Y1311588D03*
Y1316588D03*
Y1241588D03*
Y1246588D03*
Y1251588D03*
Y1256588D03*
Y1261588D03*
Y1266588D03*
Y1271588D03*
Y1276588D03*
Y1281588D03*
Y1421588D03*
Y1416588D03*
Y1411588D03*
Y1406588D03*
Y1401588D03*
Y1396588D03*
Y1391588D03*
Y1386588D03*
Y1381588D03*
Y1376588D03*
Y1371588D03*
Y1366588D03*
Y1361588D03*
Y1356588D03*
Y1351588D03*
Y1346588D03*
Y1341588D03*
Y1426588D03*
Y1336588D03*
Y1451588D03*
Y1446588D03*
Y1441588D03*
Y1436588D03*
Y1431588D03*
X99000Y1501000D03*
X61500Y1502000D03*
X87539Y1499118D03*
X82539D03*
X77539D03*
X72539D03*
X67539D03*
X92539D03*
X11000Y1455500D03*
X15500Y1458500D03*
X17811Y1462693D03*
Y1467693D03*
Y1472693D03*
Y1477693D03*
Y1482693D03*
Y1487693D03*
Y1492693D03*
Y1497693D03*
Y1502693D03*
Y1507693D03*
X17500Y1512000D03*
X21819Y1513685D03*
X26819D03*
X31819D03*
X36819D03*
X41819D03*
X46819D03*
X51819D03*
X56819D03*
X58500Y1508000D03*
X195412Y6000D03*
X190412D03*
X185412D03*
X180412D03*
X175412D03*
X170412D03*
X165412D03*
X160412D03*
X155412D03*
X150412D03*
X145412D03*
X140412D03*
X135412D03*
X130412D03*
X125412D03*
X120412D03*
X115412D03*
X110412D03*
X105412D03*
X127600Y437500D03*
Y432700D03*
X122800Y437500D03*
Y432700D03*
X127600Y427900D03*
X122800D03*
X169215Y876085D03*
Y880885D03*
X154215D03*
Y876085D03*
X169215Y895685D03*
Y890885D03*
X154215Y895685D03*
Y890885D03*
X164200Y885700D03*
X158900D03*
X192963Y888625D03*
Y883625D03*
X188163Y888625D03*
X183363D03*
X178563D03*
Y883625D03*
X173763D03*
Y888625D03*
X183363Y883625D03*
X188163D03*
X113363Y884925D03*
X180000Y1424000D03*
Y1430000D03*
X186000Y1424000D03*
Y1430000D03*
X152000Y1377000D03*
Y1383000D03*
X158000Y1377000D03*
Y1383000D03*
X170000D03*
Y1377000D03*
X164000Y1383000D03*
Y1377000D03*
X102000Y1505500D03*
X177433Y1513685D03*
X182433D03*
X187433D03*
X192433D03*
X147433D03*
X152433D03*
X157433D03*
X162433D03*
X167433D03*
X172433D03*
X103000Y1511000D03*
X107433Y1513685D03*
X112433D03*
X117433D03*
X122433D03*
X127433D03*
X132433D03*
X137433D03*
X142433D03*
X290412Y6000D03*
X285412D03*
X280412D03*
X275412D03*
X270412D03*
X265412D03*
X260412D03*
X255412D03*
X250412D03*
X245412D03*
X240412D03*
X235412D03*
X230412D03*
X225412D03*
X220412D03*
X215412D03*
X210412D03*
X205412D03*
X200412D03*
X251200Y457900D03*
Y438300D03*
Y443100D03*
Y453100D03*
X291500Y451100D03*
Y446100D03*
X286700D03*
Y451100D03*
X281900D03*
Y446100D03*
X272300D03*
Y451100D03*
X277100Y446100D03*
Y451100D03*
X267752Y458160D03*
Y438560D03*
Y443360D03*
Y453360D03*
X257127Y448364D03*
X261927D03*
X211590Y427289D03*
X211190Y447189D03*
X197763Y888625D03*
Y883625D03*
X233074Y1429500D03*
X239274Y1429600D03*
X237235Y1419039D03*
X236974Y1425000D03*
X283000Y1492000D03*
X279000Y1498500D03*
X197433Y1513685D03*
X202433D03*
X207433D03*
X212433D03*
X217433D03*
X222433D03*
X227433D03*
X232433D03*
X237433D03*
X242433D03*
X247433D03*
X252433D03*
X257433D03*
X262433D03*
X267433D03*
X272433D03*
X277433D03*
X278646Y1509398D03*
Y1504398D03*
X288685Y1490063D03*
X385412Y6000D03*
X380412D03*
X375412D03*
X370412D03*
X365412D03*
X360412D03*
X355412D03*
X350412D03*
X345412D03*
X340412D03*
X335412D03*
X330412D03*
X325412D03*
X320412D03*
X315412D03*
X310412D03*
X305412D03*
X300412D03*
X295412D03*
X296300Y446100D03*
Y451100D03*
X380780Y1428599D03*
Y1422599D03*
Y1416599D03*
Y1410599D03*
X374780Y1428599D03*
Y1422599D03*
Y1416599D03*
Y1410599D03*
X293685Y1490063D03*
X298685D03*
X303685D03*
X308685D03*
X313685D03*
X318685D03*
X323685D03*
X328685D03*
X333685D03*
X338685D03*
X343685D03*
X348685D03*
X353685D03*
X358685D03*
X363685D03*
X368685D03*
X373685D03*
X378685D03*
X383685D03*
X380780Y1434599D03*
X374780D03*
X480412Y6000D03*
X475412D03*
X470412D03*
X465412D03*
X460412D03*
X455412D03*
X450412D03*
X445412D03*
X440412D03*
X435412D03*
X430412D03*
X425412D03*
X420412D03*
X415412D03*
X410412D03*
X405412D03*
X400412D03*
X395412D03*
X390412D03*
X388685Y1490063D03*
X393685D03*
X398685D03*
X403685D03*
X408685D03*
X413685D03*
X418685D03*
X423685D03*
X428685D03*
X433685D03*
X438685D03*
X443685D03*
X448685D03*
X453685D03*
X458685D03*
X463685D03*
X468685D03*
X473685D03*
X478685D03*
X575412Y6000D03*
X570412D03*
X565412D03*
X560412D03*
X555412D03*
X550412D03*
X545412D03*
X540412D03*
X535412D03*
X530412D03*
X525412D03*
X520412D03*
X515412D03*
X510412D03*
X505412D03*
X500412D03*
X495412D03*
X490412D03*
X485412D03*
X501000Y1494000D03*
X503000Y1499000D03*
X494500Y1490500D03*
X574937Y1513685D03*
X569937D03*
X564937D03*
X559937D03*
X554937D03*
X549937D03*
X544937D03*
X539937D03*
X534937D03*
X529937D03*
X524937D03*
X483685Y1490063D03*
X488685D03*
X503244Y1504378D03*
Y1509378D03*
X504937Y1513685D03*
X509937D03*
X514937D03*
X519937D03*
X513917Y1447297D03*
X507917D03*
X519717D03*
X670412Y6000D03*
X665412D03*
X660412D03*
X655412D03*
X650412D03*
X645412D03*
X640412D03*
X635412D03*
X630412D03*
X625412D03*
X620412D03*
X615412D03*
X610412D03*
X605412D03*
X600412D03*
X595412D03*
X590412D03*
X585412D03*
X580412D03*
X669937Y1513685D03*
X659937D03*
X654937D03*
X649937D03*
X644937D03*
X639937D03*
X634937D03*
X629937D03*
X624937D03*
X619937D03*
X614937D03*
X609937D03*
X604937D03*
X599937D03*
X594937D03*
X589937D03*
X584937D03*
X579937D03*
X664937D03*
X765412Y6000D03*
X760412D03*
X755412D03*
X750412D03*
X745412D03*
X740412D03*
X735412D03*
X730412D03*
X725412D03*
X720412D03*
X715412D03*
X710412D03*
X705412D03*
X700412D03*
X695412D03*
X690412D03*
X685412D03*
X680412D03*
X675412D03*
X722000Y1503500D03*
X718500Y1500000D03*
X680500Y1503500D03*
X674937Y1513685D03*
X688012Y1499118D03*
X693012D03*
X698012D03*
X703012D03*
X708012D03*
X713012D03*
X724000Y1509500D03*
X725551Y1513685D03*
X730551D03*
X735551D03*
X740551D03*
X745551D03*
X750551D03*
X755551D03*
X760551D03*
X765551D03*
X678500Y1510500D03*
X777465Y93947D03*
Y88947D03*
Y83947D03*
Y78947D03*
Y73947D03*
Y68947D03*
Y63947D03*
Y58947D03*
Y53947D03*
Y48947D03*
Y43947D03*
Y38947D03*
Y33947D03*
Y28947D03*
Y23947D03*
Y18947D03*
Y13947D03*
X778000Y9500D03*
X775412Y6000D03*
X770412D03*
X777465Y183947D03*
Y178947D03*
Y173947D03*
Y168947D03*
Y163947D03*
Y158947D03*
Y153947D03*
Y148947D03*
Y143947D03*
Y138947D03*
Y133947D03*
Y128947D03*
Y123947D03*
Y118947D03*
Y113947D03*
Y108947D03*
Y103947D03*
Y98947D03*
X809500Y197500D03*
X805522Y195764D03*
X808961Y201678D03*
Y206678D03*
Y211678D03*
Y216678D03*
Y236678D03*
Y231678D03*
Y226678D03*
Y221678D03*
Y241678D03*
X779022Y190764D03*
X784022Y194764D03*
X800522Y195764D03*
X795522D03*
X790522D03*
X826843Y409096D03*
Y404296D03*
Y399496D03*
X822043D03*
Y404296D03*
Y409096D03*
X807643Y408996D03*
Y404196D03*
Y399396D03*
X802843D03*
Y404196D03*
Y408996D03*
X826843Y419764D03*
Y424564D03*
Y429364D03*
X802843Y419664D03*
X807643D03*
X822043Y419764D03*
X802843Y429264D03*
Y424464D03*
X807643D03*
Y429264D03*
X822043Y429364D03*
Y424564D03*
X822400Y567100D03*
Y562300D03*
Y557500D03*
X817600D03*
Y562300D03*
Y567100D03*
X803200Y557400D03*
Y562200D03*
Y567000D03*
X798400Y557400D03*
Y562200D03*
Y567000D03*
X822400Y587368D03*
Y582568D03*
X817600D03*
Y587368D03*
X803200Y587268D03*
Y582468D03*
X798400D03*
Y587268D03*
X822400Y577768D03*
X817600D03*
X803200Y577668D03*
X798400D03*
X808300Y1197300D03*
X813100D03*
Y1206900D03*
Y1202100D03*
X808300D03*
Y1206900D03*
X794100Y1197300D03*
X789300D03*
X794100Y1202100D03*
Y1206900D03*
X789300Y1202100D03*
Y1206900D03*
X808300Y1227168D03*
Y1222368D03*
X813100D03*
Y1227168D03*
X794100D03*
Y1222368D03*
X789300D03*
Y1227168D03*
X813100Y1217568D03*
X808300D03*
X789300D03*
X794100D03*
X779500Y1491000D03*
X775000Y1495500D03*
X770551Y1513685D03*
X773528Y1510662D03*
Y1505662D03*
Y1500662D03*
X786803Y1490063D03*
X791803D03*
X796803D03*
X801803D03*
X806803D03*
X811803D03*
X816803D03*
X821803D03*
X826803D03*
X831803D03*
X836803D03*
X841803D03*
X846803D03*
X851803D03*
X856803D03*
X861803D03*
X887127Y254031D03*
X944200Y1083100D03*
X938900Y1103700D03*
X938800Y1109300D03*
X945200Y1398300D03*
Y1393500D03*
X950200Y1394500D03*
X866803Y1490063D03*
X871803D03*
X876803D03*
X881803D03*
X886803D03*
X891803D03*
X896803D03*
X901803D03*
X906803D03*
X911803D03*
X916803D03*
X921803D03*
X926803D03*
X931803D03*
X936803D03*
X941803D03*
X946803D03*
X951803D03*
X956803D03*
X1012000Y371369D03*
X1015537Y365911D03*
X1038200Y762300D03*
X1021194Y766883D03*
X1035594Y766983D03*
X1040394D03*
X1021194Y771683D03*
Y776483D03*
X1035594Y776583D03*
Y771783D03*
X1040394D03*
Y776583D03*
X1016394Y766883D03*
Y776483D03*
Y771683D03*
X997000Y1496000D03*
X993000Y1491500D03*
X961803Y1490063D03*
X966803D03*
X971803D03*
X976803D03*
X981803D03*
X986803D03*
X998126Y1503614D03*
Y1508614D03*
Y1513614D03*
X1003126D03*
X1008126D03*
X1013126D03*
X1018126D03*
X1023126D03*
X1028126D03*
X1033126D03*
X1038126D03*
X1043126D03*
X1048126D03*
X1053126D03*
X1068734Y195764D03*
X1064500Y197500D03*
X1065055Y201895D03*
Y206895D03*
Y211895D03*
Y216895D03*
Y226895D03*
Y231895D03*
Y236895D03*
Y241895D03*
Y221895D03*
X1148734Y195764D03*
X1143734D03*
X1138734D03*
X1133734D03*
X1128734D03*
X1123734D03*
X1118734D03*
X1113734D03*
X1103734D03*
X1098734D03*
X1093734D03*
X1088734D03*
X1083734D03*
X1078734D03*
X1073734D03*
X1075627Y374973D03*
X1075829Y380885D03*
X1119877Y408072D03*
Y403272D03*
Y398472D03*
X1124677D03*
Y403272D03*
Y408072D03*
X1100677Y407972D03*
Y403172D03*
Y398372D03*
X1105477D03*
Y403172D03*
Y407972D03*
X1119877Y423540D03*
Y428340D03*
Y418740D03*
X1124677Y428340D03*
Y423540D03*
Y418740D03*
X1105477Y428240D03*
Y423440D03*
X1100677D03*
Y428240D03*
X1105477Y418640D03*
X1100677D03*
X1076142Y386839D03*
X1057400Y771600D03*
X1057600Y776500D03*
X1067200Y786500D03*
X1062400D03*
Y781500D03*
X1057600Y786500D03*
Y781500D03*
X1067200Y791500D03*
X1062400D03*
X1067200Y796500D03*
X1062400D03*
X1057600D03*
Y791500D03*
X1128700Y1206500D03*
X1133500D03*
Y1201700D03*
X1128700D03*
X1133500Y1196900D03*
X1128700D03*
X1109600Y1197100D03*
X1114400D03*
X1109600Y1201900D03*
X1114400D03*
Y1206700D03*
X1109600D03*
X1128500Y1225700D03*
X1133300D03*
X1109400Y1221100D03*
X1114200D03*
Y1225900D03*
X1109400D03*
X1133300Y1220900D03*
X1128500D03*
X1133300Y1216100D03*
X1128500D03*
X1109400Y1216300D03*
X1114200D03*
X1087933Y1411323D03*
X1082933D03*
X1077933D03*
X1095567Y1426057D03*
X1117200Y1346700D03*
X1058126Y1513614D03*
X1061675Y1510352D03*
X1065210Y1506817D03*
X1066638Y1472408D03*
Y1467408D03*
Y1462408D03*
Y1457408D03*
Y1452408D03*
Y1447408D03*
Y1442408D03*
X1095567Y1431057D03*
Y1436057D03*
Y1441057D03*
Y1446057D03*
Y1451057D03*
Y1456057D03*
Y1461057D03*
Y1466057D03*
X1096039Y1505861D03*
X1099575Y1509397D03*
X1103110Y1512932D03*
X1107798Y1513685D03*
X1112798D03*
X1117798D03*
X1122798D03*
X1127798D03*
X1132798D03*
X1137798D03*
X1142798D03*
X1147798D03*
X1095567Y1471057D03*
X1066638Y1502408D03*
X1115000Y1485000D03*
X1118000Y1480500D03*
X1112000D03*
X1234500Y6000D03*
X1243844D03*
X1238844D03*
X1230409Y7565D03*
Y12565D03*
Y17565D03*
Y22565D03*
Y27565D03*
Y32565D03*
Y37565D03*
Y42565D03*
Y47565D03*
Y52565D03*
Y57565D03*
Y62565D03*
Y67565D03*
Y72565D03*
Y77565D03*
Y82565D03*
Y87565D03*
Y92565D03*
X1229000Y189500D03*
X1230409Y97565D03*
Y102565D03*
Y107565D03*
Y112565D03*
Y117565D03*
Y122565D03*
Y127565D03*
Y132565D03*
Y137565D03*
Y142565D03*
Y147565D03*
Y152565D03*
Y157565D03*
Y162565D03*
Y167565D03*
Y172565D03*
Y177565D03*
Y182565D03*
X1225000Y194000D03*
X1218734Y195764D03*
X1213734D03*
X1208734D03*
X1203734D03*
X1198734D03*
X1193734D03*
X1188734D03*
X1183734D03*
X1178734D03*
X1173734D03*
X1168734D03*
X1163734D03*
X1158734D03*
X1153734D03*
X1151100Y1179300D03*
X1155900D03*
X1151100Y1184100D03*
X1155900D03*
Y1188900D03*
X1151100D03*
X1245500Y1500500D03*
X1208000Y1502500D03*
X1234783Y1499118D03*
X1229783D03*
X1224783D03*
X1219783D03*
X1214783D03*
X1239783D03*
X1152798Y1513685D03*
X1157798D03*
X1162798D03*
X1167798D03*
X1172798D03*
X1177798D03*
X1182798D03*
X1187798D03*
X1192798D03*
X1197798D03*
X1202798D03*
X1205500Y1509000D03*
X1338844Y6000D03*
X1333844D03*
X1328844D03*
X1323844D03*
X1318844D03*
X1313844D03*
X1308844D03*
X1303844D03*
X1298844D03*
X1293844D03*
X1288844D03*
X1283844D03*
X1278844D03*
X1273844D03*
X1268844D03*
X1263844D03*
X1258844D03*
X1253844D03*
X1248844D03*
X1249000Y1504500D03*
X1328464Y1513685D03*
X1333464D03*
X1338464D03*
X1293464D03*
X1298464D03*
X1303464D03*
X1308464D03*
X1313464D03*
X1318464D03*
X1323464D03*
X1250500Y1510500D03*
X1253464Y1513685D03*
X1258464D03*
X1263464D03*
X1268464D03*
X1273464D03*
X1278464D03*
X1283464D03*
X1288464D03*
X1433844Y6000D03*
X1428844D03*
X1423844D03*
X1418844D03*
X1413844D03*
X1408844D03*
X1403844D03*
X1398844D03*
X1393844D03*
X1388844D03*
X1383844D03*
X1378844D03*
X1373844D03*
X1368844D03*
X1363844D03*
X1358844D03*
X1353844D03*
X1348844D03*
X1343844D03*
X1385474Y1429500D03*
X1380074D03*
X1383374Y1425000D03*
X1383674Y1419000D03*
X1433500Y1490500D03*
X1428500Y1494000D03*
X1403500Y1513500D03*
X1398500D03*
X1363464Y1513685D03*
X1368464D03*
X1373464D03*
X1378464D03*
X1383464D03*
X1388464D03*
X1393464D03*
X1353464D03*
X1358464D03*
X1343464D03*
X1348464D03*
X1408464D03*
X1413464D03*
X1418464D03*
X1423464D03*
X1425890Y1510111D03*
Y1505111D03*
Y1500111D03*
X1528844Y6000D03*
X1523844D03*
X1518844D03*
X1513844D03*
X1508844D03*
X1503844D03*
X1498844D03*
X1493844D03*
X1488844D03*
X1483844D03*
X1478844D03*
X1473844D03*
X1468844D03*
X1463844D03*
X1458844D03*
X1453844D03*
X1448844D03*
X1443844D03*
X1438844D03*
X1439716Y1490063D03*
X1444716D03*
X1449716D03*
X1454716D03*
X1459716D03*
X1464716D03*
X1469716D03*
X1474716D03*
X1479716D03*
X1484716D03*
X1489716D03*
X1494716D03*
X1499716D03*
X1504716D03*
X1509716D03*
X1514716D03*
X1519716D03*
X1524716D03*
X1529716D03*
X1623844Y6000D03*
X1618844D03*
X1613844D03*
X1608844D03*
X1603844D03*
X1598844D03*
X1593844D03*
X1588844D03*
X1583844D03*
X1578844D03*
X1573844D03*
X1568844D03*
X1563844D03*
X1558844D03*
X1553844D03*
X1548844D03*
X1543844D03*
X1538844D03*
X1533844D03*
X1534716Y1490063D03*
X1539716D03*
X1544716D03*
X1549716D03*
X1554716D03*
X1559716D03*
X1564716D03*
X1569716D03*
X1574716D03*
X1579716D03*
X1584716D03*
X1589716D03*
X1594716D03*
X1599716D03*
X1604716D03*
X1609716D03*
X1614716D03*
X1619716D03*
X1624716D03*
X1718844Y6000D03*
X1713844D03*
X1708844D03*
X1703844D03*
X1698844D03*
X1693844D03*
X1688844D03*
X1683844D03*
X1678844D03*
X1673844D03*
X1668844D03*
X1663844D03*
X1658844D03*
X1653844D03*
X1648844D03*
X1643844D03*
X1638844D03*
X1633844D03*
X1628844D03*
X1667359Y434407D03*
Y439207D03*
Y429607D03*
X1662559D03*
Y434407D03*
Y439207D03*
X1649500Y1497500D03*
X1646000Y1492000D03*
X1720968Y1513685D03*
X1715968D03*
X1710968D03*
X1705968D03*
X1700968D03*
X1695968D03*
X1690968D03*
X1685968D03*
X1680968D03*
X1670968D03*
X1675968D03*
X1629716Y1490063D03*
X1634716D03*
X1639716D03*
X1650488Y1504165D03*
Y1509165D03*
X1650968Y1513685D03*
X1655968D03*
X1660968D03*
X1665968D03*
X1813844Y6000D03*
X1808844D03*
X1803844D03*
X1798844D03*
X1793844D03*
X1788844D03*
X1783844D03*
X1778844D03*
X1773844D03*
X1768844D03*
X1763844D03*
X1758844D03*
X1753844D03*
X1748844D03*
X1743844D03*
X1738844D03*
X1733844D03*
X1728844D03*
X1723844D03*
X1814463Y449725D03*
Y454725D03*
X1804900Y451800D03*
X1809915Y461785D03*
Y446985D03*
Y456985D03*
Y442185D03*
X1799600Y451800D03*
X1794915Y461785D03*
Y446985D03*
Y456985D03*
Y442185D03*
X1751774Y430510D03*
X1753959Y450607D03*
X1741159Y873707D03*
X1736359D03*
X1741159Y864107D03*
X1736359D03*
X1741159Y868907D03*
X1736359D03*
X1766526Y1429400D03*
X1760326Y1429500D03*
X1763926Y1419000D03*
X1763626Y1425000D03*
X1786004Y1513500D03*
X1780968Y1513685D03*
X1775968D03*
X1770968D03*
X1765968D03*
X1760968D03*
X1755968D03*
X1750968D03*
X1745968D03*
X1740968D03*
X1796004Y1513500D03*
X1801004D03*
X1806004D03*
X1811004D03*
X1816004D03*
X1730968Y1513685D03*
X1725968D03*
X1791004Y1513500D03*
X1735968Y1513685D03*
X1913844Y6000D03*
X1908844D03*
X1903844D03*
X1898844D03*
X1893844D03*
X1888844D03*
X1883844D03*
X1878844D03*
X1873844D03*
X1868844D03*
X1863844D03*
X1858844D03*
X1853844D03*
X1848844D03*
X1843844D03*
X1838844D03*
X1833844D03*
X1828844D03*
X1823844D03*
X1818844D03*
X1838463Y454725D03*
Y449725D03*
X1819263D03*
Y454725D03*
X1833663D03*
Y449725D03*
X1828863D03*
Y454725D03*
X1824063D03*
Y449725D03*
X1912663Y888925D03*
Y883925D03*
X1869115Y876385D03*
Y891185D03*
Y881185D03*
Y895985D03*
X1873800Y886300D03*
X1884115Y876385D03*
X1898263Y883925D03*
Y888925D03*
X1903063D03*
Y883925D03*
X1907863D03*
Y888925D03*
X1884115Y891185D03*
Y881185D03*
Y895985D03*
X1893463Y888925D03*
Y883925D03*
X1879100Y886300D03*
X1888663Y888925D03*
Y883925D03*
X1828363Y884925D03*
X1869500Y1503500D03*
X1865500Y1500000D03*
X1829500Y1501500D03*
X1826500Y1506500D03*
X1855256Y1499118D03*
X1850256D03*
X1845256D03*
X1840256D03*
X1826040Y1513315D03*
X1821040D03*
X1835256Y1499118D03*
X1860256D03*
X1871157Y1509110D03*
X1871582Y1513685D03*
X1876582D03*
X1881582D03*
X1886582D03*
X1891582D03*
X1896582D03*
X1901582D03*
X1906582D03*
X1911582D03*
X1928843Y8985D03*
Y93985D03*
Y88985D03*
Y83985D03*
Y78985D03*
Y73985D03*
Y68985D03*
Y63985D03*
Y58985D03*
Y53985D03*
Y48985D03*
Y43985D03*
Y38985D03*
Y28985D03*
Y23985D03*
Y18985D03*
Y13985D03*
Y33985D03*
X1923844Y6000D03*
X1918844D03*
X1928843Y98985D03*
Y188985D03*
Y183985D03*
Y178985D03*
Y173985D03*
Y168985D03*
Y163985D03*
Y158985D03*
Y153985D03*
Y148985D03*
Y143985D03*
Y138985D03*
Y133985D03*
Y128985D03*
Y123985D03*
Y118985D03*
Y113985D03*
Y108985D03*
Y103985D03*
Y283985D03*
Y278985D03*
Y273985D03*
Y268985D03*
Y263985D03*
Y258985D03*
Y253985D03*
Y248985D03*
Y243985D03*
Y238985D03*
Y233985D03*
Y228985D03*
Y223985D03*
Y218985D03*
Y213985D03*
Y208985D03*
Y203985D03*
Y198985D03*
Y193985D03*
Y378985D03*
Y373985D03*
Y368985D03*
Y363985D03*
Y358985D03*
Y353985D03*
Y348985D03*
Y343985D03*
Y338985D03*
Y333985D03*
Y328985D03*
Y323985D03*
Y318985D03*
Y313985D03*
Y308985D03*
Y303985D03*
Y298985D03*
Y293985D03*
Y288985D03*
Y418985D03*
Y433985D03*
Y428985D03*
Y423985D03*
Y473985D03*
Y468985D03*
Y463985D03*
Y458985D03*
Y453985D03*
Y448985D03*
Y443985D03*
Y438985D03*
Y413985D03*
Y408985D03*
Y403985D03*
Y398985D03*
Y393985D03*
Y388985D03*
Y383985D03*
Y568985D03*
Y563985D03*
Y558985D03*
Y553985D03*
Y548985D03*
Y543985D03*
Y538985D03*
Y533985D03*
Y528985D03*
Y523985D03*
Y518985D03*
Y513985D03*
Y508985D03*
Y503985D03*
Y498985D03*
Y493985D03*
Y488985D03*
Y483985D03*
Y478985D03*
Y663985D03*
Y658985D03*
Y653985D03*
Y648985D03*
Y643985D03*
Y638985D03*
Y633985D03*
Y628985D03*
Y623985D03*
Y618985D03*
Y613985D03*
Y608985D03*
Y603985D03*
Y598985D03*
Y593985D03*
Y588985D03*
Y583985D03*
Y578985D03*
Y573985D03*
Y758985D03*
Y753985D03*
Y748985D03*
Y743985D03*
Y738985D03*
Y733985D03*
Y728985D03*
Y723985D03*
Y718985D03*
Y713985D03*
Y708985D03*
Y703985D03*
Y698985D03*
Y693985D03*
Y688985D03*
Y683985D03*
Y678985D03*
Y673985D03*
Y668985D03*
Y853985D03*
Y848985D03*
Y843985D03*
Y838985D03*
Y833985D03*
Y828985D03*
Y823985D03*
Y818985D03*
Y813985D03*
Y808985D03*
Y803985D03*
Y798985D03*
Y793985D03*
Y788985D03*
Y783985D03*
Y778985D03*
Y773985D03*
Y768985D03*
Y763985D03*
Y918985D03*
Y913985D03*
Y908985D03*
Y903985D03*
Y898985D03*
Y893985D03*
Y888985D03*
Y883985D03*
Y878985D03*
Y873985D03*
Y868985D03*
Y863985D03*
Y858985D03*
Y948985D03*
Y943985D03*
Y938985D03*
Y933985D03*
Y928985D03*
Y923985D03*
Y1043985D03*
Y1038985D03*
Y1033985D03*
Y1028985D03*
Y1023985D03*
Y1018985D03*
Y1013985D03*
Y1008985D03*
Y1003985D03*
Y998985D03*
Y993985D03*
Y988985D03*
Y983985D03*
Y978985D03*
Y973985D03*
Y968985D03*
Y963985D03*
Y958985D03*
Y953985D03*
Y1143985D03*
Y1138985D03*
Y1133985D03*
Y1128985D03*
Y1123985D03*
Y1118985D03*
Y1113985D03*
Y1108985D03*
Y1103985D03*
Y1098985D03*
Y1093985D03*
Y1088985D03*
Y1083985D03*
Y1078985D03*
Y1073985D03*
Y1068985D03*
Y1063985D03*
Y1058985D03*
Y1053985D03*
Y1048985D03*
Y1238985D03*
Y1233985D03*
Y1228985D03*
Y1223985D03*
Y1218985D03*
Y1213985D03*
Y1208985D03*
Y1203985D03*
Y1198985D03*
Y1193985D03*
Y1188985D03*
Y1183985D03*
Y1178985D03*
Y1173985D03*
Y1168985D03*
Y1163985D03*
Y1158985D03*
Y1153985D03*
Y1148985D03*
Y1288985D03*
Y1293985D03*
Y1298985D03*
Y1303985D03*
Y1308985D03*
Y1313985D03*
Y1318985D03*
Y1323985D03*
Y1328985D03*
Y1333985D03*
Y1283985D03*
Y1278985D03*
Y1273985D03*
Y1268985D03*
Y1263985D03*
Y1258985D03*
Y1253985D03*
Y1248985D03*
Y1243985D03*
Y1348985D03*
Y1353985D03*
Y1358985D03*
Y1363985D03*
Y1368985D03*
Y1373985D03*
Y1378985D03*
Y1383985D03*
Y1388985D03*
Y1393985D03*
Y1398985D03*
Y1403985D03*
Y1408985D03*
Y1413985D03*
Y1418985D03*
Y1423985D03*
Y1428985D03*
Y1338985D03*
Y1343985D03*
Y1448985D03*
Y1443985D03*
Y1433985D03*
Y1438985D03*
X1920000Y1458000D03*
X1917500Y1463500D03*
X1916582Y1513685D03*
X1917031Y1509134D03*
Y1504134D03*
Y1499134D03*
Y1494134D03*
Y1489134D03*
Y1484134D03*
Y1479134D03*
Y1474134D03*
Y1469134D03*
X1926500Y1455000D03*
X2261450Y1043500D03*
G54D31*
G01X466941Y-145664D02*
Y-225664D01*
G01D02*
X1593241D01*
G01X462941Y-129664D02*
G02I-12000J0D01*
G01X457791D02*
G02I-6850J0D01*
G01X450941Y-145664D02*
Y-113664D01*
G01X466941Y-129664D02*
X434941D01*
G01X466941Y-145664D02*
X1593241D01*
G01X466941Y-181164D02*
X1593241D01*
G01X805741Y-145664D02*
Y-225664D01*
G01X943241Y-145664D02*
Y-225664D01*
G01X1058241Y-145664D02*
Y-225664D01*
G01X1225741Y-145664D02*
Y-225664D01*
G01X1395741Y-145664D02*
Y-225664D01*
G01X1593241Y-145664D02*
Y-225664D01*
G01X1621241Y-129664D02*
G02I-12000J0D01*
G01X1616091D02*
G02I-6850J0D01*
G01X1609241Y-145664D02*
Y-113664D01*
G01X1625241Y-129664D02*
X1593241D01*
G54D13*
X90709Y1485118D03*
X80709D03*
X70709D03*
X711181D03*
X701181D03*
X691181D03*
X1237953D03*
X1227953D03*
X1217953D03*
X1858425D03*
X1848425D03*
X1838425D03*
X2261450Y861700D03*
G54D22*
X246535Y1320472D03*
X531535D03*
X2261450Y255700D03*
G54D32*
G01X126200Y274803D02*
X79869D01*
G01X126200Y251181D02*
X79869D01*
G01X84869Y257513D02*
Y251181D01*
G01X83369Y256181D02*
X84869Y251181D01*
X86369Y256181D01*
X83369D01*
G01X84869Y268113D02*
Y274803D01*
G01X86369Y269803D02*
X84869Y274803D01*
X83369Y269803D01*
X86369D01*
G01X126200Y229527D02*
X62730D01*
G01X67730Y249700D02*
Y229527D01*
G01X66230Y234527D02*
X67730Y229527D01*
X69230Y234527D01*
X66230D01*
G01X67730Y260300D02*
Y285236D01*
G01X69230Y280236D02*
X67730Y285236D01*
X66230Y280236D01*
X69230D01*
G01X126200Y285236D02*
X62730D01*
G01X69230Y732992D02*
X67730Y737992D01*
X66230Y732992D01*
X69230D01*
G01X67730Y713056D02*
Y737992D01*
G01X66230Y687283D02*
X67730Y682283D01*
X69230Y687283D01*
X66230D01*
G01X67730Y702456D02*
Y682283D01*
G01X126200D02*
X62730D01*
G01X126200Y737992D02*
X62730D01*
G01X86369Y722559D02*
X84869Y727559D01*
X83369Y722559D01*
X86369D01*
G01X84869Y720869D02*
Y727559D01*
G01X83369Y708937D02*
X84869Y703937D01*
X86369Y708937D01*
X83369D01*
G01X84869Y710269D02*
Y703937D01*
G01X126200D02*
X79869D01*
G01X126200Y727559D02*
X79869D01*
G01X126200Y1135038D02*
X62730D01*
G01X67730Y1155211D02*
Y1135038D01*
G01X66230Y1140038D02*
X67730Y1135038D01*
X69230Y1140038D01*
X66230D01*
G01X126200Y1180314D02*
X79869D01*
G01X126200Y1156692D02*
X79869D01*
G01X84869Y1163024D02*
Y1156692D01*
G01X83369Y1161692D02*
X84869Y1156692D01*
X86369Y1161692D01*
X83369D01*
G01X84869Y1173624D02*
Y1180314D01*
G01X86369Y1175314D02*
X84869Y1180314D01*
X83369Y1175314D01*
X86369D01*
G01X126200Y1190747D02*
X62730D01*
G01X67730Y1165811D02*
Y1190747D01*
G01X69230Y1185747D02*
X67730Y1190747D01*
X66230Y1185747D01*
X69230D01*
G01X141181Y277843D02*
G03X121220I-9980J-3040D01*
G02X114295Y264712I-37662J11471D01*
G03X148106I16905J-13531D01*
G02X141181Y277843I30737J24602D01*
G01X155513Y259383D02*
X152492Y255126D01*
X157357Y257017D01*
X155513Y259383D01*
G01X152492Y255126D02*
X164864Y264772D01*
G01X142288Y285643D02*
X139331Y281341D01*
X144167Y283305D01*
X142288Y285643D01*
G01X139331Y281341D02*
X167176Y303731D01*
G01X169397Y222552D02*
G03I-2000J0D01*
G01Y225552D02*
X165397Y219552D01*
G01X152408Y234967D02*
X147636Y237083D01*
X150455Y232689D01*
X152408Y234967D01*
G01X147636Y237083D02*
X165017Y222176D01*
G01X171556Y303543D02*
G03I-2000J0D01*
G01Y306543D02*
X167556Y300543D01*
G01X147636Y689839D02*
X165017Y674932D01*
G01X152408Y687723D02*
X147636Y689839D01*
X150455Y685445D01*
X152408Y687723D01*
G01X169397Y678308D02*
X165397Y672308D01*
G01X169397Y675308D02*
G03I-2000J0D01*
G01X139331Y734097D02*
X167176Y756487D01*
G01X142288Y738399D02*
X139331Y734097D01*
X144167Y736061D01*
X142288Y738399D01*
G01X171556Y759299D02*
X167556Y753299D01*
G01X171556Y756299D02*
G03I-2000J0D01*
G01X152492Y707882D02*
X164864Y717528D01*
G01X155513Y712139D02*
X152492Y707882D01*
X157357Y709773D01*
X155513Y712139D01*
G01X141181Y730599D02*
G03X121220I-9980J-3040D01*
G02X114295Y717468I-37662J11471D01*
G03X148106I16905J-13531D01*
G02X141181Y730599I30737J24602D01*
G01Y1183354D02*
G03X121220I-9980J-3040D01*
G02X114295Y1170223I-37662J11471D01*
G03X148106I16905J-13531D01*
G02X141181Y1183354I30737J24602D01*
G01X169397Y1128063D02*
G03I-2000J0D01*
G01Y1131063D02*
X165397Y1125063D01*
G01X152408Y1140478D02*
X147636Y1142594D01*
X150455Y1138200D01*
X152408Y1140478D01*
G01X147636Y1142594D02*
X165017Y1127687D01*
G01X155513Y1164894D02*
X152492Y1160637D01*
X157357Y1162528D01*
X155513Y1164894D01*
G01X152492Y1160637D02*
X164864Y1170283D01*
G01X171556Y1209054D02*
G03I-2000J0D01*
G01Y1212054D02*
X167556Y1206054D01*
G01X142288Y1191154D02*
X139331Y1186852D01*
X144167Y1188816D01*
X142288Y1191154D01*
G01X139331Y1186852D02*
X167176Y1209242D01*
G01X317262Y280236D02*
X315762Y285236D01*
X314262Y280236D01*
X317262D01*
G01X315762Y260300D02*
Y285236D01*
G01X314262Y234527D02*
X315762Y229527D01*
X317262Y234527D01*
X314262D01*
G01X315762Y249700D02*
Y229527D01*
G01X374232D02*
X310762D01*
G01X334401Y269803D02*
X332901Y274803D01*
X331401Y269803D01*
X334401D01*
G01X332901Y268113D02*
Y274803D01*
G01X331401Y256181D02*
X332901Y251181D01*
X334401Y256181D01*
X331401D01*
G01X332901Y257513D02*
Y251181D01*
G01X374232D02*
X327901D01*
G01X374232Y274803D02*
X327901D01*
G01X389213Y277843D02*
G03X369252I-9981J-3040D01*
G02X362327Y264712I-37662J11471D01*
G03X396138I16905J-13531D01*
G02X389213Y277843I30737J24602D01*
G01X374232Y285236D02*
X310762D01*
G01X317262Y732992D02*
X315762Y737992D01*
X314262Y732992D01*
X317262D01*
G01X315762Y713056D02*
Y737992D01*
G01X314262Y687283D02*
X315762Y682283D01*
X317262Y687283D01*
X314262D01*
G01X315762Y702456D02*
Y682283D01*
G01X374232D02*
X310762D01*
G01X374232Y737992D02*
X310762D01*
G01X334401Y722559D02*
X332901Y727559D01*
X331401Y722559D01*
X334401D01*
G01X332901Y720869D02*
Y727559D01*
G01X331401Y708937D02*
X332901Y703937D01*
X334401Y708937D01*
X331401D01*
G01X332901Y710269D02*
Y703937D01*
G01X374232D02*
X327901D01*
G01X374232Y727559D02*
X327901D01*
G01X389213Y730599D02*
G03X369252I-9981J-3040D01*
G02X362327Y717468I-37662J11471D01*
G03X396138I16905J-13531D01*
G02X389213Y730599I30737J24602D01*
G01X314262Y1140038D02*
X315762Y1135038D01*
X317262Y1140038D01*
X314262D01*
G01X315762Y1155211D02*
Y1135038D01*
G01X374232D02*
X310762D01*
G01X389213Y1183354D02*
G03X369252I-9981J-3040D01*
G02X362327Y1170223I-37662J11471D01*
G03X396138I16905J-13531D01*
G02X389213Y1183354I30737J24602D01*
G01X317262Y1185747D02*
X315762Y1190747D01*
X314262Y1185747D01*
X317262D01*
G01X315762Y1165811D02*
Y1190747D01*
G01X374232D02*
X310762D01*
G01X334401Y1175314D02*
X332901Y1180314D01*
X331401Y1175314D01*
X334401D01*
G01X332901Y1173624D02*
Y1180314D01*
G01X331401Y1161692D02*
X332901Y1156692D01*
X334401Y1161692D01*
X331401D01*
G01X332901Y1163024D02*
Y1156692D01*
G01X374232D02*
X327901D01*
G01X374232Y1180314D02*
X327901D01*
G01X489037Y-206331D02*
X489911Y-205456D01*
X490566Y-203998D01*
X491003Y-201955D01*
X490566Y-200206D01*
X489693Y-199039D01*
X488164Y-198164D01*
X482269D01*
Y-215664D01*
X489474D01*
X491003Y-214498D01*
X491876Y-212747D01*
X492313Y-210706D01*
X491876Y-208664D01*
X490566Y-206914D01*
X489037Y-206331D01*
X482269D01*
G01X501734Y-215664D02*
Y-203998D01*
G01Y-206331D02*
X502826Y-205164D01*
X503918Y-204289D01*
X505446Y-203998D01*
X506537Y-204289D01*
X507848Y-205164D01*
G01X517706Y-220914D02*
X519016Y-221497D01*
X520763Y-220914D01*
X521854Y-219748D01*
X522728Y-218289D01*
X524037Y-213623D01*
X526876Y-203998D01*
G01X519889D02*
X524037Y-213623D01*
G01X543284Y-205456D02*
X541756Y-204289D01*
X540446Y-203998D01*
X538699Y-204581D01*
X537389Y-205747D01*
X536516Y-207789D01*
X536297Y-209831D01*
X536516Y-211873D01*
X537389Y-213623D01*
X538699Y-215081D01*
X540446Y-215664D01*
X541974Y-215081D01*
X543284Y-213914D01*
G01X554016Y-207789D02*
X561003D01*
X560348Y-205747D01*
X559256Y-204581D01*
X557728Y-203998D01*
X556199Y-204289D01*
X554889Y-205164D01*
X554016Y-207206D01*
X553579Y-208956D01*
Y-210706D01*
X554016Y-212456D01*
X555108Y-214206D01*
X556418Y-215372D01*
X557946Y-215664D01*
X559474Y-215081D01*
X561003Y-213331D01*
G01X597094Y-199623D02*
X595784Y-198747D01*
X594256Y-198164D01*
X592509D01*
X590544Y-199039D01*
X589016Y-200497D01*
X587924Y-202248D01*
X587051Y-205164D01*
X586832Y-207789D01*
X587269Y-210414D01*
X587924Y-212164D01*
X589234Y-213914D01*
X590763Y-215081D01*
X592291Y-215664D01*
X593819D01*
X595348Y-215081D01*
X596658Y-214206D01*
X597750Y-213040D01*
G01X613721Y-215664D02*
Y-203998D01*
G01Y-206039D02*
X612848Y-204873D01*
X611537Y-204289D01*
X610009Y-203998D01*
X608481Y-204581D01*
X607171Y-205747D01*
X606297Y-207497D01*
X605861Y-209831D01*
X606297Y-212164D01*
X607171Y-213914D01*
X608481Y-215081D01*
X610009Y-215664D01*
X611537Y-215372D01*
X612848Y-214498D01*
X613721Y-213331D01*
G01X623579Y-215664D02*
Y-203998D01*
G01Y-206914D02*
X624453Y-205456D01*
X625763Y-204289D01*
X627509Y-203998D01*
X629037Y-204289D01*
X630348Y-205456D01*
X631003Y-207497D01*
Y-215664D01*
G01X640206Y-220914D02*
X641516Y-221497D01*
X643263Y-220914D01*
X644354Y-219748D01*
X645228Y-218289D01*
X646537Y-213623D01*
X649376Y-203998D01*
G01X642389D02*
X646537Y-213623D01*
G01X662291Y-215664D02*
X660981Y-215372D01*
X659671Y-214206D01*
X658797Y-212164D01*
X658361Y-209831D01*
X658797Y-207497D01*
X659671Y-205456D01*
X660981Y-204289D01*
X662291Y-203998D01*
X663601Y-204289D01*
X664911Y-205456D01*
X665784Y-207497D01*
X666003Y-209831D01*
X665784Y-212164D01*
X664911Y-214206D01*
X663601Y-215372D01*
X662291Y-215664D01*
G01X676079D02*
Y-203998D01*
G01Y-206914D02*
X676953Y-205456D01*
X678263Y-204289D01*
X680009Y-203998D01*
X681537Y-204289D01*
X682848Y-205456D01*
X683503Y-207497D01*
Y-215664D01*
G01X710424D02*
Y-198164D01*
X715883D01*
X717629Y-199039D01*
X718721Y-200206D01*
X719158Y-202539D01*
X718721Y-204873D01*
X717411Y-206331D01*
X715883Y-207206D01*
X710424D01*
G01X715883D02*
X719158Y-215664D01*
G01X732291Y-216247D02*
X731854Y-215956D01*
Y-215372D01*
X732291Y-215081D01*
X732728Y-215372D01*
Y-215956D01*
X732291Y-216247D01*
G01X744988Y-215664D02*
Y-198164D01*
X749354D01*
X751101Y-199039D01*
X752411Y-200206D01*
X753503Y-201955D01*
X754376Y-203998D01*
X754594Y-206914D01*
X754376Y-209831D01*
X753503Y-211873D01*
X752411Y-213623D01*
X751101Y-214789D01*
X749354Y-215664D01*
X744988D01*
G01X762924D02*
Y-198164D01*
X768164D01*
X769911Y-199039D01*
X771221Y-201081D01*
X771658Y-203414D01*
X771221Y-205747D01*
X770129Y-207497D01*
X768164Y-208373D01*
X762924D01*
G01X786537Y-206331D02*
X787411Y-205456D01*
X788066Y-203998D01*
X788503Y-201955D01*
X788066Y-200206D01*
X787193Y-199039D01*
X785664Y-198164D01*
X779769D01*
Y-215664D01*
X786974D01*
X788503Y-214498D01*
X789376Y-212747D01*
X789813Y-210706D01*
X789376Y-208664D01*
X788066Y-206914D01*
X786537Y-206331D01*
X779769D01*
G01X395668Y237083D02*
X413049Y222176D01*
G01X400440Y234967D02*
X395668Y237083D01*
X398487Y232689D01*
X400440Y234967D01*
G01X417429Y225552D02*
X413429Y219552D01*
G01X417429Y222552D02*
G03I-2000J0D01*
G01X387363Y281341D02*
X415208Y303731D01*
G01X390320Y285643D02*
X387363Y281341D01*
X392199Y283305D01*
X390320Y285643D01*
G01X400524Y255126D02*
X412896Y264772D01*
G01X403545Y259383D02*
X400524Y255126D01*
X405389Y257017D01*
X403545Y259383D01*
G01X419588Y306543D02*
X415588Y300543D01*
G01X419588Y303543D02*
G03I-2000J0D01*
G01X395668Y689839D02*
X413049Y674932D01*
G01X400440Y687723D02*
X395668Y689839D01*
X398487Y685445D01*
X400440Y687723D01*
G01X417429Y678308D02*
X413429Y672308D01*
G01X417429Y675308D02*
G03I-2000J0D01*
G01X387363Y734097D02*
X415208Y756487D01*
G01X390320Y738399D02*
X387363Y734097D01*
X392199Y736061D01*
X390320Y738399D01*
G01X419588Y759299D02*
X415588Y753299D01*
G01X419588Y756299D02*
G03I-2000J0D01*
G01X400524Y707882D02*
X412896Y717528D01*
G01X403545Y712139D02*
X400524Y707882D01*
X405389Y709773D01*
X403545Y712139D01*
G01X395668Y1142594D02*
X413049Y1127687D01*
G01X400440Y1140478D02*
X395668Y1142594D01*
X398487Y1138200D01*
X400440Y1140478D01*
G01X417429Y1131063D02*
X413429Y1125063D01*
G01X417429Y1128063D02*
G03I-2000J0D01*
G01X387363Y1186852D02*
X415208Y1209242D01*
G01X390320Y1191154D02*
X387363Y1186852D01*
X392199Y1188816D01*
X390320Y1191154D01*
G01X419588Y1212054D02*
X415588Y1206054D01*
G01X419588Y1209054D02*
G03I-2000J0D01*
G01X400524Y1160637D02*
X412896Y1170283D01*
G01X403545Y1164894D02*
X400524Y1160637D01*
X405389Y1162528D01*
X403545Y1164894D01*
G01X565293Y280236D02*
X563793Y285236D01*
X562293Y280236D01*
X565293D01*
G01X563793Y260300D02*
Y285236D01*
G01X562293Y234527D02*
X563793Y229527D01*
X565293Y234527D01*
X562293D01*
G01X563793Y249700D02*
Y229527D01*
G01X622263D02*
X558793D01*
G01X622263Y251181D02*
X575932D01*
G01X622263Y274803D02*
X575932D01*
G01X622263Y285236D02*
X558793D01*
G01X565293Y732992D02*
X563793Y737992D01*
X562293Y732992D01*
X565293D01*
G01X563793Y713056D02*
Y737992D01*
G01X562293Y687283D02*
X563793Y682283D01*
X565293Y687283D01*
X562293D01*
G01X563793Y702456D02*
Y682283D01*
G01X622263D02*
X558793D01*
G01X622263Y737992D02*
X558793D01*
G01X622263Y703937D02*
X575932D01*
G01X622263Y727559D02*
X575932D01*
G01X562293Y1140038D02*
X563793Y1135038D01*
X565293Y1140038D01*
X562293D01*
G01X563793Y1155211D02*
Y1135038D01*
G01X622263D02*
X558793D01*
G01X565293Y1185747D02*
X563793Y1190747D01*
X562293Y1185747D01*
X565293D01*
G01X563793Y1165811D02*
Y1190747D01*
G01X622263D02*
X558793D01*
G01X622263Y1156692D02*
X575932D01*
G01X622263Y1180314D02*
X575932D01*
G01X595364Y-170664D02*
Y-153164D01*
X601041Y-167747D01*
X606718Y-153164D01*
Y-170664D01*
G01X618541D02*
X617231Y-170372D01*
X615921Y-169206D01*
X615047Y-167164D01*
X614611Y-164831D01*
X615047Y-162497D01*
X615921Y-160456D01*
X617231Y-159289D01*
X618541Y-158998D01*
X619851Y-159289D01*
X621161Y-160456D01*
X622034Y-162497D01*
X622253Y-164831D01*
X622034Y-167164D01*
X621161Y-169206D01*
X619851Y-170372D01*
X618541Y-170664D01*
G01X639971Y-153164D02*
Y-170664D01*
G01Y-168040D02*
X639098Y-169498D01*
X637787Y-170372D01*
X636259Y-170664D01*
X634513Y-170081D01*
X633203Y-168623D01*
X632329Y-166873D01*
X632111Y-164831D01*
X632329Y-162789D01*
X633203Y-161039D01*
X634513Y-159581D01*
X636259Y-158998D01*
X637787Y-159289D01*
X638879Y-159873D01*
X639971Y-161039D01*
G01X650266Y-162789D02*
X657253D01*
X656598Y-160747D01*
X655506Y-159581D01*
X653978Y-158998D01*
X652449Y-159289D01*
X651139Y-160164D01*
X650266Y-162206D01*
X649829Y-163956D01*
Y-165706D01*
X650266Y-167456D01*
X651358Y-169206D01*
X652668Y-170372D01*
X654196Y-170664D01*
X655724Y-170081D01*
X657253Y-168331D01*
G01X671041Y-170664D02*
Y-153164D01*
G01X582432Y269803D02*
X580932Y274803D01*
X579432Y269803D01*
X582432D01*
G01X580932Y268113D02*
Y274803D01*
G01X579432Y256181D02*
X580932Y251181D01*
X582432Y256181D01*
X579432D01*
G01X580932Y257513D02*
Y251181D01*
G01X643699Y237083D02*
X661080Y222176D01*
G01X648471Y234967D02*
X643699Y237083D01*
X646518Y232689D01*
X648471Y234967D01*
G01X665460Y225552D02*
X661460Y219552D01*
G01X665460Y222552D02*
G03I-2000J0D01*
G01X635394Y281341D02*
X663239Y303731D01*
G01X638351Y285643D02*
X635394Y281341D01*
X640230Y283305D01*
X638351Y285643D01*
G01X648555Y255126D02*
X660927Y264772D01*
G01X651576Y259383D02*
X648555Y255126D01*
X653420Y257017D01*
X651576Y259383D01*
G01X637244Y277843D02*
G03X617283I-9980J-3040D01*
G02X610358Y264712I-37662J11471D01*
G03X644169I16906J-13531D01*
G02X637244Y277843I30737J24602D01*
G01X667619Y306543D02*
X663619Y300543D01*
G01X667619Y303543D02*
G03I-2000J0D01*
G01X582432Y722559D02*
X580932Y727559D01*
X579432Y722559D01*
X582432D01*
G01X580932Y720869D02*
Y727559D01*
G01X579432Y708937D02*
X580932Y703937D01*
X582432Y708937D01*
X579432D01*
G01X580932Y710269D02*
Y703937D01*
G01X643699Y689839D02*
X661080Y674932D01*
G01X648471Y687723D02*
X643699Y689839D01*
X646518Y685445D01*
X648471Y687723D01*
G01X665460Y678308D02*
X661460Y672308D01*
G01X665460Y675308D02*
G03I-2000J0D01*
G01X635394Y734097D02*
X663239Y756487D01*
G01X638351Y738399D02*
X635394Y734097D01*
X640230Y736061D01*
X638351Y738399D01*
G01X667619Y759299D02*
X663619Y753299D01*
G01X667619Y756299D02*
G03I-2000J0D01*
G01X648555Y707882D02*
X660927Y717528D01*
G01X651576Y712139D02*
X648555Y707882D01*
X653420Y709773D01*
X651576Y712139D01*
G01X637244Y730599D02*
G03X617283I-9980J-3040D01*
G02X610358Y717468I-37662J11471D01*
G03X644169I16906J-13531D01*
G02X637244Y730599I30737J24602D01*
G01X643699Y1142594D02*
X661080Y1127687D01*
G01X648471Y1140478D02*
X643699Y1142594D01*
X646518Y1138200D01*
X648471Y1140478D01*
G01X665460Y1131063D02*
X661460Y1125063D01*
G01X665460Y1128063D02*
G03I-2000J0D01*
G01X637244Y1183354D02*
G03X617283I-9980J-3040D01*
G02X610358Y1170223I-37662J11471D01*
G03X644169I16906J-13531D01*
G02X637244Y1183354I30737J24602D01*
G01X582432Y1175314D02*
X580932Y1180314D01*
X579432Y1175314D01*
X582432D01*
G01X580932Y1173624D02*
Y1180314D01*
G01X579432Y1161692D02*
X580932Y1156692D01*
X582432Y1161692D01*
X579432D01*
G01X580932Y1163024D02*
Y1156692D01*
G01X635394Y1186852D02*
X663239Y1209242D01*
G01X638351Y1191154D02*
X635394Y1186852D01*
X640230Y1188816D01*
X638351Y1191154D01*
G01X667619Y1212054D02*
X663619Y1206054D01*
G01X667619Y1209054D02*
G03I-2000J0D01*
G01X648555Y1160637D02*
X660927Y1170283D01*
G01X651576Y1164894D02*
X648555Y1160637D01*
X653420Y1162528D01*
X651576Y1164894D01*
G01X683774Y379197D02*
Y404133D01*
G01X682274Y353424D02*
X683774Y348424D01*
X685274Y353424D01*
X682274D01*
G01X683774Y368597D02*
Y348424D01*
G01X742244D02*
X678774D01*
G01X699413Y375078D02*
X700913Y370078D01*
X702413Y375078D01*
X699413D01*
G01X700913Y376410D02*
Y370078D01*
G01X742244D02*
X695913D01*
G01X763680Y355980D02*
X781061Y341073D01*
G01X768452Y353864D02*
X763680Y355980D01*
X766499Y351586D01*
X768452Y353864D01*
G01X757225Y396740D02*
G03X737264I-9981J-3040D01*
G02X730339Y383609I-37662J11471D01*
G03X764150I16905J-13531D01*
G02X757225Y396740I30737J24602D01*
G01X685274Y399133D02*
X683774Y404133D01*
X682274Y399133D01*
X685274D01*
G01X742244Y404133D02*
X678774D01*
G01X702413Y388700D02*
X700913Y393700D01*
X699413Y388700D01*
X702413D01*
G01X700913Y387010D02*
Y393700D01*
G01X742244D02*
X695913D01*
G01X755375Y400238D02*
X783220Y422628D01*
G01X758332Y404540D02*
X755375Y400238D01*
X760211Y402202D01*
X758332Y404540D01*
G01X685274Y832204D02*
X683774Y837204D01*
X682274Y832204D01*
X685274D01*
G01X683774Y812268D02*
Y837204D01*
G01X682274Y786495D02*
X683774Y781495D01*
X685274Y786495D01*
X682274D01*
G01X683774Y801668D02*
Y781495D01*
G01X742244D02*
X678774D01*
G01X742244Y837204D02*
X678774D01*
G01X702413Y821771D02*
X700913Y826771D01*
X699413Y821771D01*
X702413D01*
G01X700913Y820081D02*
Y826771D01*
G01X699413Y808149D02*
X700913Y803149D01*
X702413Y808149D01*
X699413D01*
G01X700913Y809481D02*
Y803149D01*
G01X742244D02*
X695913D01*
G01X742244Y826771D02*
X695913D01*
G01X763680Y789051D02*
X781061Y774144D01*
G01X768452Y786935D02*
X763680Y789051D01*
X766499Y784657D01*
X768452Y786935D01*
G01X755375Y833309D02*
X783220Y855699D01*
G01X758332Y837611D02*
X755375Y833309D01*
X760211Y835273D01*
X758332Y837611D01*
G01X757225Y829811D02*
G03X737264I-9981J-3040D01*
G02X730339Y816680I-37662J11471D01*
G03X764150I16905J-13531D01*
G02X757225Y829811I30737J24602D01*
G01X839441Y-215664D02*
Y-198164D01*
X836821Y-201664D01*
G01Y-215664D02*
X842061D01*
G01X852793Y-208373D02*
X854321Y-206331D01*
X855631Y-205164D01*
X857378Y-204581D01*
X858906Y-205164D01*
X859998Y-206331D01*
X860871Y-208081D01*
X861089Y-210122D01*
X860871Y-211873D01*
X859998Y-213623D01*
X858687Y-215081D01*
X857159Y-215664D01*
X855413Y-215081D01*
X853884Y-213331D01*
X853011Y-210706D01*
X852793Y-207789D01*
X853229Y-203998D01*
X853884Y-201955D01*
X854976Y-199914D01*
X856504Y-198456D01*
X858033Y-198164D01*
X859561Y-198747D01*
X860653Y-200206D01*
G01X869638Y-212164D02*
X870947Y-214206D01*
X872694Y-215372D01*
X874659Y-215664D01*
X876406Y-215372D01*
X878153Y-213914D01*
X879244Y-212164D01*
X879463Y-210414D01*
X879026Y-208373D01*
X877498Y-206914D01*
X875969Y-206331D01*
X874004D01*
G01X875969D02*
X877279Y-205456D01*
X878371Y-203998D01*
X878808Y-202248D01*
X878371Y-200497D01*
X877279Y-199039D01*
X875314Y-198164D01*
X873349Y-198456D01*
X871384Y-199623D01*
G01X891941Y-215664D02*
Y-198164D01*
X889321Y-201664D01*
G01Y-215664D02*
X894561D01*
G01X909004D02*
X909441Y-211873D01*
X910096Y-208664D01*
X910969Y-205747D01*
X912061Y-202539D01*
X913808Y-198164D01*
X905074D01*
G01X826324Y-170664D02*
Y-153164D01*
X831564D01*
X833311Y-154039D01*
X834621Y-156081D01*
X835058Y-158414D01*
X834621Y-160747D01*
X833529Y-162497D01*
X831564Y-163373D01*
X826324D01*
G01X852994Y-154623D02*
X851684Y-153747D01*
X850156Y-153164D01*
X848409D01*
X846444Y-154039D01*
X844916Y-155497D01*
X843824Y-157248D01*
X842951Y-160164D01*
X842732Y-162789D01*
X843169Y-165414D01*
X843824Y-167164D01*
X845134Y-168914D01*
X846663Y-170081D01*
X848191Y-170664D01*
X849719D01*
X851248Y-170081D01*
X852558Y-169206D01*
X853650Y-168040D01*
G01X867437Y-161331D02*
X868311Y-160456D01*
X868966Y-158998D01*
X869403Y-156955D01*
X868966Y-155206D01*
X868093Y-154039D01*
X866564Y-153164D01*
X860669D01*
Y-170664D01*
X867874D01*
X869403Y-169498D01*
X870276Y-167747D01*
X870713Y-165706D01*
X870276Y-163664D01*
X868966Y-161914D01*
X867437Y-161331D01*
X860669D01*
G01X876641Y-176497D02*
X889741D01*
G01X895669Y-170664D02*
Y-153164D01*
X905713Y-170664D01*
Y-153164D01*
G01X918191Y-170664D02*
X916444Y-170372D01*
X914916Y-169206D01*
X913606Y-167456D01*
X912732Y-165414D01*
X912296Y-163081D01*
Y-160747D01*
X912732Y-158414D01*
X913606Y-156372D01*
X914916Y-154623D01*
X916444Y-153456D01*
X918191Y-153164D01*
X919937Y-153456D01*
X921466Y-154623D01*
X922776Y-156372D01*
X923650Y-158414D01*
X924086Y-160747D01*
Y-163081D01*
X923650Y-165414D01*
X922776Y-167456D01*
X921466Y-169206D01*
X919937Y-170372D01*
X918191Y-170664D01*
G01X785441Y344449D02*
X781441Y338449D01*
G01X785441Y341449D02*
G03I-2000J0D01*
G01X768536Y374023D02*
X780908Y383669D01*
G01X771557Y378280D02*
X768536Y374023D01*
X773401Y375914D01*
X771557Y378280D01*
G01X787600Y425440D02*
X783600Y419440D01*
G01X787600Y422440D02*
G03I-2000J0D01*
G01X785441Y777520D02*
X781441Y771520D01*
G01X785441Y774520D02*
G03I-2000J0D01*
G01X787600Y858511D02*
X783600Y852511D01*
G01X787600Y855511D02*
G03I-2000J0D01*
G01X768536Y807094D02*
X780908Y816740D01*
G01X771557Y811351D02*
X768536Y807094D01*
X773401Y808985D01*
X771557Y811351D01*
G01X899447Y721180D02*
X897947Y726180D01*
X896447Y721180D01*
X899447D01*
G01X897947Y701244D02*
Y726180D01*
G01X896447Y675471D02*
X897947Y670471D01*
X899447Y675471D01*
X896447D01*
G01X897947Y690644D02*
Y670471D01*
G01X956417D02*
X892947D01*
G01X956417Y726180D02*
X892947D01*
G01X916586Y710747D02*
X915086Y715747D01*
X913586Y710747D01*
X916586D01*
G01X915086Y709057D02*
Y715747D01*
G01X913586Y697125D02*
X915086Y692125D01*
X916586Y697125D01*
X913586D01*
G01X915086Y698457D02*
Y692125D01*
G01X956417D02*
X910086D01*
G01X956417Y715747D02*
X910086D01*
G01X971398Y718787D02*
G03X951437I-9980J-3040D01*
G02X944512Y705656I-37662J11471D01*
G03X978323I16905J-13531D01*
G02X971398Y718787I30737J24602D01*
G01X896447Y943975D02*
X897947Y938975D01*
X899447Y943975D01*
X896447D01*
G01X897947Y959148D02*
Y938975D01*
G01X956417D02*
X892947D01*
G01X971398Y987291D02*
G03X951437I-9980J-3040D01*
G02X944512Y974160I-37662J11471D01*
G03X978323I16905J-13531D01*
G02X971398Y987291I30737J24602D01*
G01X899447Y989684D02*
X897947Y994684D01*
X896447Y989684D01*
X899447D01*
G01X897947Y969748D02*
Y994684D01*
G01X956417D02*
X892947D01*
G01X916586Y979251D02*
X915086Y984251D01*
X913586Y979251D01*
X916586D01*
G01X915086Y977561D02*
Y984251D01*
G01X913586Y965629D02*
X915086Y960629D01*
X916586Y965629D01*
X913586D01*
G01X915086Y966961D02*
Y960629D01*
G01X956417D02*
X910086D01*
G01X956417Y984251D02*
X910086D01*
G01X1000741Y-215664D02*
Y-198164D01*
X998121Y-201664D01*
G01Y-215664D02*
X1003361D01*
G01X969032Y-153164D02*
X974491Y-170664D01*
X979950Y-153164D01*
G01X996358Y-170664D02*
X987624D01*
Y-153164D01*
X996358D01*
G01X992864Y-161622D02*
X987624D01*
G01X1005124Y-170664D02*
Y-153164D01*
X1010583D01*
X1012329Y-154039D01*
X1013421Y-155206D01*
X1013858Y-157539D01*
X1013421Y-159873D01*
X1012111Y-161331D01*
X1010583Y-162206D01*
X1005124D01*
G01X1010583D02*
X1013858Y-170664D01*
G01X1026991Y-171247D02*
X1026554Y-170956D01*
Y-170372D01*
X1026991Y-170081D01*
X1027428Y-170372D01*
Y-170956D01*
X1026991Y-171247D01*
G01X977853Y678027D02*
X995234Y663120D01*
G01X999614Y666496D02*
X995614Y660496D01*
G01X999614Y663496D02*
G03I-2000J0D01*
G01X982625Y675911D02*
X977853Y678027D01*
X980672Y673633D01*
X982625Y675911D01*
G01X969548Y722285D02*
X997393Y744675D01*
G01X972505Y726587D02*
X969548Y722285D01*
X974384Y724249D01*
X972505Y726587D01*
G01X1001773Y747487D02*
X997773Y741487D01*
G01X1001773Y744487D02*
G03I-2000J0D01*
G01X982709Y696070D02*
X995081Y705716D01*
G01X985730Y700327D02*
X982709Y696070D01*
X987574Y697961D01*
X985730Y700327D01*
G01X977853Y946531D02*
X995234Y931624D01*
G01X982625Y944415D02*
X977853Y946531D01*
X980672Y942137D01*
X982625Y944415D01*
G01X999614Y935000D02*
X995614Y929000D01*
G01X999614Y932000D02*
G03I-2000J0D01*
G01X969548Y990789D02*
X997393Y1013179D01*
G01X972505Y995091D02*
X969548Y990789D01*
X974384Y992753D01*
X972505Y995091D01*
G01X1001773Y1015991D02*
X997773Y1009991D01*
G01X1001773Y1012991D02*
G03I-2000J0D01*
G01X982709Y964574D02*
X995081Y974220D01*
G01X985730Y968831D02*
X982709Y964574D01*
X987574Y966465D01*
X985730Y968831D01*
G01X1102138Y-215664D02*
Y-198164D01*
X1106504D01*
X1108251Y-199039D01*
X1109561Y-200206D01*
X1110653Y-201955D01*
X1111526Y-203998D01*
X1111744Y-206914D01*
X1111526Y-209831D01*
X1110653Y-211873D01*
X1109561Y-213623D01*
X1108251Y-214789D01*
X1106504Y-215664D01*
X1102138D01*
G01X1120074D02*
Y-198164D01*
X1125533D01*
X1127279Y-199039D01*
X1128371Y-200206D01*
X1128808Y-202539D01*
X1128371Y-204873D01*
X1127061Y-206331D01*
X1125533Y-207206D01*
X1120074D01*
G01X1125533D02*
X1128808Y-215664D01*
G01X1139321Y-198164D02*
X1144561D01*
G01X1141941D02*
Y-215664D01*
G01X1139321D02*
X1144561D01*
G01X1155074Y-198164D02*
Y-215664D01*
X1163808D01*
G01X1172574Y-198164D02*
Y-215664D01*
X1181308D01*
G01X1102574Y-153164D02*
Y-170664D01*
X1111308D01*
G01X1128371D02*
Y-158998D01*
G01Y-161039D02*
X1127498Y-159873D01*
X1126187Y-159289D01*
X1124659Y-158998D01*
X1123131Y-159581D01*
X1121821Y-160747D01*
X1120947Y-162497D01*
X1120511Y-164831D01*
X1120947Y-167164D01*
X1121821Y-168914D01*
X1123131Y-170081D01*
X1124659Y-170664D01*
X1126187Y-170372D01*
X1127498Y-169498D01*
X1128371Y-168331D01*
G01X1137356Y-175914D02*
X1138666Y-176497D01*
X1140413Y-175914D01*
X1141504Y-174748D01*
X1142378Y-173289D01*
X1143687Y-168623D01*
X1146526Y-158998D01*
G01X1139539D02*
X1143687Y-168623D01*
G01X1156166Y-162789D02*
X1163153D01*
X1162498Y-160747D01*
X1161406Y-159581D01*
X1159878Y-158998D01*
X1158349Y-159289D01*
X1157039Y-160164D01*
X1156166Y-162206D01*
X1155729Y-163956D01*
Y-165706D01*
X1156166Y-167456D01*
X1157258Y-169206D01*
X1158568Y-170372D01*
X1160096Y-170664D01*
X1161624Y-170081D01*
X1163153Y-168331D01*
G01X1173884Y-170664D02*
Y-158998D01*
G01Y-161331D02*
X1174976Y-160164D01*
X1176068Y-159289D01*
X1177596Y-158998D01*
X1178687Y-159289D01*
X1179998Y-160164D01*
G01X1118419Y379197D02*
Y404133D01*
G01X1116919Y353424D02*
X1118419Y348424D01*
X1119919Y353424D01*
X1116919D01*
G01X1118419Y368597D02*
Y348424D01*
G01X1176889D02*
X1113419D01*
G01X1134058Y375078D02*
X1135558Y370078D01*
X1137058Y375078D01*
X1134058D01*
G01X1135558Y376410D02*
Y370078D01*
G01X1176889D02*
X1130558D01*
G01X1119919Y399133D02*
X1118419Y404133D01*
X1116919Y399133D01*
X1119919D01*
G01X1176889Y404133D02*
X1113419D01*
G01X1137058Y388700D02*
X1135558Y393700D01*
X1134058Y388700D01*
X1137058D01*
G01X1135558Y387010D02*
Y393700D01*
G01X1176889D02*
X1130558D01*
G01X1116919Y943975D02*
X1118419Y938975D01*
X1119919Y943975D01*
X1116919D01*
G01X1118419Y959148D02*
Y938975D01*
G01X1176889D02*
X1113419D01*
G01X1119919Y989684D02*
X1118419Y994684D01*
X1116919Y989684D01*
X1119919D01*
G01X1118419Y969748D02*
Y994684D01*
G01X1176889D02*
X1113419D01*
G01X1137058Y979251D02*
X1135558Y984251D01*
X1134058Y979251D01*
X1137058D01*
G01X1135558Y977561D02*
Y984251D01*
G01X1134058Y965629D02*
X1135558Y960629D01*
X1137058Y965629D01*
X1134058D01*
G01X1135558Y966961D02*
Y960629D01*
G01X1176889D02*
X1130558D01*
G01X1176889Y984251D02*
X1130558D01*
G01X1244688Y-170664D02*
Y-153164D01*
X1249054D01*
X1250801Y-154039D01*
X1252111Y-155206D01*
X1253203Y-156955D01*
X1254076Y-158998D01*
X1254294Y-161914D01*
X1254076Y-164831D01*
X1253203Y-166873D01*
X1252111Y-168623D01*
X1250801Y-169789D01*
X1249054Y-170664D01*
X1244688D01*
G01X1263716Y-162789D02*
X1270703D01*
X1270048Y-160747D01*
X1268956Y-159581D01*
X1267428Y-158998D01*
X1265899Y-159289D01*
X1264589Y-160164D01*
X1263716Y-162206D01*
X1263279Y-163956D01*
Y-165706D01*
X1263716Y-167456D01*
X1264808Y-169206D01*
X1266118Y-170372D01*
X1267646Y-170664D01*
X1269174Y-170081D01*
X1270703Y-168331D01*
G01X1281216Y-168623D02*
X1282308Y-169789D01*
X1283836Y-170664D01*
X1285146D01*
X1286456Y-170081D01*
X1287329Y-169206D01*
X1287766Y-168040D01*
X1287548Y-166289D01*
X1286674Y-165414D01*
X1282744Y-163664D01*
X1281871Y-161622D01*
X1282308Y-160164D01*
X1283181Y-159289D01*
X1284491Y-158998D01*
X1285801Y-159289D01*
X1287111Y-160164D01*
G01X1301991Y-158998D02*
Y-170664D01*
G01Y-154331D02*
X1301554Y-154039D01*
Y-153456D01*
X1301991Y-153164D01*
X1302428Y-153456D01*
Y-154039D01*
X1301991Y-154331D01*
G01X1316434Y-175039D02*
X1317963Y-176206D01*
X1319709Y-176497D01*
X1321237Y-176206D01*
X1322548Y-174748D01*
X1323421Y-172706D01*
Y-158998D01*
G01Y-161331D02*
X1322548Y-160164D01*
X1321237Y-159289D01*
X1319709Y-158998D01*
X1317963Y-159581D01*
X1316871Y-160747D01*
X1315997Y-162789D01*
X1315561Y-164831D01*
X1315779Y-166581D01*
X1316653Y-168623D01*
X1317963Y-170081D01*
X1319709Y-170664D01*
X1321019Y-170372D01*
X1322548Y-169206D01*
X1323421Y-168040D01*
G01X1333279Y-170664D02*
Y-158998D01*
G01Y-161914D02*
X1334153Y-160456D01*
X1335463Y-159289D01*
X1337209Y-158998D01*
X1338737Y-159289D01*
X1340048Y-160456D01*
X1340703Y-162497D01*
Y-170664D01*
G01X1351216Y-162789D02*
X1358203D01*
X1357548Y-160747D01*
X1356456Y-159581D01*
X1354928Y-158998D01*
X1353399Y-159289D01*
X1352089Y-160164D01*
X1351216Y-162206D01*
X1350779Y-163956D01*
Y-165706D01*
X1351216Y-167456D01*
X1352308Y-169206D01*
X1353618Y-170372D01*
X1355146Y-170664D01*
X1356674Y-170081D01*
X1358203Y-168331D01*
G01X1368934Y-170664D02*
Y-158998D01*
G01Y-161331D02*
X1370026Y-160164D01*
X1371118Y-159289D01*
X1372646Y-158998D01*
X1373737Y-159289D01*
X1375048Y-160164D01*
G01X1239900Y280235D02*
X1238400Y285235D01*
X1236900Y280235D01*
X1239900D01*
G01X1238400Y260299D02*
Y285235D01*
G01X1236900Y234526D02*
X1238400Y229526D01*
X1239900Y234526D01*
X1236900D01*
G01X1238400Y249699D02*
Y229526D01*
G01X1296870D02*
X1233400D01*
G01X1296870Y285235D02*
X1233400D01*
G01X1198325Y355980D02*
X1215706Y341073D01*
G01X1203097Y353864D02*
X1198325Y355980D01*
X1201144Y351586D01*
X1203097Y353864D01*
G01X1220086Y344449D02*
X1216086Y338449D01*
G01X1220086Y341449D02*
G03I-2000J0D01*
G01X1203181Y374023D02*
X1215553Y383669D01*
G01X1206202Y378280D02*
X1203181Y374023D01*
X1208046Y375914D01*
X1206202Y378280D01*
G01X1191870Y396740D02*
G03X1171909I-9980J-3040D01*
G02X1164984Y383609I-37662J11471D01*
G03X1198795I16906J-13531D01*
G02X1191870Y396740I30737J24602D01*
G01X1190020Y400238D02*
X1217865Y422628D01*
G01X1192977Y404540D02*
X1190020Y400238D01*
X1194856Y402202D01*
X1192977Y404540D01*
G01X1222245Y425440D02*
X1218245Y419440D01*
G01X1222245Y422440D02*
G03I-2000J0D01*
G01X1239900Y732992D02*
X1238400Y737992D01*
X1236900Y732992D01*
X1239900D01*
G01X1238400Y713056D02*
Y737992D01*
G01X1236900Y687283D02*
X1238400Y682283D01*
X1239900Y687283D01*
X1236900D01*
G01X1238400Y702456D02*
Y682283D01*
G01X1296870D02*
X1233400D01*
G01X1296870Y737992D02*
X1233400D01*
G01X1198325Y946531D02*
X1215706Y931624D01*
G01X1203097Y944415D02*
X1198325Y946531D01*
X1201144Y942137D01*
X1203097Y944415D01*
G01X1220086Y935000D02*
X1216086Y929000D01*
G01X1220086Y932000D02*
G03I-2000J0D01*
G01X1191870Y987291D02*
G03X1171909I-9980J-3040D01*
G02X1164984Y974160I-37662J11471D01*
G03X1198795I16906J-13531D01*
G02X1191870Y987291I30737J24602D01*
G01X1190020Y990789D02*
X1217865Y1013179D01*
G01X1192977Y995091D02*
X1190020Y990789D01*
X1194856Y992753D01*
X1192977Y995091D01*
G01X1222245Y1015991D02*
X1218245Y1009991D01*
G01X1222245Y1012991D02*
G03I-2000J0D01*
G01X1203181Y964574D02*
X1215553Y974220D01*
G01X1206202Y968831D02*
X1203181Y964574D01*
X1208046Y966465D01*
X1206202Y968831D01*
G01X1236900Y1140038D02*
X1238400Y1135038D01*
X1239900Y1140038D01*
X1236900D01*
G01X1238400Y1155211D02*
Y1135038D01*
G01X1296870D02*
X1233400D01*
G01X1239900Y1185747D02*
X1238400Y1190747D01*
X1236900Y1185747D01*
X1239900D01*
G01X1238400Y1165811D02*
Y1190747D01*
G01X1296870D02*
X1233400D01*
G01X1266991Y-215664D02*
X1265244Y-215372D01*
X1263716Y-214206D01*
X1262406Y-212456D01*
X1261532Y-210414D01*
X1261096Y-208081D01*
Y-205747D01*
X1261532Y-203414D01*
X1262406Y-201372D01*
X1263716Y-199623D01*
X1265244Y-198456D01*
X1266991Y-198164D01*
X1268737Y-198456D01*
X1270266Y-199623D01*
X1271576Y-201372D01*
X1272450Y-203414D01*
X1272886Y-205747D01*
Y-208081D01*
X1272450Y-210414D01*
X1271576Y-212456D01*
X1270266Y-214206D01*
X1268737Y-215372D01*
X1266991Y-215664D01*
G01X1268737Y-210997D02*
X1271358Y-215664D01*
G01X1279688Y-198164D02*
Y-210706D01*
X1280561Y-213331D01*
X1282308Y-215081D01*
X1284491Y-215664D01*
X1286674Y-215081D01*
X1288421Y-213331D01*
X1289294Y-210706D01*
Y-198164D01*
G01X1299371D02*
X1304611D01*
G01X1301991D02*
Y-215664D01*
G01X1299371D02*
X1304611D01*
G01X1314469D02*
Y-198164D01*
X1324513Y-215664D01*
Y-198164D01*
G01X1341794Y-199623D02*
X1340484Y-198747D01*
X1338956Y-198164D01*
X1337209D01*
X1335244Y-199039D01*
X1333716Y-200497D01*
X1332624Y-202248D01*
X1331751Y-205164D01*
X1331532Y-207789D01*
X1331969Y-210414D01*
X1332624Y-212164D01*
X1333934Y-213914D01*
X1335463Y-215081D01*
X1336991Y-215664D01*
X1338519D01*
X1340048Y-215081D01*
X1341358Y-214206D01*
X1342450Y-213040D01*
G01X1354491Y-215664D02*
Y-207789D01*
X1350124Y-198164D01*
G01X1358858D02*
X1354491Y-207789D01*
G01X1257039Y269802D02*
X1255539Y274802D01*
X1254039Y269802D01*
X1257039D01*
G01X1255539Y268112D02*
Y274802D01*
G01X1254039Y256180D02*
X1255539Y251180D01*
X1257039Y256180D01*
X1254039D01*
G01X1255539Y257512D02*
Y251180D01*
G01X1296870D02*
X1250539D01*
G01X1296870Y274802D02*
X1250539D01*
G01X1318306Y237082D02*
X1335687Y222175D01*
G01X1323078Y234966D02*
X1318306Y237082D01*
X1321125Y232688D01*
X1323078Y234966D01*
G01X1340067Y225551D02*
X1336067Y219551D01*
G01X1340067Y222551D02*
G03I-2000J0D01*
G01X1310001Y281340D02*
X1337846Y303730D01*
G01X1312958Y285642D02*
X1310001Y281340D01*
X1314837Y283304D01*
X1312958Y285642D01*
G01X1323162Y255125D02*
X1335534Y264771D01*
G01X1326183Y259382D02*
X1323162Y255125D01*
X1328027Y257016D01*
X1326183Y259382D01*
G01X1311851Y277842D02*
G03X1291890I-9980J-3040D01*
G02X1284965Y264711I-37662J11471D01*
G03X1318776I16906J-13531D01*
G02X1311851Y277842I30737J24602D01*
G01X1342226Y306542D02*
X1338226Y300542D01*
G01X1342226Y303542D02*
G03I-2000J0D01*
G01X1257039Y722559D02*
X1255539Y727559D01*
X1254039Y722559D01*
X1257039D01*
G01X1255539Y720869D02*
Y727559D01*
G01X1254039Y708937D02*
X1255539Y703937D01*
X1257039Y708937D01*
X1254039D01*
G01X1255539Y710269D02*
Y703937D01*
G01X1296870D02*
X1250539D01*
G01X1296870Y727559D02*
X1250539D01*
G01X1318306Y689839D02*
X1335687Y674932D01*
G01X1323078Y687723D02*
X1318306Y689839D01*
X1321125Y685445D01*
X1323078Y687723D01*
G01X1340067Y678308D02*
X1336067Y672308D01*
G01X1340067Y675308D02*
G03I-2000J0D01*
G01X1310001Y734097D02*
X1337846Y756487D01*
G01X1312958Y738399D02*
X1310001Y734097D01*
X1314837Y736061D01*
X1312958Y738399D01*
G01X1342226Y759299D02*
X1338226Y753299D01*
G01X1342226Y756299D02*
G03I-2000J0D01*
G01X1323162Y707882D02*
X1335534Y717528D01*
G01X1326183Y712139D02*
X1323162Y707882D01*
X1328027Y709773D01*
X1326183Y712139D01*
G01X1311851Y730599D02*
G03X1291890I-9980J-3040D01*
G02X1284965Y717468I-37662J11471D01*
G03X1318776I16906J-13531D01*
G02X1311851Y730599I30737J24602D01*
G01X1318306Y1142594D02*
X1335687Y1127687D01*
G01X1323078Y1140478D02*
X1318306Y1142594D01*
X1321125Y1138200D01*
X1323078Y1140478D01*
G01X1340067Y1131063D02*
X1336067Y1125063D01*
G01X1340067Y1128063D02*
G03I-2000J0D01*
G01X1311851Y1183354D02*
G03X1291890I-9980J-3040D01*
G02X1284965Y1170223I-37662J11471D01*
G03X1318776I16906J-13531D01*
G02X1311851Y1183354I30737J24602D01*
G01X1257039Y1175314D02*
X1255539Y1180314D01*
X1254039Y1175314D01*
X1257039D01*
G01X1255539Y1173624D02*
Y1180314D01*
G01X1254039Y1161692D02*
X1255539Y1156692D01*
X1257039Y1161692D01*
X1254039D01*
G01X1255539Y1163024D02*
Y1156692D01*
G01X1296870D02*
X1250539D01*
G01X1296870Y1180314D02*
X1250539D01*
G01X1310001Y1186852D02*
X1337846Y1209242D01*
G01X1312958Y1191154D02*
X1310001Y1186852D01*
X1314837Y1188816D01*
X1312958Y1191154D01*
G01X1342226Y1212054D02*
X1338226Y1206054D01*
G01X1342226Y1209054D02*
G03I-2000J0D01*
G01X1323162Y1160637D02*
X1335534Y1170283D01*
G01X1326183Y1164894D02*
X1323162Y1160637D01*
X1328027Y1162528D01*
X1326183Y1164894D01*
G01X1415691Y-198164D02*
X1413944Y-198747D01*
X1412634Y-200206D01*
X1411761Y-201955D01*
X1411106Y-204289D01*
X1410888Y-206914D01*
X1411106Y-209539D01*
X1411761Y-211873D01*
X1412634Y-213623D01*
X1413944Y-215081D01*
X1415691Y-215664D01*
X1417437Y-215081D01*
X1418748Y-213623D01*
X1419621Y-211873D01*
X1420276Y-209539D01*
X1420494Y-206914D01*
X1420276Y-204289D01*
X1419621Y-201955D01*
X1418748Y-200206D01*
X1417437Y-198747D01*
X1415691Y-198164D01*
G01X1429043Y-208373D02*
X1430571Y-206331D01*
X1431881Y-205164D01*
X1433628Y-204581D01*
X1435156Y-205164D01*
X1436248Y-206331D01*
X1437121Y-208081D01*
X1437339Y-210122D01*
X1437121Y-211873D01*
X1436248Y-213623D01*
X1434937Y-215081D01*
X1433409Y-215664D01*
X1431663Y-215081D01*
X1430134Y-213331D01*
X1429261Y-210706D01*
X1429043Y-207789D01*
X1429479Y-203998D01*
X1430134Y-201955D01*
X1431226Y-199914D01*
X1432754Y-198456D01*
X1434283Y-198164D01*
X1435811Y-198747D01*
X1436903Y-200206D01*
G01X1446761Y-216247D02*
X1454621Y-198164D01*
G01X1468191D02*
X1466444Y-198747D01*
X1465134Y-200206D01*
X1464261Y-201955D01*
X1463606Y-204289D01*
X1463388Y-206914D01*
X1463606Y-209539D01*
X1464261Y-211873D01*
X1465134Y-213623D01*
X1466444Y-215081D01*
X1468191Y-215664D01*
X1469937Y-215081D01*
X1471248Y-213623D01*
X1472121Y-211873D01*
X1472776Y-209539D01*
X1472994Y-206914D01*
X1472776Y-204289D01*
X1472121Y-201955D01*
X1471248Y-200206D01*
X1469937Y-198747D01*
X1468191Y-198164D01*
G01X1481979Y-213623D02*
X1483508Y-215081D01*
X1485254Y-215664D01*
X1487001Y-215081D01*
X1488529Y-213331D01*
X1489621Y-210706D01*
X1490058Y-208081D01*
Y-204873D01*
X1489621Y-202248D01*
X1488529Y-199914D01*
X1487219Y-198747D01*
X1485691Y-198164D01*
X1483944Y-198747D01*
X1482634Y-199914D01*
X1481761Y-201664D01*
X1481324Y-203998D01*
X1481761Y-206039D01*
X1482853Y-208081D01*
X1484163Y-209248D01*
X1485691Y-209539D01*
X1487437Y-208956D01*
X1488748Y-207497D01*
X1490058Y-204873D01*
G01X1499261Y-216247D02*
X1507121Y-198164D01*
G01X1516543Y-201081D02*
X1517853Y-199331D01*
X1519381Y-198456D01*
X1521128Y-198164D01*
X1523311Y-198747D01*
X1524839Y-200206D01*
X1525276Y-201955D01*
X1525058Y-203706D01*
X1524184Y-205164D01*
X1519818Y-208081D01*
X1517853Y-210122D01*
X1516543Y-213040D01*
X1516106Y-215664D01*
X1525276D01*
G01X1538191Y-198164D02*
X1536444Y-198747D01*
X1535134Y-200206D01*
X1534261Y-201955D01*
X1533606Y-204289D01*
X1533388Y-206914D01*
X1533606Y-209539D01*
X1534261Y-211873D01*
X1535134Y-213623D01*
X1536444Y-215081D01*
X1538191Y-215664D01*
X1539937Y-215081D01*
X1541248Y-213623D01*
X1542121Y-211873D01*
X1542776Y-209539D01*
X1542994Y-206914D01*
X1542776Y-204289D01*
X1542121Y-201955D01*
X1541248Y-200206D01*
X1539937Y-198747D01*
X1538191Y-198164D01*
G01X1555691Y-215664D02*
Y-198164D01*
X1553071Y-201664D01*
G01Y-215664D02*
X1558311D01*
G01X1572754D02*
X1573191Y-211873D01*
X1573846Y-208664D01*
X1574719Y-205747D01*
X1575811Y-202539D01*
X1577558Y-198164D01*
X1568824D01*
G01X1463388Y-170664D02*
Y-153164D01*
X1467754D01*
X1469501Y-154039D01*
X1470811Y-155206D01*
X1471903Y-156955D01*
X1472776Y-158998D01*
X1472994Y-161914D01*
X1472776Y-164831D01*
X1471903Y-166873D01*
X1470811Y-168623D01*
X1469501Y-169789D01*
X1467754Y-170664D01*
X1463388D01*
G01X1489621D02*
Y-158998D01*
G01Y-161039D02*
X1488748Y-159873D01*
X1487437Y-159289D01*
X1485909Y-158998D01*
X1484381Y-159581D01*
X1483071Y-160747D01*
X1482197Y-162497D01*
X1481761Y-164831D01*
X1482197Y-167164D01*
X1483071Y-168914D01*
X1484381Y-170081D01*
X1485909Y-170664D01*
X1487437Y-170372D01*
X1488748Y-169498D01*
X1489621Y-168331D01*
G01X1503191Y-153164D02*
Y-170664D01*
G01X1500134Y-158998D02*
X1506248D01*
G01X1517416Y-162789D02*
X1524403D01*
X1523748Y-160747D01*
X1522656Y-159581D01*
X1521128Y-158998D01*
X1519599Y-159289D01*
X1518289Y-160164D01*
X1517416Y-162206D01*
X1516979Y-163956D01*
Y-165706D01*
X1517416Y-167456D01*
X1518508Y-169206D01*
X1519818Y-170372D01*
X1521346Y-170664D01*
X1522874Y-170081D01*
X1524403Y-168331D01*
G01X1487931Y280236D02*
X1486431Y285236D01*
X1484931Y280236D01*
X1487931D01*
G01X1486431Y260300D02*
Y285236D01*
G01X1484931Y234527D02*
X1486431Y229527D01*
X1487931Y234527D01*
X1484931D01*
G01X1486431Y249700D02*
Y229527D01*
G01X1544901D02*
X1481431D01*
G01X1505070Y269803D02*
X1503570Y274803D01*
X1502070Y269803D01*
X1505070D01*
G01X1503570Y268113D02*
Y274803D01*
G01X1502070Y256181D02*
X1503570Y251181D01*
X1505070Y256181D01*
X1502070D01*
G01X1503570Y257513D02*
Y251181D01*
G01X1544901D02*
X1498570D01*
G01X1544901Y274803D02*
X1498570D01*
G01X1559882Y277843D02*
G03X1539921I-9980J-3040D01*
G02X1532996Y264712I-37662J11471D01*
G03X1566807I16906J-13531D01*
G02X1559882Y277843I30737J24602D01*
G01X1544901Y285236D02*
X1481431D01*
G01X1487931Y732992D02*
X1486431Y737992D01*
X1484931Y732992D01*
X1487931D01*
G01X1486431Y713056D02*
Y737992D01*
G01X1484931Y687283D02*
X1486431Y682283D01*
X1487931Y687283D01*
X1484931D01*
G01X1486431Y702456D02*
Y682283D01*
G01X1544901D02*
X1481431D01*
G01X1544901Y737992D02*
X1481431D01*
G01X1505070Y722559D02*
X1503570Y727559D01*
X1502070Y722559D01*
X1505070D01*
G01X1503570Y720869D02*
Y727559D01*
G01X1502070Y708937D02*
X1503570Y703937D01*
X1505070Y708937D01*
X1502070D01*
G01X1503570Y710269D02*
Y703937D01*
G01X1544901D02*
X1498570D01*
G01X1544901Y727559D02*
X1498570D01*
G01X1559882Y730599D02*
G03X1539921I-9980J-3040D01*
G02X1532996Y717468I-37662J11471D01*
G03X1566807I16906J-13531D01*
G02X1559882Y730599I30737J24602D01*
G01X1484931Y1140038D02*
X1486431Y1135038D01*
X1487931Y1140038D01*
X1484931D01*
G01X1486431Y1155211D02*
Y1135038D01*
G01X1544901D02*
X1481431D01*
G01X1487931Y1185747D02*
X1486431Y1190747D01*
X1484931Y1185747D01*
X1487931D01*
G01X1486431Y1165811D02*
Y1190747D01*
G01X1544901D02*
X1481431D01*
G01X1505070Y1175314D02*
X1503570Y1180314D01*
X1502070Y1175314D01*
X1505070D01*
G01X1503570Y1173624D02*
Y1180314D01*
G01X1502070Y1161692D02*
X1503570Y1156692D01*
X1505070Y1161692D01*
X1502070D01*
G01X1503570Y1163024D02*
Y1156692D01*
G01X1544901D02*
X1498570D01*
G01X1544901Y1180314D02*
X1498570D01*
G01X1559882Y1183354D02*
G03X1539921I-9980J-3040D01*
G02X1532996Y1170223I-37662J11471D01*
G03X1566807I16906J-13531D01*
G02X1559882Y1183354I30737J24602D01*
G01X1566337Y237083D02*
X1583718Y222176D01*
G01X1571109Y234967D02*
X1566337Y237083D01*
X1569156Y232689D01*
X1571109Y234967D01*
G01X1588098Y225552D02*
X1584098Y219552D01*
G01X1588098Y222552D02*
G03I-2000J0D01*
G01X1558032Y281341D02*
X1585877Y303731D01*
G01X1560989Y285643D02*
X1558032Y281341D01*
X1562868Y283305D01*
X1560989Y285643D01*
G01X1571193Y255126D02*
X1583565Y264772D01*
G01X1574214Y259383D02*
X1571193Y255126D01*
X1576058Y257017D01*
X1574214Y259383D01*
G01X1590257Y306543D02*
X1586257Y300543D01*
G01X1590257Y303543D02*
G03I-2000J0D01*
G01X1566337Y689839D02*
X1583718Y674932D01*
G01X1571109Y687723D02*
X1566337Y689839D01*
X1569156Y685445D01*
X1571109Y687723D01*
G01X1588098Y678308D02*
X1584098Y672308D01*
G01X1588098Y675308D02*
G03I-2000J0D01*
G01X1558032Y734097D02*
X1585877Y756487D01*
G01X1560989Y738399D02*
X1558032Y734097D01*
X1562868Y736061D01*
X1560989Y738399D01*
G01X1590257Y759299D02*
X1586257Y753299D01*
G01X1590257Y756299D02*
G03I-2000J0D01*
G01X1571193Y707882D02*
X1583565Y717528D01*
G01X1574214Y712139D02*
X1571193Y707882D01*
X1576058Y709773D01*
X1574214Y712139D01*
G01X1566337Y1142594D02*
X1583718Y1127687D01*
G01X1571109Y1140478D02*
X1566337Y1142594D01*
X1569156Y1138200D01*
X1571109Y1140478D01*
G01X1588098Y1131063D02*
X1584098Y1125063D01*
G01X1588098Y1128063D02*
G03I-2000J0D01*
G01X1558032Y1186852D02*
X1585877Y1209242D01*
G01X1560989Y1191154D02*
X1558032Y1186852D01*
X1562868Y1188816D01*
X1560989Y1191154D01*
G01X1590257Y1212054D02*
X1586257Y1206054D01*
G01X1590257Y1209054D02*
G03I-2000J0D01*
G01X1571193Y1160637D02*
X1583565Y1170283D01*
G01X1574214Y1164894D02*
X1571193Y1160637D01*
X1576058Y1162528D01*
X1574214Y1164894D01*
G01X1807914Y277842D02*
G03X1787953I-9980J-3040D01*
G02X1781028Y264711I-37662J11471D01*
G03X1814839I16906J-13531D01*
G02X1807914Y277842I30737J24602D01*
G01X1809021Y285642D02*
X1806064Y281340D01*
X1810900Y283304D01*
X1809021Y285642D01*
G01X1806064Y281340D02*
X1833909Y303730D01*
G01X1819141Y234966D02*
X1814369Y237082D01*
X1817188Y232688D01*
X1819141Y234966D01*
G01X1814369Y237082D02*
X1831750Y222175D01*
G01X1792933Y274802D02*
X1746602D01*
G01X1792933Y251180D02*
X1746602D01*
G01X1751602Y257512D02*
Y251180D01*
G01X1750102Y256180D02*
X1751602Y251180D01*
X1753102Y256180D01*
X1750102D01*
G01X1751602Y268112D02*
Y274802D01*
G01X1753102Y269802D02*
X1751602Y274802D01*
X1750102Y269802D01*
X1753102D01*
G01X1792933Y229526D02*
X1729463D01*
G01X1734463Y249699D02*
Y229526D01*
G01X1732963Y234526D02*
X1734463Y229526D01*
X1735963Y234526D01*
X1732963D01*
G01X1734463Y260299D02*
Y285235D01*
G01X1735963Y280235D02*
X1734463Y285235D01*
X1732963Y280235D01*
X1735963D01*
G01X1792933Y285235D02*
X1729463D01*
G01X1735963Y732992D02*
X1734463Y737992D01*
X1732963Y732992D01*
X1735963D01*
G01X1734463Y713056D02*
Y737992D01*
G01X1732963Y687283D02*
X1734463Y682283D01*
X1735963Y687283D01*
X1732963D01*
G01X1734463Y702456D02*
Y682283D01*
G01X1792933D02*
X1729463D01*
G01X1792933Y737992D02*
X1729463D01*
G01X1753102Y722559D02*
X1751602Y727559D01*
X1750102Y722559D01*
X1753102D01*
G01X1751602Y720869D02*
Y727559D01*
G01X1750102Y708937D02*
X1751602Y703937D01*
X1753102Y708937D01*
X1750102D01*
G01X1751602Y710269D02*
Y703937D01*
G01X1792933D02*
X1746602D01*
G01X1792933Y727559D02*
X1746602D01*
G01X1814369Y689839D02*
X1831750Y674932D01*
G01X1819141Y687723D02*
X1814369Y689839D01*
X1817188Y685445D01*
X1819141Y687723D01*
G01X1806064Y734097D02*
X1833909Y756487D01*
G01X1809021Y738399D02*
X1806064Y734097D01*
X1810900Y736061D01*
X1809021Y738399D01*
G01X1807914Y730599D02*
G03X1787953I-9980J-3040D01*
G02X1781028Y717468I-37662J11471D01*
G03X1814839I16906J-13531D01*
G02X1807914Y730599I30737J24602D01*
G01Y1183354D02*
G03X1787953I-9980J-3040D01*
G02X1781028Y1170223I-37662J11471D01*
G03X1814839I16906J-13531D01*
G02X1807914Y1183354I30737J24602D01*
G01X1819141Y1140478D02*
X1814369Y1142594D01*
X1817188Y1138200D01*
X1819141Y1140478D01*
G01X1814369Y1142594D02*
X1831750Y1127687D01*
G01X1792933Y1135038D02*
X1729463D01*
G01X1734463Y1155211D02*
Y1135038D01*
G01X1732963Y1140038D02*
X1734463Y1135038D01*
X1735963Y1140038D01*
X1732963D01*
G01X1809021Y1191154D02*
X1806064Y1186852D01*
X1810900Y1188816D01*
X1809021Y1191154D01*
G01X1806064Y1186852D02*
X1833909Y1209242D01*
G01X1792933Y1180314D02*
X1746602D01*
G01X1792933Y1156692D02*
X1746602D01*
G01X1751602Y1163024D02*
Y1156692D01*
G01X1750102Y1161692D02*
X1751602Y1156692D01*
X1753102Y1161692D01*
X1750102D01*
G01X1751602Y1173624D02*
Y1180314D01*
G01X1753102Y1175314D02*
X1751602Y1180314D01*
X1750102Y1175314D01*
X1753102D01*
G01X1792933Y1190747D02*
X1729463D01*
G01X1734463Y1165811D02*
Y1190747D01*
G01X1735963Y1185747D02*
X1734463Y1190747D01*
X1732963Y1185747D01*
X1735963D01*
G01X1822246Y259382D02*
X1819225Y255125D01*
X1824090Y257016D01*
X1822246Y259382D01*
G01X1819225Y255125D02*
X1831597Y264771D01*
G01X1836130Y222551D02*
G03I-2000J0D01*
G01Y225551D02*
X1832130Y219551D01*
G01X1838289Y303542D02*
G03I-2000J0D01*
G01Y306542D02*
X1834289Y300542D01*
G01X1836130Y678308D02*
X1832130Y672308D01*
G01X1836130Y675308D02*
G03I-2000J0D01*
G01X1838289Y759299D02*
X1834289Y753299D01*
G01X1838289Y756299D02*
G03I-2000J0D01*
G01X1819225Y707882D02*
X1831597Y717528D01*
G01X1822246Y712139D02*
X1819225Y707882D01*
X1824090Y709773D01*
X1822246Y712139D01*
G01X1836130Y1128063D02*
G03I-2000J0D01*
G01Y1131063D02*
X1832130Y1125063D01*
G01X1822246Y1164894D02*
X1819225Y1160637D01*
X1824090Y1162528D01*
X1822246Y1164894D01*
G01X1819225Y1160637D02*
X1831597Y1170283D01*
G01X1838289Y1209054D02*
G03I-2000J0D01*
G01Y1212054D02*
X1834289Y1206054D01*
G01X2217585Y74200D02*
Y86700D01*
X2224715Y74200D01*
Y86700D01*
G01X2233550Y74200D02*
X2232620Y74408D01*
X2231690Y75241D01*
X2231070Y76700D01*
X2230760Y78367D01*
X2231070Y80033D01*
X2231690Y81492D01*
X2232620Y82325D01*
X2233550Y82533D01*
X2234480Y82325D01*
X2235410Y81492D01*
X2236030Y80033D01*
X2236185Y78367D01*
X2236030Y76700D01*
X2235410Y75241D01*
X2234480Y74408D01*
X2233550Y74200D01*
G01X2245950Y86700D02*
Y74200D01*
G01X2243780Y82533D02*
X2248120D01*
G01X2256025Y79825D02*
X2260985D01*
X2260520Y81283D01*
X2259745Y82117D01*
X2258660Y82533D01*
X2257575Y82325D01*
X2256645Y81700D01*
X2256025Y80242D01*
X2255715Y78991D01*
Y77742D01*
X2256025Y76492D01*
X2256800Y75241D01*
X2257730Y74408D01*
X2258815Y74200D01*
X2259900Y74617D01*
X2260985Y75866D01*
G01X2270750Y73783D02*
X2270440Y73992D01*
Y74408D01*
X2270750Y74617D01*
X2271060Y74408D01*
Y73992D01*
X2270750Y73783D01*
G01Y79408D02*
X2270440Y79617D01*
Y80033D01*
X2270750Y80242D01*
X2271060Y80033D01*
Y79617D01*
X2270750Y79408D01*
G01X2280050Y74200D02*
Y86700D01*
X2283925D01*
X2285165Y86075D01*
X2285940Y85242D01*
X2286250Y83575D01*
X2285940Y81908D01*
X2285010Y80867D01*
X2283925Y80242D01*
X2280050D01*
G01X2283925D02*
X2286250Y74200D01*
G01X2293225Y79825D02*
X2298185D01*
X2297720Y81283D01*
X2296945Y82117D01*
X2295860Y82533D01*
X2294775Y82325D01*
X2293845Y81700D01*
X2293225Y80242D01*
X2292915Y78991D01*
Y77742D01*
X2293225Y76492D01*
X2294000Y75241D01*
X2294930Y74408D01*
X2296015Y74200D01*
X2297100Y74617D01*
X2298185Y75866D01*
G01X2307020Y74200D02*
Y84825D01*
X2307330Y85866D01*
X2307950Y86492D01*
X2308880Y86700D01*
X2309810Y86283D01*
X2310275Y85242D01*
G01X2308415Y81700D02*
X2305315D01*
G01X2318025Y79825D02*
X2322985D01*
X2322520Y81283D01*
X2321745Y82117D01*
X2320660Y82533D01*
X2319575Y82325D01*
X2318645Y81700D01*
X2318025Y80242D01*
X2317715Y78991D01*
Y77742D01*
X2318025Y76492D01*
X2318800Y75241D01*
X2319730Y74408D01*
X2320815Y74200D01*
X2321900Y74617D01*
X2322985Y75866D01*
G01X2330580Y74200D02*
Y82533D01*
G01Y80867D02*
X2331355Y81700D01*
X2332130Y82325D01*
X2333215Y82533D01*
X2333990Y82325D01*
X2334920Y81700D01*
G01X2357550Y86700D02*
Y74200D01*
G01X2355380Y82533D02*
X2359720D01*
G01X2369950Y74200D02*
X2369020Y74408D01*
X2368090Y75241D01*
X2367470Y76700D01*
X2367160Y78367D01*
X2367470Y80033D01*
X2368090Y81492D01*
X2369020Y82325D01*
X2369950Y82533D01*
X2370880Y82325D01*
X2371810Y81492D01*
X2372430Y80033D01*
X2372585Y78367D01*
X2372430Y76700D01*
X2371810Y75241D01*
X2370880Y74408D01*
X2369950Y74200D01*
G01X2391340D02*
Y86700D01*
X2394440D01*
X2395680Y86075D01*
X2396610Y85242D01*
X2397385Y83992D01*
X2398005Y82533D01*
X2398160Y80450D01*
X2398005Y78367D01*
X2397385Y76908D01*
X2396610Y75658D01*
X2395680Y74825D01*
X2394440Y74200D01*
X2391340D01*
G01X2404050D02*
Y86700D01*
X2407925D01*
X2409165Y86075D01*
X2409940Y85242D01*
X2410250Y83575D01*
X2409940Y81908D01*
X2409010Y80867D01*
X2407925Y80242D01*
X2404050D01*
G01X2407925D02*
X2410250Y74200D01*
G01X2417690Y86700D02*
X2421410D01*
G01X2419550D02*
Y74200D01*
G01X2417690D02*
X2421410D01*
G01X2428850Y86700D02*
Y74200D01*
X2435050D01*
G01X2441250Y86700D02*
Y74200D01*
X2447450D01*
G01X2469150D02*
Y86700D01*
G01X2484340Y74200D02*
Y82533D01*
G01Y81075D02*
X2483720Y81908D01*
X2482790Y82325D01*
X2481705Y82533D01*
X2480620Y82117D01*
X2479690Y81283D01*
X2479070Y80033D01*
X2478760Y78367D01*
X2479070Y76700D01*
X2479690Y75450D01*
X2480620Y74617D01*
X2481705Y74200D01*
X2482790Y74408D01*
X2483720Y75033D01*
X2484340Y75866D01*
G01X2490695Y70450D02*
X2491625Y70033D01*
X2492865Y70450D01*
X2493640Y71283D01*
X2494260Y72325D01*
X2495190Y75658D01*
X2497205Y82533D01*
G01X2492245D02*
X2495190Y75658D01*
G01X2504025Y79825D02*
X2508985D01*
X2508520Y81283D01*
X2507745Y82117D01*
X2506660Y82533D01*
X2505575Y82325D01*
X2504645Y81700D01*
X2504025Y80242D01*
X2503715Y78991D01*
Y77742D01*
X2504025Y76492D01*
X2504800Y75241D01*
X2505730Y74408D01*
X2506815Y74200D01*
X2507900Y74617D01*
X2508985Y75866D01*
G01X2516580Y74200D02*
Y82533D01*
G01Y80867D02*
X2517355Y81700D01*
X2518130Y82325D01*
X2519215Y82533D01*
X2519990Y82325D01*
X2520920Y81700D01*
G01X2542620Y74200D02*
Y84825D01*
X2542930Y85866D01*
X2543550Y86492D01*
X2544480Y86700D01*
X2545410Y86283D01*
X2545875Y85242D01*
G01X2544015Y81700D02*
X2540915D01*
G01X2555950Y74200D02*
X2555020Y74408D01*
X2554090Y75241D01*
X2553470Y76700D01*
X2553160Y78367D01*
X2553470Y80033D01*
X2554090Y81492D01*
X2555020Y82325D01*
X2555950Y82533D01*
X2556880Y82325D01*
X2557810Y81492D01*
X2558430Y80033D01*
X2558585Y78367D01*
X2558430Y76700D01*
X2557810Y75241D01*
X2556880Y74408D01*
X2555950Y74200D01*
G01X2566180D02*
Y82533D01*
G01Y80867D02*
X2566955Y81700D01*
X2567730Y82325D01*
X2568815Y82533D01*
X2569590Y82325D01*
X2570520Y81700D01*
G01X2596250Y74200D02*
X2590050D01*
Y86700D01*
X2596250D01*
G01X2593770Y80658D02*
X2590050D01*
G01X2602450Y86700D02*
Y74200D01*
X2608650D01*
G01X2614850Y86700D02*
Y74200D01*
X2621050D01*
G01X2628490Y86700D02*
X2632210D01*
G01X2630350D02*
Y74200D01*
G01X2628490D02*
X2632210D01*
G01X2639650D02*
Y86700D01*
X2643370D01*
X2644610Y86075D01*
X2645540Y84617D01*
X2645850Y82950D01*
X2645540Y81283D01*
X2644765Y80033D01*
X2643370Y79408D01*
X2639650D01*
G01X2651895Y75866D02*
X2653135Y74825D01*
X2654530Y74200D01*
X2655770D01*
X2657010Y74825D01*
X2657940Y75866D01*
X2658405Y77325D01*
X2658095Y78783D01*
X2657320Y80033D01*
X2655925Y80867D01*
X2654065Y81283D01*
X2652980Y82117D01*
X2652515Y83575D01*
X2652825Y85033D01*
X2653600Y86075D01*
X2654685Y86700D01*
X2655770D01*
X2656855Y86283D01*
X2657785Y85242D01*
G01X2670650Y74200D02*
X2664450D01*
Y86700D01*
X2670650D01*
G01X2668170Y80658D02*
X2664450D01*
G01X2695140Y86700D02*
Y74200D01*
G01Y76075D02*
X2694520Y75033D01*
X2693590Y74408D01*
X2692505Y74200D01*
X2691265Y74617D01*
X2690335Y75658D01*
X2689715Y76908D01*
X2689560Y78367D01*
X2689715Y79825D01*
X2690335Y81075D01*
X2691265Y82117D01*
X2692505Y82533D01*
X2693590Y82325D01*
X2694365Y81908D01*
X2695140Y81075D01*
G01X2702580Y74200D02*
Y82533D01*
G01Y80867D02*
X2703355Y81700D01*
X2704130Y82325D01*
X2705215Y82533D01*
X2705990Y82325D01*
X2706920Y81700D01*
G01X2717150Y82533D02*
Y74200D01*
G01Y85866D02*
X2716840Y86075D01*
Y86492D01*
X2717150Y86700D01*
X2717460Y86492D01*
Y86075D01*
X2717150Y85866D01*
G01X2729550Y74200D02*
Y86700D01*
G01X2741950Y74200D02*
Y86700D01*
G01X2769540D02*
Y74200D01*
G01Y76075D02*
X2768920Y75033D01*
X2767990Y74408D01*
X2766905Y74200D01*
X2765665Y74617D01*
X2764735Y75658D01*
X2764115Y76908D01*
X2763960Y78367D01*
X2764115Y79825D01*
X2764735Y81075D01*
X2765665Y82117D01*
X2766905Y82533D01*
X2767990Y82325D01*
X2768765Y81908D01*
X2769540Y81075D01*
G01X2779150Y82533D02*
Y74200D01*
G01Y85866D02*
X2778840Y86075D01*
Y86492D01*
X2779150Y86700D01*
X2779460Y86492D01*
Y86075D01*
X2779150Y85866D01*
G01X2789380Y74200D02*
Y82533D01*
G01Y80867D02*
X2790155Y81700D01*
X2790930Y82325D01*
X2792015Y82533D01*
X2792790Y82325D01*
X2793720Y81700D01*
G01X2801625Y79825D02*
X2806585D01*
X2806120Y81283D01*
X2805345Y82117D01*
X2804260Y82533D01*
X2803175Y82325D01*
X2802245Y81700D01*
X2801625Y80242D01*
X2801315Y78991D01*
Y77742D01*
X2801625Y76492D01*
X2802400Y75241D01*
X2803330Y74408D01*
X2804415Y74200D01*
X2805500Y74617D01*
X2806585Y75866D01*
G01X2818830Y81492D02*
X2817745Y82325D01*
X2816815Y82533D01*
X2815575Y82117D01*
X2814645Y81283D01*
X2814025Y79825D01*
X2813870Y78367D01*
X2814025Y76908D01*
X2814645Y75658D01*
X2815575Y74617D01*
X2816815Y74200D01*
X2817900Y74617D01*
X2818830Y75450D01*
G01X2828750Y86700D02*
Y74200D01*
G01X2826580Y82533D02*
X2830920D01*
G01X2841150D02*
Y74200D01*
G01Y85866D02*
X2840840Y86075D01*
Y86492D01*
X2841150Y86700D01*
X2841460Y86492D01*
Y86075D01*
X2841150Y85866D01*
G01X2853550Y74200D02*
X2852620Y74408D01*
X2851690Y75241D01*
X2851070Y76700D01*
X2850760Y78367D01*
X2851070Y80033D01*
X2851690Y81492D01*
X2852620Y82325D01*
X2853550Y82533D01*
X2854480Y82325D01*
X2855410Y81492D01*
X2856030Y80033D01*
X2856185Y78367D01*
X2856030Y76700D01*
X2855410Y75241D01*
X2854480Y74408D01*
X2853550Y74200D01*
G01X2863315D02*
Y82533D01*
G01Y80450D02*
X2863935Y81492D01*
X2864865Y82325D01*
X2866105Y82533D01*
X2867190Y82325D01*
X2868120Y81492D01*
X2868585Y80033D01*
Y74200D01*
G01X2216500Y104200D02*
Y1458000D01*
X2700100D01*
Y104200D01*
X2216500D01*
G01Y164800D02*
X2700100D01*
G01X2216500Y225400D02*
X2700100D01*
G01X2216500Y346600D02*
X2700100D01*
G01X2216500Y286000D02*
X2700100D01*
G01X2216500Y467800D02*
X2700100D01*
G01X2216500Y407200D02*
X2700100D01*
G01X2216500Y528400D02*
X2700100D01*
G01X2216500Y649600D02*
X2700100D01*
G01X2216500Y589000D02*
X2700100D01*
G01X2216500Y710200D02*
X2700100D01*
G01X2216500Y831400D02*
X2700100D01*
G01X2216500Y770800D02*
X2700100D01*
G01X2216500Y892000D02*
X2700100D01*
G01X2216500Y1013200D02*
X2700100D01*
G01X2216500Y952600D02*
X2700100D01*
G01X2216500Y1134400D02*
X2700100D01*
G01X2216500Y1073800D02*
X2700100D01*
G01X2216500Y1195000D02*
X2700100D01*
G01X2216500Y1316200D02*
X2700100D01*
G01X2216500Y1255600D02*
X2700100D01*
G01X2227505Y1386150D02*
Y1398650D01*
X2233395D01*
G01X2231225Y1392608D02*
X2227505D01*
G01X2240990Y1398650D02*
X2244710D01*
G01X2242850D02*
Y1386150D01*
G01X2240990D02*
X2244710D01*
G01X2256180Y1392400D02*
X2259280D01*
Y1388650D01*
X2258350Y1387400D01*
X2257265Y1386567D01*
X2255715Y1386150D01*
X2254165Y1386567D01*
X2253080Y1387400D01*
X2252150Y1388650D01*
X2251530Y1390108D01*
X2251220Y1391775D01*
Y1393233D01*
X2251530Y1394483D01*
X2252150Y1395942D01*
X2253080Y1397192D01*
X2254010Y1398025D01*
X2255250Y1398650D01*
X2256335D01*
X2257575Y1398233D01*
X2258505Y1397400D01*
G01X2264240Y1398650D02*
Y1389692D01*
X2264860Y1387816D01*
X2266100Y1386567D01*
X2267650Y1386150D01*
X2269200Y1386567D01*
X2270440Y1387816D01*
X2271060Y1389692D01*
Y1398650D01*
G01X2276950Y1386150D02*
Y1398650D01*
X2280825D01*
X2282065Y1398025D01*
X2282840Y1397192D01*
X2283150Y1395525D01*
X2282840Y1393858D01*
X2281910Y1392817D01*
X2280825Y1392192D01*
X2276950D01*
G01X2280825D02*
X2283150Y1386150D01*
G01X2295550D02*
X2289350D01*
Y1398650D01*
X2295550D01*
G01X2293070Y1392608D02*
X2289350D01*
G01X2216500Y1404900D02*
X2700100D01*
G01X2216500Y1376800D02*
X2700100D01*
G01X2216500Y1433000D02*
X2700100D01*
G01X2376150Y188850D02*
Y201350D01*
X2374290Y198850D01*
G01Y188850D02*
X2378010D01*
G01X2385140Y191350D02*
X2386070Y189891D01*
X2387310Y189058D01*
X2388705Y188850D01*
X2389945Y189058D01*
X2391185Y190100D01*
X2391960Y191350D01*
X2392115Y192600D01*
X2391805Y194058D01*
X2390720Y195100D01*
X2389635Y195517D01*
X2388240D01*
G01X2389635D02*
X2390565Y196142D01*
X2391340Y197183D01*
X2391650Y198433D01*
X2391340Y199683D01*
X2390565Y200725D01*
X2389170Y201350D01*
X2387775Y201142D01*
X2386380Y200308D01*
G01X2400950Y188850D02*
X2402035Y189058D01*
X2403275Y189683D01*
X2404050Y190725D01*
X2404360Y192183D01*
X2404050Y193641D01*
X2403120Y194892D01*
X2401725Y195517D01*
X2400175D01*
X2399245Y195933D01*
X2398470Y196975D01*
X2398160Y198433D01*
X2398625Y199892D01*
X2399710Y200933D01*
X2400950Y201350D01*
X2402190Y200933D01*
X2403275Y199892D01*
X2403740Y198433D01*
X2403430Y196975D01*
X2402655Y195933D01*
X2401725Y195517D01*
X2400175D01*
X2398780Y194892D01*
X2397850Y193641D01*
X2397540Y192183D01*
X2397850Y190725D01*
X2398625Y189683D01*
X2399865Y189058D01*
X2400950Y188850D01*
G01X2413350Y188433D02*
X2413040Y188642D01*
Y189058D01*
X2413350Y189267D01*
X2413660Y189058D01*
Y188642D01*
X2413350Y188433D01*
G01X2425750Y201350D02*
X2424510Y200933D01*
X2423580Y199892D01*
X2422960Y198642D01*
X2422495Y196975D01*
X2422340Y195100D01*
X2422495Y193225D01*
X2422960Y191558D01*
X2423580Y190308D01*
X2424510Y189267D01*
X2425750Y188850D01*
X2426990Y189267D01*
X2427920Y190308D01*
X2428540Y191558D01*
X2429005Y193225D01*
X2429160Y195100D01*
X2429005Y196975D01*
X2428540Y198642D01*
X2427920Y199892D01*
X2426990Y200933D01*
X2425750Y201350D01*
G01X2378010Y128250D02*
Y140750D01*
X2372275Y131792D01*
X2380025D01*
G01X2388550Y140750D02*
X2387310Y140333D01*
X2386380Y139292D01*
X2385760Y138042D01*
X2385295Y136375D01*
X2385140Y134500D01*
X2385295Y132625D01*
X2385760Y130958D01*
X2386380Y129708D01*
X2387310Y128667D01*
X2388550Y128250D01*
X2389790Y128667D01*
X2390720Y129708D01*
X2391340Y130958D01*
X2391805Y132625D01*
X2391960Y134500D01*
X2391805Y136375D01*
X2391340Y138042D01*
X2390720Y139292D01*
X2389790Y140333D01*
X2388550Y140750D01*
G01X2402810Y128250D02*
Y140750D01*
X2397075Y131792D01*
X2404825D01*
G01X2413350Y127833D02*
X2413040Y128042D01*
Y128458D01*
X2413350Y128667D01*
X2413660Y128458D01*
Y128042D01*
X2413350Y127833D01*
G01X2425750Y140750D02*
X2424510Y140333D01*
X2423580Y139292D01*
X2422960Y138042D01*
X2422495Y136375D01*
X2422340Y134500D01*
X2422495Y132625D01*
X2422960Y130958D01*
X2423580Y129708D01*
X2424510Y128667D01*
X2425750Y128250D01*
X2426990Y128667D01*
X2427920Y129708D01*
X2428540Y130958D01*
X2429005Y132625D01*
X2429160Y134500D01*
X2429005Y136375D01*
X2428540Y138042D01*
X2427920Y139292D01*
X2426990Y140333D01*
X2425750Y140750D01*
G01X2306400Y1404900D02*
Y104200D01*
G01X2376150Y249450D02*
Y261950D01*
X2374290Y259450D01*
G01Y249450D02*
X2378010D01*
G01X2385605Y259867D02*
X2386535Y261116D01*
X2387620Y261742D01*
X2388860Y261950D01*
X2390410Y261533D01*
X2391495Y260492D01*
X2391805Y259242D01*
X2391650Y257991D01*
X2391030Y256950D01*
X2387930Y254867D01*
X2386535Y253408D01*
X2385605Y251325D01*
X2385295Y249450D01*
X2391805D01*
G01X2398005Y254658D02*
X2399090Y256117D01*
X2400020Y256950D01*
X2401260Y257367D01*
X2402345Y256950D01*
X2403120Y256117D01*
X2403740Y254867D01*
X2403895Y253408D01*
X2403740Y252158D01*
X2403120Y250908D01*
X2402190Y249867D01*
X2401105Y249450D01*
X2399865Y249867D01*
X2398780Y251116D01*
X2398160Y252992D01*
X2398005Y255075D01*
X2398315Y257783D01*
X2398780Y259242D01*
X2399555Y260700D01*
X2400640Y261742D01*
X2401725Y261950D01*
X2402810Y261533D01*
X2403585Y260492D01*
G01X2413350Y249033D02*
X2413040Y249242D01*
Y249658D01*
X2413350Y249867D01*
X2413660Y249658D01*
Y249242D01*
X2413350Y249033D01*
G01X2425750Y261950D02*
X2424510Y261533D01*
X2423580Y260492D01*
X2422960Y259242D01*
X2422495Y257575D01*
X2422340Y255700D01*
X2422495Y253825D01*
X2422960Y252158D01*
X2423580Y250908D01*
X2424510Y249867D01*
X2425750Y249450D01*
X2426990Y249867D01*
X2427920Y250908D01*
X2428540Y252158D01*
X2429005Y253825D01*
X2429160Y255700D01*
X2429005Y257575D01*
X2428540Y259242D01*
X2427920Y260492D01*
X2426990Y261533D01*
X2425750Y261950D01*
G01X2376150Y370650D02*
Y383150D01*
X2374290Y380650D01*
G01Y370650D02*
X2378010D01*
G01X2388550D02*
Y383150D01*
X2386690Y380650D01*
G01Y370650D02*
X2390410D01*
G01X2400950D02*
Y383150D01*
X2399090Y380650D01*
G01Y370650D02*
X2402810D01*
G01X2413350Y370233D02*
X2413040Y370442D01*
Y370858D01*
X2413350Y371067D01*
X2413660Y370858D01*
Y370442D01*
X2413350Y370233D01*
G01X2425750Y383150D02*
X2424510Y382733D01*
X2423580Y381692D01*
X2422960Y380442D01*
X2422495Y378775D01*
X2422340Y376900D01*
X2422495Y375025D01*
X2422960Y373358D01*
X2423580Y372108D01*
X2424510Y371067D01*
X2425750Y370650D01*
X2426990Y371067D01*
X2427920Y372108D01*
X2428540Y373358D01*
X2429005Y375025D01*
X2429160Y376900D01*
X2429005Y378775D01*
X2428540Y380442D01*
X2427920Y381692D01*
X2426990Y382733D01*
X2425750Y383150D01*
G01X2376150Y310050D02*
Y322550D01*
X2374290Y320050D01*
G01Y310050D02*
X2378010D01*
G01X2388550D02*
Y322550D01*
X2386690Y320050D01*
G01Y310050D02*
X2390410D01*
G01X2398315Y311508D02*
X2399400Y310467D01*
X2400640Y310050D01*
X2401880Y310467D01*
X2402965Y311716D01*
X2403740Y313592D01*
X2404050Y315467D01*
Y317758D01*
X2403740Y319633D01*
X2402965Y321300D01*
X2402035Y322133D01*
X2400950Y322550D01*
X2399710Y322133D01*
X2398780Y321300D01*
X2398160Y320050D01*
X2397850Y318383D01*
X2398160Y316925D01*
X2398935Y315467D01*
X2399865Y314633D01*
X2400950Y314425D01*
X2402190Y314841D01*
X2403120Y315883D01*
X2404050Y317758D01*
G01X2413350Y309633D02*
X2413040Y309842D01*
Y310258D01*
X2413350Y310467D01*
X2413660Y310258D01*
Y309842D01*
X2413350Y309633D01*
G01X2425750Y322550D02*
X2424510Y322133D01*
X2423580Y321092D01*
X2422960Y319842D01*
X2422495Y318175D01*
X2422340Y316300D01*
X2422495Y314425D01*
X2422960Y312758D01*
X2423580Y311508D01*
X2424510Y310467D01*
X2425750Y310050D01*
X2426990Y310467D01*
X2427920Y311508D01*
X2428540Y312758D01*
X2429005Y314425D01*
X2429160Y316300D01*
X2429005Y318175D01*
X2428540Y319842D01*
X2427920Y321092D01*
X2426990Y322133D01*
X2425750Y322550D01*
G01X2379715Y432708D02*
X2380800Y431667D01*
X2382040Y431250D01*
X2383280Y431667D01*
X2384365Y432916D01*
X2385140Y434792D01*
X2385450Y436667D01*
Y438958D01*
X2385140Y440833D01*
X2384365Y442500D01*
X2383435Y443333D01*
X2382350Y443750D01*
X2381110Y443333D01*
X2380180Y442500D01*
X2379560Y441250D01*
X2379250Y439583D01*
X2379560Y438125D01*
X2380335Y436667D01*
X2381265Y435833D01*
X2382350Y435625D01*
X2383590Y436041D01*
X2384520Y437083D01*
X2385450Y438958D01*
G01X2392115Y432708D02*
X2393200Y431667D01*
X2394440Y431250D01*
X2395680Y431667D01*
X2396765Y432916D01*
X2397540Y434792D01*
X2397850Y436667D01*
Y438958D01*
X2397540Y440833D01*
X2396765Y442500D01*
X2395835Y443333D01*
X2394750Y443750D01*
X2393510Y443333D01*
X2392580Y442500D01*
X2391960Y441250D01*
X2391650Y439583D01*
X2391960Y438125D01*
X2392735Y436667D01*
X2393665Y435833D01*
X2394750Y435625D01*
X2395990Y436041D01*
X2396920Y437083D01*
X2397850Y438958D01*
G01X2407150Y430833D02*
X2406840Y431042D01*
Y431458D01*
X2407150Y431667D01*
X2407460Y431458D01*
Y431042D01*
X2407150Y430833D01*
G01X2419550Y443750D02*
X2418310Y443333D01*
X2417380Y442292D01*
X2416760Y441042D01*
X2416295Y439375D01*
X2416140Y437500D01*
X2416295Y435625D01*
X2416760Y433958D01*
X2417380Y432708D01*
X2418310Y431667D01*
X2419550Y431250D01*
X2420790Y431667D01*
X2421720Y432708D01*
X2422340Y433958D01*
X2422805Y435625D01*
X2422960Y437500D01*
X2422805Y439375D01*
X2422340Y441042D01*
X2421720Y442292D01*
X2420790Y443333D01*
X2419550Y443750D01*
G01X2378940Y554325D02*
X2379870Y553283D01*
X2380955Y552658D01*
X2382350Y552450D01*
X2383745Y552867D01*
X2384830Y553700D01*
X2385605Y555158D01*
X2385760Y556825D01*
X2385450Y558492D01*
X2384675Y559533D01*
X2383590Y560367D01*
X2382505Y560575D01*
X2381420Y560367D01*
X2380025Y559533D01*
X2380490Y564950D01*
X2384675D01*
G01X2391340Y554950D02*
X2392270Y553491D01*
X2393510Y552658D01*
X2394905Y552450D01*
X2396145Y552658D01*
X2397385Y553700D01*
X2398160Y554950D01*
X2398315Y556200D01*
X2398005Y557658D01*
X2396920Y558700D01*
X2395835Y559117D01*
X2394440D01*
G01X2395835D02*
X2396765Y559742D01*
X2397540Y560783D01*
X2397850Y562033D01*
X2397540Y563283D01*
X2396765Y564325D01*
X2395370Y564950D01*
X2393975Y564742D01*
X2392580Y563908D01*
G01X2407150Y552033D02*
X2406840Y552242D01*
Y552658D01*
X2407150Y552867D01*
X2407460Y552658D01*
Y552242D01*
X2407150Y552033D01*
G01X2419550Y564950D02*
X2418310Y564533D01*
X2417380Y563492D01*
X2416760Y562242D01*
X2416295Y560575D01*
X2416140Y558700D01*
X2416295Y556825D01*
X2416760Y555158D01*
X2417380Y553908D01*
X2418310Y552867D01*
X2419550Y552450D01*
X2420790Y552867D01*
X2421720Y553908D01*
X2422340Y555158D01*
X2422805Y556825D01*
X2422960Y558700D01*
X2422805Y560575D01*
X2422340Y562242D01*
X2421720Y563492D01*
X2420790Y564533D01*
X2419550Y564950D01*
G01X2382350Y491850D02*
X2383435Y492058D01*
X2384675Y492683D01*
X2385450Y493725D01*
X2385760Y495183D01*
X2385450Y496641D01*
X2384520Y497892D01*
X2383125Y498517D01*
X2381575D01*
X2380645Y498933D01*
X2379870Y499975D01*
X2379560Y501433D01*
X2380025Y502892D01*
X2381110Y503933D01*
X2382350Y504350D01*
X2383590Y503933D01*
X2384675Y502892D01*
X2385140Y501433D01*
X2384830Y499975D01*
X2384055Y498933D01*
X2383125Y498517D01*
X2381575D01*
X2380180Y497892D01*
X2379250Y496641D01*
X2378940Y495183D01*
X2379250Y493725D01*
X2380025Y492683D01*
X2381265Y492058D01*
X2382350Y491850D01*
G01X2391805Y497058D02*
X2392890Y498517D01*
X2393820Y499350D01*
X2395060Y499767D01*
X2396145Y499350D01*
X2396920Y498517D01*
X2397540Y497267D01*
X2397695Y495808D01*
X2397540Y494558D01*
X2396920Y493308D01*
X2395990Y492267D01*
X2394905Y491850D01*
X2393665Y492267D01*
X2392580Y493516D01*
X2391960Y495392D01*
X2391805Y497475D01*
X2392115Y500183D01*
X2392580Y501642D01*
X2393355Y503100D01*
X2394440Y504142D01*
X2395525Y504350D01*
X2396610Y503933D01*
X2397385Y502892D01*
G01X2407150Y491433D02*
X2406840Y491642D01*
Y492058D01*
X2407150Y492267D01*
X2407460Y492058D01*
Y491642D01*
X2407150Y491433D01*
G01X2419550Y504350D02*
X2418310Y503933D01*
X2417380Y502892D01*
X2416760Y501642D01*
X2416295Y499975D01*
X2416140Y498100D01*
X2416295Y496225D01*
X2416760Y494558D01*
X2417380Y493308D01*
X2418310Y492267D01*
X2419550Y491850D01*
X2420790Y492267D01*
X2421720Y493308D01*
X2422340Y494558D01*
X2422805Y496225D01*
X2422960Y498100D01*
X2422805Y499975D01*
X2422340Y501642D01*
X2421720Y502892D01*
X2420790Y503933D01*
X2419550Y504350D01*
G01X2378940Y615550D02*
X2379870Y614091D01*
X2381110Y613258D01*
X2382505Y613050D01*
X2383745Y613258D01*
X2384985Y614300D01*
X2385760Y615550D01*
X2385915Y616800D01*
X2385605Y618258D01*
X2384520Y619300D01*
X2383435Y619717D01*
X2382040D01*
G01X2383435D02*
X2384365Y620342D01*
X2385140Y621383D01*
X2385450Y622633D01*
X2385140Y623883D01*
X2384365Y624925D01*
X2382970Y625550D01*
X2381575Y625342D01*
X2380180Y624508D01*
G01X2394440Y613050D02*
X2394750Y615758D01*
X2395215Y618050D01*
X2395835Y620133D01*
X2396610Y622425D01*
X2397850Y625550D01*
X2391650D01*
G01X2407150Y612633D02*
X2406840Y612842D01*
Y613258D01*
X2407150Y613467D01*
X2407460Y613258D01*
Y612842D01*
X2407150Y612633D01*
G01X2419550Y625550D02*
X2418310Y625133D01*
X2417380Y624092D01*
X2416760Y622842D01*
X2416295Y621175D01*
X2416140Y619300D01*
X2416295Y617425D01*
X2416760Y615758D01*
X2417380Y614508D01*
X2418310Y613467D01*
X2419550Y613050D01*
X2420790Y613467D01*
X2421720Y614508D01*
X2422340Y615758D01*
X2422805Y617425D01*
X2422960Y619300D01*
X2422805Y621175D01*
X2422340Y622842D01*
X2421720Y624092D01*
X2420790Y625133D01*
X2419550Y625550D01*
G01X2382040Y734250D02*
X2382350Y736958D01*
X2382815Y739250D01*
X2383435Y741333D01*
X2384210Y743625D01*
X2385450Y746750D01*
X2379250D01*
G01X2394750Y734250D02*
Y746750D01*
X2392890Y744250D01*
G01Y734250D02*
X2396610D01*
G01X2407150Y733833D02*
X2406840Y734042D01*
Y734458D01*
X2407150Y734667D01*
X2407460Y734458D01*
Y734042D01*
X2407150Y733833D01*
G01X2419550Y746750D02*
X2418310Y746333D01*
X2417380Y745292D01*
X2416760Y744042D01*
X2416295Y742375D01*
X2416140Y740500D01*
X2416295Y738625D01*
X2416760Y736958D01*
X2417380Y735708D01*
X2418310Y734667D01*
X2419550Y734250D01*
X2420790Y734667D01*
X2421720Y735708D01*
X2422340Y736958D01*
X2422805Y738625D01*
X2422960Y740500D01*
X2422805Y742375D01*
X2422340Y744042D01*
X2421720Y745292D01*
X2420790Y746333D01*
X2419550Y746750D01*
G01X2376150Y673650D02*
Y686150D01*
X2374290Y683650D01*
G01Y673650D02*
X2378010D01*
G01X2390410D02*
Y686150D01*
X2384675Y677192D01*
X2392425D01*
G01X2400950Y686150D02*
X2399710Y685733D01*
X2398780Y684692D01*
X2398160Y683442D01*
X2397695Y681775D01*
X2397540Y679900D01*
X2397695Y678025D01*
X2398160Y676358D01*
X2398780Y675108D01*
X2399710Y674067D01*
X2400950Y673650D01*
X2402190Y674067D01*
X2403120Y675108D01*
X2403740Y676358D01*
X2404205Y678025D01*
X2404360Y679900D01*
X2404205Y681775D01*
X2403740Y683442D01*
X2403120Y684692D01*
X2402190Y685733D01*
X2400950Y686150D01*
G01X2413350Y673233D02*
X2413040Y673442D01*
Y673858D01*
X2413350Y674067D01*
X2413660Y673858D01*
Y673442D01*
X2413350Y673233D01*
G01X2425750Y686150D02*
X2424510Y685733D01*
X2423580Y684692D01*
X2422960Y683442D01*
X2422495Y681775D01*
X2422340Y679900D01*
X2422495Y678025D01*
X2422960Y676358D01*
X2423580Y675108D01*
X2424510Y674067D01*
X2425750Y673650D01*
X2426990Y674067D01*
X2427920Y675108D01*
X2428540Y676358D01*
X2429005Y678025D01*
X2429160Y679900D01*
X2429005Y681775D01*
X2428540Y683442D01*
X2427920Y684692D01*
X2426990Y685733D01*
X2425750Y686150D01*
G01X2378940Y857950D02*
X2379870Y856491D01*
X2381110Y855658D01*
X2382505Y855450D01*
X2383745Y855658D01*
X2384985Y856700D01*
X2385760Y857950D01*
X2385915Y859200D01*
X2385605Y860658D01*
X2384520Y861700D01*
X2383435Y862117D01*
X2382040D01*
G01X2383435D02*
X2384365Y862742D01*
X2385140Y863783D01*
X2385450Y865033D01*
X2385140Y866283D01*
X2384365Y867325D01*
X2382970Y867950D01*
X2381575Y867742D01*
X2380180Y866908D01*
G01X2391340Y857325D02*
X2392270Y856283D01*
X2393355Y855658D01*
X2394750Y855450D01*
X2396145Y855867D01*
X2397230Y856700D01*
X2398005Y858158D01*
X2398160Y859825D01*
X2397850Y861492D01*
X2397075Y862533D01*
X2395990Y863367D01*
X2394905Y863575D01*
X2393820Y863367D01*
X2392425Y862533D01*
X2392890Y867950D01*
X2397075D01*
G01X2407150Y855033D02*
X2406840Y855242D01*
Y855658D01*
X2407150Y855867D01*
X2407460Y855658D01*
Y855242D01*
X2407150Y855033D01*
G01X2419550Y867950D02*
X2418310Y867533D01*
X2417380Y866492D01*
X2416760Y865242D01*
X2416295Y863575D01*
X2416140Y861700D01*
X2416295Y859825D01*
X2416760Y858158D01*
X2417380Y856908D01*
X2418310Y855867D01*
X2419550Y855450D01*
X2420790Y855867D01*
X2421720Y856908D01*
X2422340Y858158D01*
X2422805Y859825D01*
X2422960Y861700D01*
X2422805Y863575D01*
X2422340Y865242D01*
X2421720Y866492D01*
X2420790Y867533D01*
X2419550Y867950D01*
G01X2378010Y794850D02*
Y807350D01*
X2372275Y798392D01*
X2380025D01*
G01X2388550Y807350D02*
X2387310Y806933D01*
X2386380Y805892D01*
X2385760Y804642D01*
X2385295Y802975D01*
X2385140Y801100D01*
X2385295Y799225D01*
X2385760Y797558D01*
X2386380Y796308D01*
X2387310Y795267D01*
X2388550Y794850D01*
X2389790Y795267D01*
X2390720Y796308D01*
X2391340Y797558D01*
X2391805Y799225D01*
X2391960Y801100D01*
X2391805Y802975D01*
X2391340Y804642D01*
X2390720Y805892D01*
X2389790Y806933D01*
X2388550Y807350D01*
G01X2400950Y794433D02*
X2400640Y794642D01*
Y795058D01*
X2400950Y795267D01*
X2401260Y795058D01*
Y794642D01*
X2400950Y794433D01*
G01X2413350Y794850D02*
Y807350D01*
X2411490Y804850D01*
G01Y794850D02*
X2415210D01*
G01X2422340Y796725D02*
X2423270Y795683D01*
X2424355Y795058D01*
X2425750Y794850D01*
X2427145Y795267D01*
X2428230Y796100D01*
X2429005Y797558D01*
X2429160Y799225D01*
X2428850Y800892D01*
X2428075Y801933D01*
X2426990Y802767D01*
X2425905Y802975D01*
X2424820Y802767D01*
X2423425Y801933D01*
X2423890Y807350D01*
X2428075D01*
G01X2373205Y926467D02*
X2374135Y927716D01*
X2375220Y928342D01*
X2376460Y928550D01*
X2378010Y928133D01*
X2379095Y927092D01*
X2379405Y925842D01*
X2379250Y924591D01*
X2378630Y923550D01*
X2375530Y921467D01*
X2374135Y920008D01*
X2373205Y917925D01*
X2372895Y916050D01*
X2379405D01*
G01X2385915Y917508D02*
X2387000Y916467D01*
X2388240Y916050D01*
X2389480Y916467D01*
X2390565Y917716D01*
X2391340Y919592D01*
X2391650Y921467D01*
Y923758D01*
X2391340Y925633D01*
X2390565Y927300D01*
X2389635Y928133D01*
X2388550Y928550D01*
X2387310Y928133D01*
X2386380Y927300D01*
X2385760Y926050D01*
X2385450Y924383D01*
X2385760Y922925D01*
X2386535Y921467D01*
X2387465Y920633D01*
X2388550Y920425D01*
X2389790Y920841D01*
X2390720Y921883D01*
X2391650Y923758D01*
G01X2400950Y915633D02*
X2400640Y915842D01*
Y916258D01*
X2400950Y916467D01*
X2401260Y916258D01*
Y915842D01*
X2400950Y915633D01*
G01X2413350Y916050D02*
Y928550D01*
X2411490Y926050D01*
G01Y916050D02*
X2415210D01*
G01X2422340Y918550D02*
X2423270Y917091D01*
X2424510Y916258D01*
X2425905Y916050D01*
X2427145Y916258D01*
X2428385Y917300D01*
X2429160Y918550D01*
X2429315Y919800D01*
X2429005Y921258D01*
X2427920Y922300D01*
X2426835Y922717D01*
X2425440D01*
G01X2426835D02*
X2427765Y923342D01*
X2428540Y924383D01*
X2428850Y925633D01*
X2428540Y926883D01*
X2427765Y927925D01*
X2426370Y928550D01*
X2424975Y928342D01*
X2423580Y927508D01*
G01X2382350Y1037250D02*
Y1049750D01*
X2380490Y1047250D01*
G01Y1037250D02*
X2384210D01*
G01X2391805Y1042458D02*
X2392890Y1043917D01*
X2393820Y1044750D01*
X2395060Y1045167D01*
X2396145Y1044750D01*
X2396920Y1043917D01*
X2397540Y1042667D01*
X2397695Y1041208D01*
X2397540Y1039958D01*
X2396920Y1038708D01*
X2395990Y1037667D01*
X2394905Y1037250D01*
X2393665Y1037667D01*
X2392580Y1038916D01*
X2391960Y1040792D01*
X2391805Y1042875D01*
X2392115Y1045583D01*
X2392580Y1047042D01*
X2393355Y1048500D01*
X2394440Y1049542D01*
X2395525Y1049750D01*
X2396610Y1049333D01*
X2397385Y1048292D01*
G01X2407150Y1036833D02*
X2406840Y1037042D01*
Y1037458D01*
X2407150Y1037667D01*
X2407460Y1037458D01*
Y1037042D01*
X2407150Y1036833D01*
G01X2419550Y1049750D02*
X2418310Y1049333D01*
X2417380Y1048292D01*
X2416760Y1047042D01*
X2416295Y1045375D01*
X2416140Y1043500D01*
X2416295Y1041625D01*
X2416760Y1039958D01*
X2417380Y1038708D01*
X2418310Y1037667D01*
X2419550Y1037250D01*
X2420790Y1037667D01*
X2421720Y1038708D01*
X2422340Y1039958D01*
X2422805Y1041625D01*
X2422960Y1043500D01*
X2422805Y1045375D01*
X2422340Y1047042D01*
X2421720Y1048292D01*
X2420790Y1049333D01*
X2419550Y1049750D01*
G01X2379405Y987067D02*
X2380335Y988316D01*
X2381420Y988942D01*
X2382660Y989150D01*
X2384210Y988733D01*
X2385295Y987692D01*
X2385605Y986442D01*
X2385450Y985191D01*
X2384830Y984150D01*
X2381730Y982067D01*
X2380335Y980608D01*
X2379405Y978525D01*
X2379095Y976650D01*
X2385605D01*
G01X2394750Y989150D02*
X2393510Y988733D01*
X2392580Y987692D01*
X2391960Y986442D01*
X2391495Y984775D01*
X2391340Y982900D01*
X2391495Y981025D01*
X2391960Y979358D01*
X2392580Y978108D01*
X2393510Y977067D01*
X2394750Y976650D01*
X2395990Y977067D01*
X2396920Y978108D01*
X2397540Y979358D01*
X2398005Y981025D01*
X2398160Y982900D01*
X2398005Y984775D01*
X2397540Y986442D01*
X2396920Y987692D01*
X2395990Y988733D01*
X2394750Y989150D01*
G01X2407150Y976233D02*
X2406840Y976442D01*
Y976858D01*
X2407150Y977067D01*
X2407460Y976858D01*
Y976442D01*
X2407150Y976233D01*
G01X2419550Y989150D02*
X2418310Y988733D01*
X2417380Y987692D01*
X2416760Y986442D01*
X2416295Y984775D01*
X2416140Y982900D01*
X2416295Y981025D01*
X2416760Y979358D01*
X2417380Y978108D01*
X2418310Y977067D01*
X2419550Y976650D01*
X2420790Y977067D01*
X2421720Y978108D01*
X2422340Y979358D01*
X2422805Y981025D01*
X2422960Y982900D01*
X2422805Y984775D01*
X2422340Y986442D01*
X2421720Y987692D01*
X2420790Y988733D01*
X2419550Y989150D01*
G01X2376150Y1097850D02*
Y1110350D01*
X2374290Y1107850D01*
G01Y1097850D02*
X2378010D01*
G01X2390410D02*
Y1110350D01*
X2384675Y1101392D01*
X2392425D01*
G01X2400950Y1097433D02*
X2400640Y1097642D01*
Y1098058D01*
X2400950Y1098267D01*
X2401260Y1098058D01*
Y1097642D01*
X2400950Y1097433D01*
G01X2413350Y1097850D02*
Y1110350D01*
X2411490Y1107850D01*
G01Y1097850D02*
X2415210D01*
G01X2425440D02*
X2425750Y1100558D01*
X2426215Y1102850D01*
X2426835Y1104933D01*
X2427610Y1107225D01*
X2428850Y1110350D01*
X2422650D01*
G01X2382350Y1219050D02*
Y1231550D01*
X2380490Y1229050D01*
G01Y1219050D02*
X2384210D01*
G01X2391805Y1229467D02*
X2392735Y1230716D01*
X2393820Y1231342D01*
X2395060Y1231550D01*
X2396610Y1231133D01*
X2397695Y1230092D01*
X2398005Y1228842D01*
X2397850Y1227591D01*
X2397230Y1226550D01*
X2394130Y1224467D01*
X2392735Y1223008D01*
X2391805Y1220925D01*
X2391495Y1219050D01*
X2398005D01*
G01X2407150Y1218633D02*
X2406840Y1218842D01*
Y1219258D01*
X2407150Y1219467D01*
X2407460Y1219258D01*
Y1218842D01*
X2407150Y1218633D01*
G01X2419550Y1231550D02*
X2418310Y1231133D01*
X2417380Y1230092D01*
X2416760Y1228842D01*
X2416295Y1227175D01*
X2416140Y1225300D01*
X2416295Y1223425D01*
X2416760Y1221758D01*
X2417380Y1220508D01*
X2418310Y1219467D01*
X2419550Y1219050D01*
X2420790Y1219467D01*
X2421720Y1220508D01*
X2422340Y1221758D01*
X2422805Y1223425D01*
X2422960Y1225300D01*
X2422805Y1227175D01*
X2422340Y1228842D01*
X2421720Y1230092D01*
X2420790Y1231133D01*
X2419550Y1231550D01*
G01X2382350Y1158450D02*
Y1170950D01*
X2380490Y1168450D01*
G01Y1158450D02*
X2384210D01*
G01X2396610D02*
Y1170950D01*
X2390875Y1161992D01*
X2398625D01*
G01X2407150Y1158033D02*
X2406840Y1158242D01*
Y1158658D01*
X2407150Y1158867D01*
X2407460Y1158658D01*
Y1158242D01*
X2407150Y1158033D01*
G01X2419550Y1170950D02*
X2418310Y1170533D01*
X2417380Y1169492D01*
X2416760Y1168242D01*
X2416295Y1166575D01*
X2416140Y1164700D01*
X2416295Y1162825D01*
X2416760Y1161158D01*
X2417380Y1159908D01*
X2418310Y1158867D01*
X2419550Y1158450D01*
X2420790Y1158867D01*
X2421720Y1159908D01*
X2422340Y1161158D01*
X2422805Y1162825D01*
X2422960Y1164700D01*
X2422805Y1166575D01*
X2422340Y1168242D01*
X2421720Y1169492D01*
X2420790Y1170533D01*
X2419550Y1170950D01*
G01X2382350Y1279650D02*
Y1292150D01*
X2380490Y1289650D01*
G01Y1279650D02*
X2384210D01*
G01X2394750Y1292150D02*
X2393510Y1291733D01*
X2392580Y1290692D01*
X2391960Y1289442D01*
X2391495Y1287775D01*
X2391340Y1285900D01*
X2391495Y1284025D01*
X2391960Y1282358D01*
X2392580Y1281108D01*
X2393510Y1280067D01*
X2394750Y1279650D01*
X2395990Y1280067D01*
X2396920Y1281108D01*
X2397540Y1282358D01*
X2398005Y1284025D01*
X2398160Y1285900D01*
X2398005Y1287775D01*
X2397540Y1289442D01*
X2396920Y1290692D01*
X2395990Y1291733D01*
X2394750Y1292150D01*
G01X2407150Y1279233D02*
X2406840Y1279442D01*
Y1279858D01*
X2407150Y1280067D01*
X2407460Y1279858D01*
Y1279442D01*
X2407150Y1279233D01*
G01X2419550Y1292150D02*
X2418310Y1291733D01*
X2417380Y1290692D01*
X2416760Y1289442D01*
X2416295Y1287775D01*
X2416140Y1285900D01*
X2416295Y1284025D01*
X2416760Y1282358D01*
X2417380Y1281108D01*
X2418310Y1280067D01*
X2419550Y1279650D01*
X2420790Y1280067D01*
X2421720Y1281108D01*
X2422340Y1282358D01*
X2422805Y1284025D01*
X2422960Y1285900D01*
X2422805Y1287775D01*
X2422340Y1289442D01*
X2421720Y1290692D01*
X2420790Y1291733D01*
X2419550Y1292150D01*
G01X2330425Y1414250D02*
X2334300Y1426750D01*
X2338175Y1414250D01*
G01X2336780Y1418625D02*
X2331820D01*
G01X2343600Y1426750D02*
Y1414250D01*
X2349800D01*
G01X2356000Y1426750D02*
Y1414250D01*
X2362200D01*
G01X2380490Y1426750D02*
Y1417792D01*
X2381110Y1415916D01*
X2382350Y1414667D01*
X2383900Y1414250D01*
X2385450Y1414667D01*
X2386690Y1415916D01*
X2387310Y1417792D01*
Y1426750D01*
G01X2392735Y1414250D02*
Y1426750D01*
X2399865Y1414250D01*
Y1426750D01*
G01X2406840D02*
X2410560D01*
G01X2408700D02*
Y1414250D01*
G01X2406840D02*
X2410560D01*
G01X2421100Y1426750D02*
Y1414250D01*
G01X2417535Y1426750D02*
X2424665D01*
G01X2430245Y1415916D02*
X2431485Y1414875D01*
X2432880Y1414250D01*
X2434120D01*
X2435360Y1414875D01*
X2436290Y1415916D01*
X2436755Y1417375D01*
X2436445Y1418833D01*
X2435670Y1420083D01*
X2434275Y1420917D01*
X2432415Y1421333D01*
X2431330Y1422167D01*
X2430865Y1423625D01*
X2431175Y1425083D01*
X2431950Y1426125D01*
X2433035Y1426750D01*
X2434120D01*
X2435205Y1426333D01*
X2436135Y1425292D01*
G01X2454425Y1414250D02*
X2458300Y1426750D01*
X2462175Y1414250D01*
G01X2460780Y1418625D02*
X2455820D01*
G01X2467600Y1414250D02*
Y1426750D01*
X2471475D01*
X2472715Y1426125D01*
X2473490Y1425292D01*
X2473800Y1423625D01*
X2473490Y1421958D01*
X2472560Y1420917D01*
X2471475Y1420292D01*
X2467600D01*
G01X2471475D02*
X2473800Y1414250D01*
G01X2486200D02*
X2480000D01*
Y1426750D01*
X2486200D01*
G01X2483720Y1420708D02*
X2480000D01*
G01X2506040Y1426750D02*
X2509760D01*
G01X2507900D02*
Y1414250D01*
G01X2506040D02*
X2509760D01*
G01X2516735D02*
Y1426750D01*
X2523865Y1414250D01*
Y1426750D01*
G01X2541070Y1414250D02*
Y1426750D01*
X2545100Y1416333D01*
X2549130Y1426750D01*
Y1414250D01*
G01X2555640Y1426750D02*
X2559360D01*
G01X2557500D02*
Y1414250D01*
G01X2555640D02*
X2559360D01*
G01X2566800Y1426750D02*
Y1414250D01*
X2573000D01*
G01X2579045Y1415916D02*
X2580285Y1414875D01*
X2581680Y1414250D01*
X2582920D01*
X2584160Y1414875D01*
X2585090Y1415916D01*
X2585555Y1417375D01*
X2585245Y1418833D01*
X2584470Y1420083D01*
X2583075Y1420917D01*
X2581215Y1421333D01*
X2580130Y1422167D01*
X2579665Y1423625D01*
X2579975Y1425083D01*
X2580750Y1426125D01*
X2581835Y1426750D01*
X2582920D01*
X2584005Y1426333D01*
X2584935Y1425292D01*
G01X2379095Y1387816D02*
X2380335Y1386775D01*
X2381730Y1386150D01*
X2382970D01*
X2384210Y1386775D01*
X2385140Y1387816D01*
X2385605Y1389275D01*
X2385295Y1390733D01*
X2384520Y1391983D01*
X2383125Y1392817D01*
X2381265Y1393233D01*
X2380180Y1394067D01*
X2379715Y1395525D01*
X2380025Y1396983D01*
X2380800Y1398025D01*
X2381885Y1398650D01*
X2382970D01*
X2384055Y1398233D01*
X2384985Y1397192D01*
G01X2392890Y1398650D02*
X2396610D01*
G01X2394750D02*
Y1386150D01*
G01X2392890D02*
X2396610D01*
G01X2404205Y1398650D02*
X2410095D01*
X2404205Y1386150D01*
X2410095D01*
G01X2422650D02*
X2416450D01*
Y1398650D01*
X2422650D01*
G01X2420170Y1392608D02*
X2416450D01*
G01X2366850Y1340250D02*
X2360650D01*
Y1352750D01*
X2366850D01*
G01X2364370Y1346708D02*
X2360650D01*
G01X2373050Y1352750D02*
Y1340250D01*
X2379250D01*
G01X2385450Y1352750D02*
Y1340250D01*
X2391650D01*
G01X2399090Y1352750D02*
X2402810D01*
G01X2400950D02*
Y1340250D01*
G01X2399090D02*
X2402810D01*
G01X2410250D02*
Y1352750D01*
X2413970D01*
X2415210Y1352125D01*
X2416140Y1350667D01*
X2416450Y1349000D01*
X2416140Y1347333D01*
X2415365Y1346083D01*
X2413970Y1345458D01*
X2410250D01*
G01X2422495Y1341916D02*
X2423735Y1340875D01*
X2425130Y1340250D01*
X2426370D01*
X2427610Y1340875D01*
X2428540Y1341916D01*
X2429005Y1343375D01*
X2428695Y1344833D01*
X2427920Y1346083D01*
X2426525Y1346917D01*
X2424665Y1347333D01*
X2423580Y1348167D01*
X2423115Y1349625D01*
X2423425Y1351083D01*
X2424200Y1352125D01*
X2425285Y1352750D01*
X2426370D01*
X2427455Y1352333D01*
X2428385Y1351292D01*
G01X2441250Y1340250D02*
X2435050D01*
Y1352750D01*
X2441250D01*
G01X2438770Y1346708D02*
X2435050D01*
G01X2299890Y1439250D02*
Y1451750D01*
X2302990D01*
X2304230Y1451125D01*
X2305160Y1450292D01*
X2305935Y1449042D01*
X2306555Y1447583D01*
X2306710Y1445500D01*
X2306555Y1443417D01*
X2305935Y1441958D01*
X2305160Y1440708D01*
X2304230Y1439875D01*
X2302990Y1439250D01*
X2299890D01*
G01X2312600D02*
Y1451750D01*
X2316475D01*
X2317715Y1451125D01*
X2318490Y1450292D01*
X2318800Y1448625D01*
X2318490Y1446958D01*
X2317560Y1445917D01*
X2316475Y1445292D01*
X2312600D01*
G01X2316475D02*
X2318800Y1439250D01*
G01X2326240Y1451750D02*
X2329960D01*
G01X2328100D02*
Y1439250D01*
G01X2326240D02*
X2329960D01*
G01X2337400Y1451750D02*
Y1439250D01*
X2343600D01*
G01X2349800Y1451750D02*
Y1439250D01*
X2356000D01*
G01X2381110Y1450708D02*
X2380180Y1451333D01*
X2379095Y1451750D01*
X2377855D01*
X2376460Y1451125D01*
X2375375Y1450083D01*
X2374600Y1448833D01*
X2373980Y1446750D01*
X2373825Y1444875D01*
X2374135Y1443000D01*
X2374600Y1441750D01*
X2375530Y1440500D01*
X2376615Y1439667D01*
X2377700Y1439250D01*
X2378785D01*
X2379870Y1439667D01*
X2380800Y1440291D01*
X2381575Y1441125D01*
G01X2386845Y1439250D02*
Y1451750D01*
G01X2393355D02*
Y1439250D01*
G01Y1445500D02*
X2386845D01*
G01X2398625Y1439250D02*
X2402500Y1451750D01*
X2406375Y1439250D01*
G01X2404980Y1443625D02*
X2400020D01*
G01X2411800Y1439250D02*
Y1451750D01*
X2415675D01*
X2416915Y1451125D01*
X2417690Y1450292D01*
X2418000Y1448625D01*
X2417690Y1446958D01*
X2416760Y1445917D01*
X2415675Y1445292D01*
X2411800D01*
G01X2415675D02*
X2418000Y1439250D01*
G01X2427300Y1451750D02*
Y1439250D01*
G01X2423735Y1451750D02*
X2430865D01*
G01X2439700Y1438833D02*
X2439390Y1439042D01*
Y1439458D01*
X2439700Y1439667D01*
X2440010Y1439458D01*
Y1439042D01*
X2439700Y1438833D01*
G01Y1444458D02*
X2439390Y1444667D01*
Y1445083D01*
X2439700Y1445292D01*
X2440010Y1445083D01*
Y1444667D01*
X2439700Y1444458D01*
G01X2464500Y1451750D02*
Y1439250D01*
G01X2460935Y1451750D02*
X2468065D01*
G01X2476900Y1439250D02*
X2475660Y1439458D01*
X2474575Y1440291D01*
X2473645Y1441542D01*
X2473025Y1443000D01*
X2472715Y1444667D01*
Y1446333D01*
X2473025Y1448000D01*
X2473645Y1449458D01*
X2474575Y1450708D01*
X2475660Y1451542D01*
X2476900Y1451750D01*
X2478140Y1451542D01*
X2479225Y1450708D01*
X2480155Y1449458D01*
X2480775Y1448000D01*
X2481085Y1446333D01*
Y1444667D01*
X2480775Y1443000D01*
X2480155Y1441542D01*
X2479225Y1440291D01*
X2478140Y1439458D01*
X2476900Y1439250D01*
G01X2486200D02*
Y1451750D01*
X2489920D01*
X2491160Y1451125D01*
X2492090Y1449667D01*
X2492400Y1448000D01*
X2492090Y1446333D01*
X2491315Y1445083D01*
X2489920Y1444458D01*
X2486200D01*
G01X2514100Y1451750D02*
Y1439250D01*
G01X2511930Y1447583D02*
X2516270D01*
G01X2526500Y1439250D02*
X2525570Y1439458D01*
X2524640Y1440291D01*
X2524020Y1441750D01*
X2523710Y1443417D01*
X2524020Y1445083D01*
X2524640Y1446542D01*
X2525570Y1447375D01*
X2526500Y1447583D01*
X2527430Y1447375D01*
X2528360Y1446542D01*
X2528980Y1445083D01*
X2529135Y1443417D01*
X2528980Y1441750D01*
X2528360Y1440291D01*
X2527430Y1439458D01*
X2526500Y1439250D01*
G01X2552540Y1445917D02*
X2553160Y1446542D01*
X2553625Y1447583D01*
X2553935Y1449042D01*
X2553625Y1450292D01*
X2553005Y1451125D01*
X2551920Y1451750D01*
X2547735D01*
Y1439250D01*
X2552850D01*
X2553935Y1440083D01*
X2554555Y1441333D01*
X2554865Y1442792D01*
X2554555Y1444250D01*
X2553625Y1445500D01*
X2552540Y1445917D01*
X2547735D01*
G01X2563700Y1439250D02*
X2562460Y1439458D01*
X2561375Y1440291D01*
X2560445Y1441542D01*
X2559825Y1443000D01*
X2559515Y1444667D01*
Y1446333D01*
X2559825Y1448000D01*
X2560445Y1449458D01*
X2561375Y1450708D01*
X2562460Y1451542D01*
X2563700Y1451750D01*
X2564940Y1451542D01*
X2566025Y1450708D01*
X2566955Y1449458D01*
X2567575Y1448000D01*
X2567885Y1446333D01*
Y1444667D01*
X2567575Y1443000D01*
X2566955Y1441542D01*
X2566025Y1440291D01*
X2564940Y1439458D01*
X2563700Y1439250D01*
G01X2576100Y1451750D02*
Y1439250D01*
G01X2572535Y1451750D02*
X2579665D01*
G01X2588500D02*
Y1439250D01*
G01X2584935Y1451750D02*
X2592065D01*
G01X2600900Y1439250D02*
X2599660Y1439458D01*
X2598575Y1440291D01*
X2597645Y1441542D01*
X2597025Y1443000D01*
X2596715Y1444667D01*
Y1446333D01*
X2597025Y1448000D01*
X2597645Y1449458D01*
X2598575Y1450708D01*
X2599660Y1451542D01*
X2600900Y1451750D01*
X2602140Y1451542D01*
X2603225Y1450708D01*
X2604155Y1449458D01*
X2604775Y1448000D01*
X2605085Y1446333D01*
Y1444667D01*
X2604775Y1443000D01*
X2604155Y1441542D01*
X2603225Y1440291D01*
X2602140Y1439458D01*
X2600900Y1439250D01*
G01X2609270D02*
Y1451750D01*
X2613300Y1441333D01*
X2617330Y1451750D01*
Y1439250D01*
G01X2499685Y188850D02*
Y201350D01*
X2506815Y188850D01*
Y201350D01*
G01X2515650Y188850D02*
X2514410Y189058D01*
X2513325Y189891D01*
X2512395Y191142D01*
X2511775Y192600D01*
X2511465Y194267D01*
Y195933D01*
X2511775Y197600D01*
X2512395Y199058D01*
X2513325Y200308D01*
X2514410Y201142D01*
X2515650Y201350D01*
X2516890Y201142D01*
X2517975Y200308D01*
X2518905Y199058D01*
X2519525Y197600D01*
X2519835Y195933D01*
Y194267D01*
X2519525Y192600D01*
X2518905Y191142D01*
X2517975Y189891D01*
X2516890Y189058D01*
X2515650Y188850D01*
G01X2524485D02*
Y201350D01*
X2531615Y188850D01*
Y201350D01*
G01X2538435Y193017D02*
X2542465D01*
G01X2549750Y188850D02*
Y201350D01*
X2553470D01*
X2554710Y200725D01*
X2555640Y199267D01*
X2555950Y197600D01*
X2555640Y195933D01*
X2554865Y194683D01*
X2553470Y194058D01*
X2549750D01*
G01X2562150Y201350D02*
Y188850D01*
X2568350D01*
G01X2573775D02*
X2577650Y201350D01*
X2581525Y188850D01*
G01X2580130Y193225D02*
X2575170D01*
G01X2590050Y201350D02*
Y188850D01*
G01X2586485Y201350D02*
X2593615D01*
G01X2605550Y188850D02*
X2599350D01*
Y201350D01*
X2605550D01*
G01X2603070Y195308D02*
X2599350D01*
G01X2611440Y188850D02*
Y201350D01*
X2614540D01*
X2615780Y200725D01*
X2616710Y199892D01*
X2617485Y198642D01*
X2618105Y197183D01*
X2618260Y195100D01*
X2618105Y193017D01*
X2617485Y191558D01*
X2616710Y190308D01*
X2615780Y189475D01*
X2614540Y188850D01*
X2611440D01*
G01X2499685Y128250D02*
Y140750D01*
X2506815Y128250D01*
Y140750D01*
G01X2515650Y128250D02*
X2514410Y128458D01*
X2513325Y129291D01*
X2512395Y130542D01*
X2511775Y132000D01*
X2511465Y133667D01*
Y135333D01*
X2511775Y137000D01*
X2512395Y138458D01*
X2513325Y139708D01*
X2514410Y140542D01*
X2515650Y140750D01*
X2516890Y140542D01*
X2517975Y139708D01*
X2518905Y138458D01*
X2519525Y137000D01*
X2519835Y135333D01*
Y133667D01*
X2519525Y132000D01*
X2518905Y130542D01*
X2517975Y129291D01*
X2516890Y128458D01*
X2515650Y128250D01*
G01X2524485D02*
Y140750D01*
X2531615Y128250D01*
Y140750D01*
G01X2538435Y132417D02*
X2542465D01*
G01X2549750Y128250D02*
Y140750D01*
X2553470D01*
X2554710Y140125D01*
X2555640Y138667D01*
X2555950Y137000D01*
X2555640Y135333D01*
X2554865Y134083D01*
X2553470Y133458D01*
X2549750D01*
G01X2562150Y140750D02*
Y128250D01*
X2568350D01*
G01X2573775D02*
X2577650Y140750D01*
X2581525Y128250D01*
G01X2580130Y132625D02*
X2575170D01*
G01X2590050Y140750D02*
Y128250D01*
G01X2586485Y140750D02*
X2593615D01*
G01X2605550Y128250D02*
X2599350D01*
Y140750D01*
X2605550D01*
G01X2603070Y134708D02*
X2599350D01*
G01X2611440Y128250D02*
Y140750D01*
X2614540D01*
X2615780Y140125D01*
X2616710Y139292D01*
X2617485Y138042D01*
X2618105Y136583D01*
X2618260Y134500D01*
X2618105Y132417D01*
X2617485Y130958D01*
X2616710Y129708D01*
X2615780Y128875D01*
X2614540Y128250D01*
X2611440D01*
G01X2495500Y1404900D02*
Y104200D01*
G01X2499685Y249450D02*
Y261950D01*
X2506815Y249450D01*
Y261950D01*
G01X2515650Y249450D02*
X2514410Y249658D01*
X2513325Y250491D01*
X2512395Y251742D01*
X2511775Y253200D01*
X2511465Y254867D01*
Y256533D01*
X2511775Y258200D01*
X2512395Y259658D01*
X2513325Y260908D01*
X2514410Y261742D01*
X2515650Y261950D01*
X2516890Y261742D01*
X2517975Y260908D01*
X2518905Y259658D01*
X2519525Y258200D01*
X2519835Y256533D01*
Y254867D01*
X2519525Y253200D01*
X2518905Y251742D01*
X2517975Y250491D01*
X2516890Y249658D01*
X2515650Y249450D01*
G01X2524485D02*
Y261950D01*
X2531615Y249450D01*
Y261950D01*
G01X2538435Y253617D02*
X2542465D01*
G01X2549750Y249450D02*
Y261950D01*
X2553470D01*
X2554710Y261325D01*
X2555640Y259867D01*
X2555950Y258200D01*
X2555640Y256533D01*
X2554865Y255283D01*
X2553470Y254658D01*
X2549750D01*
G01X2562150Y261950D02*
Y249450D01*
X2568350D01*
G01X2573775D02*
X2577650Y261950D01*
X2581525Y249450D01*
G01X2580130Y253825D02*
X2575170D01*
G01X2590050Y261950D02*
Y249450D01*
G01X2586485Y261950D02*
X2593615D01*
G01X2605550Y249450D02*
X2599350D01*
Y261950D01*
X2605550D01*
G01X2603070Y255908D02*
X2599350D01*
G01X2611440Y249450D02*
Y261950D01*
X2614540D01*
X2615780Y261325D01*
X2616710Y260492D01*
X2617485Y259242D01*
X2618105Y257783D01*
X2618260Y255700D01*
X2618105Y253617D01*
X2617485Y252158D01*
X2616710Y250908D01*
X2615780Y250075D01*
X2614540Y249450D01*
X2611440D01*
G01X2499685Y370650D02*
Y383150D01*
X2506815Y370650D01*
Y383150D01*
G01X2515650Y370650D02*
X2514410Y370858D01*
X2513325Y371691D01*
X2512395Y372942D01*
X2511775Y374400D01*
X2511465Y376067D01*
Y377733D01*
X2511775Y379400D01*
X2512395Y380858D01*
X2513325Y382108D01*
X2514410Y382942D01*
X2515650Y383150D01*
X2516890Y382942D01*
X2517975Y382108D01*
X2518905Y380858D01*
X2519525Y379400D01*
X2519835Y377733D01*
Y376067D01*
X2519525Y374400D01*
X2518905Y372942D01*
X2517975Y371691D01*
X2516890Y370858D01*
X2515650Y370650D01*
G01X2524485D02*
Y383150D01*
X2531615Y370650D01*
Y383150D01*
G01X2538435Y374817D02*
X2542465D01*
G01X2549750Y370650D02*
Y383150D01*
X2553470D01*
X2554710Y382525D01*
X2555640Y381067D01*
X2555950Y379400D01*
X2555640Y377733D01*
X2554865Y376483D01*
X2553470Y375858D01*
X2549750D01*
G01X2562150Y383150D02*
Y370650D01*
X2568350D01*
G01X2573775D02*
X2577650Y383150D01*
X2581525Y370650D01*
G01X2580130Y375025D02*
X2575170D01*
G01X2590050Y383150D02*
Y370650D01*
G01X2586485Y383150D02*
X2593615D01*
G01X2605550Y370650D02*
X2599350D01*
Y383150D01*
X2605550D01*
G01X2603070Y377108D02*
X2599350D01*
G01X2611440Y370650D02*
Y383150D01*
X2614540D01*
X2615780Y382525D01*
X2616710Y381692D01*
X2617485Y380442D01*
X2618105Y378983D01*
X2618260Y376900D01*
X2618105Y374817D01*
X2617485Y373358D01*
X2616710Y372108D01*
X2615780Y371275D01*
X2614540Y370650D01*
X2611440D01*
G01X2499685Y310050D02*
Y322550D01*
X2506815Y310050D01*
Y322550D01*
G01X2515650Y310050D02*
X2514410Y310258D01*
X2513325Y311091D01*
X2512395Y312342D01*
X2511775Y313800D01*
X2511465Y315467D01*
Y317133D01*
X2511775Y318800D01*
X2512395Y320258D01*
X2513325Y321508D01*
X2514410Y322342D01*
X2515650Y322550D01*
X2516890Y322342D01*
X2517975Y321508D01*
X2518905Y320258D01*
X2519525Y318800D01*
X2519835Y317133D01*
Y315467D01*
X2519525Y313800D01*
X2518905Y312342D01*
X2517975Y311091D01*
X2516890Y310258D01*
X2515650Y310050D01*
G01X2524485D02*
Y322550D01*
X2531615Y310050D01*
Y322550D01*
G01X2538435Y314217D02*
X2542465D01*
G01X2549750Y310050D02*
Y322550D01*
X2553470D01*
X2554710Y321925D01*
X2555640Y320467D01*
X2555950Y318800D01*
X2555640Y317133D01*
X2554865Y315883D01*
X2553470Y315258D01*
X2549750D01*
G01X2562150Y322550D02*
Y310050D01*
X2568350D01*
G01X2573775D02*
X2577650Y322550D01*
X2581525Y310050D01*
G01X2580130Y314425D02*
X2575170D01*
G01X2590050Y322550D02*
Y310050D01*
G01X2586485Y322550D02*
X2593615D01*
G01X2605550Y310050D02*
X2599350D01*
Y322550D01*
X2605550D01*
G01X2603070Y316508D02*
X2599350D01*
G01X2611440Y310050D02*
Y322550D01*
X2614540D01*
X2615780Y321925D01*
X2616710Y321092D01*
X2617485Y319842D01*
X2618105Y318383D01*
X2618260Y316300D01*
X2618105Y314217D01*
X2617485Y312758D01*
X2616710Y311508D01*
X2615780Y310675D01*
X2614540Y310050D01*
X2611440D01*
G01X2499685Y431250D02*
Y443750D01*
X2506815Y431250D01*
Y443750D01*
G01X2515650Y431250D02*
X2514410Y431458D01*
X2513325Y432291D01*
X2512395Y433542D01*
X2511775Y435000D01*
X2511465Y436667D01*
Y438333D01*
X2511775Y440000D01*
X2512395Y441458D01*
X2513325Y442708D01*
X2514410Y443542D01*
X2515650Y443750D01*
X2516890Y443542D01*
X2517975Y442708D01*
X2518905Y441458D01*
X2519525Y440000D01*
X2519835Y438333D01*
Y436667D01*
X2519525Y435000D01*
X2518905Y433542D01*
X2517975Y432291D01*
X2516890Y431458D01*
X2515650Y431250D01*
G01X2524485D02*
Y443750D01*
X2531615Y431250D01*
Y443750D01*
G01X2538435Y435417D02*
X2542465D01*
G01X2549750Y431250D02*
Y443750D01*
X2553470D01*
X2554710Y443125D01*
X2555640Y441667D01*
X2555950Y440000D01*
X2555640Y438333D01*
X2554865Y437083D01*
X2553470Y436458D01*
X2549750D01*
G01X2562150Y443750D02*
Y431250D01*
X2568350D01*
G01X2573775D02*
X2577650Y443750D01*
X2581525Y431250D01*
G01X2580130Y435625D02*
X2575170D01*
G01X2590050Y443750D02*
Y431250D01*
G01X2586485Y443750D02*
X2593615D01*
G01X2605550Y431250D02*
X2599350D01*
Y443750D01*
X2605550D01*
G01X2603070Y437708D02*
X2599350D01*
G01X2611440Y431250D02*
Y443750D01*
X2614540D01*
X2615780Y443125D01*
X2616710Y442292D01*
X2617485Y441042D01*
X2618105Y439583D01*
X2618260Y437500D01*
X2618105Y435417D01*
X2617485Y433958D01*
X2616710Y432708D01*
X2615780Y431875D01*
X2614540Y431250D01*
X2611440D01*
G01X2499685Y552450D02*
Y564950D01*
X2506815Y552450D01*
Y564950D01*
G01X2515650Y552450D02*
X2514410Y552658D01*
X2513325Y553491D01*
X2512395Y554742D01*
X2511775Y556200D01*
X2511465Y557867D01*
Y559533D01*
X2511775Y561200D01*
X2512395Y562658D01*
X2513325Y563908D01*
X2514410Y564742D01*
X2515650Y564950D01*
X2516890Y564742D01*
X2517975Y563908D01*
X2518905Y562658D01*
X2519525Y561200D01*
X2519835Y559533D01*
Y557867D01*
X2519525Y556200D01*
X2518905Y554742D01*
X2517975Y553491D01*
X2516890Y552658D01*
X2515650Y552450D01*
G01X2524485D02*
Y564950D01*
X2531615Y552450D01*
Y564950D01*
G01X2538435Y556617D02*
X2542465D01*
G01X2549750Y552450D02*
Y564950D01*
X2553470D01*
X2554710Y564325D01*
X2555640Y562867D01*
X2555950Y561200D01*
X2555640Y559533D01*
X2554865Y558283D01*
X2553470Y557658D01*
X2549750D01*
G01X2562150Y564950D02*
Y552450D01*
X2568350D01*
G01X2573775D02*
X2577650Y564950D01*
X2581525Y552450D01*
G01X2580130Y556825D02*
X2575170D01*
G01X2590050Y564950D02*
Y552450D01*
G01X2586485Y564950D02*
X2593615D01*
G01X2605550Y552450D02*
X2599350D01*
Y564950D01*
X2605550D01*
G01X2603070Y558908D02*
X2599350D01*
G01X2611440Y552450D02*
Y564950D01*
X2614540D01*
X2615780Y564325D01*
X2616710Y563492D01*
X2617485Y562242D01*
X2618105Y560783D01*
X2618260Y558700D01*
X2618105Y556617D01*
X2617485Y555158D01*
X2616710Y553908D01*
X2615780Y553075D01*
X2614540Y552450D01*
X2611440D01*
G01X2499685Y491850D02*
Y504350D01*
X2506815Y491850D01*
Y504350D01*
G01X2515650Y491850D02*
X2514410Y492058D01*
X2513325Y492891D01*
X2512395Y494142D01*
X2511775Y495600D01*
X2511465Y497267D01*
Y498933D01*
X2511775Y500600D01*
X2512395Y502058D01*
X2513325Y503308D01*
X2514410Y504142D01*
X2515650Y504350D01*
X2516890Y504142D01*
X2517975Y503308D01*
X2518905Y502058D01*
X2519525Y500600D01*
X2519835Y498933D01*
Y497267D01*
X2519525Y495600D01*
X2518905Y494142D01*
X2517975Y492891D01*
X2516890Y492058D01*
X2515650Y491850D01*
G01X2524485D02*
Y504350D01*
X2531615Y491850D01*
Y504350D01*
G01X2538435Y496017D02*
X2542465D01*
G01X2549750Y491850D02*
Y504350D01*
X2553470D01*
X2554710Y503725D01*
X2555640Y502267D01*
X2555950Y500600D01*
X2555640Y498933D01*
X2554865Y497683D01*
X2553470Y497058D01*
X2549750D01*
G01X2562150Y504350D02*
Y491850D01*
X2568350D01*
G01X2573775D02*
X2577650Y504350D01*
X2581525Y491850D01*
G01X2580130Y496225D02*
X2575170D01*
G01X2590050Y504350D02*
Y491850D01*
G01X2586485Y504350D02*
X2593615D01*
G01X2605550Y491850D02*
X2599350D01*
Y504350D01*
X2605550D01*
G01X2603070Y498308D02*
X2599350D01*
G01X2611440Y491850D02*
Y504350D01*
X2614540D01*
X2615780Y503725D01*
X2616710Y502892D01*
X2617485Y501642D01*
X2618105Y500183D01*
X2618260Y498100D01*
X2618105Y496017D01*
X2617485Y494558D01*
X2616710Y493308D01*
X2615780Y492475D01*
X2614540Y491850D01*
X2611440D01*
G01X2499685Y613050D02*
Y625550D01*
X2506815Y613050D01*
Y625550D01*
G01X2515650Y613050D02*
X2514410Y613258D01*
X2513325Y614091D01*
X2512395Y615342D01*
X2511775Y616800D01*
X2511465Y618467D01*
Y620133D01*
X2511775Y621800D01*
X2512395Y623258D01*
X2513325Y624508D01*
X2514410Y625342D01*
X2515650Y625550D01*
X2516890Y625342D01*
X2517975Y624508D01*
X2518905Y623258D01*
X2519525Y621800D01*
X2519835Y620133D01*
Y618467D01*
X2519525Y616800D01*
X2518905Y615342D01*
X2517975Y614091D01*
X2516890Y613258D01*
X2515650Y613050D01*
G01X2524485D02*
Y625550D01*
X2531615Y613050D01*
Y625550D01*
G01X2538435Y617217D02*
X2542465D01*
G01X2549750Y613050D02*
Y625550D01*
X2553470D01*
X2554710Y624925D01*
X2555640Y623467D01*
X2555950Y621800D01*
X2555640Y620133D01*
X2554865Y618883D01*
X2553470Y618258D01*
X2549750D01*
G01X2562150Y625550D02*
Y613050D01*
X2568350D01*
G01X2573775D02*
X2577650Y625550D01*
X2581525Y613050D01*
G01X2580130Y617425D02*
X2575170D01*
G01X2590050Y625550D02*
Y613050D01*
G01X2586485Y625550D02*
X2593615D01*
G01X2605550Y613050D02*
X2599350D01*
Y625550D01*
X2605550D01*
G01X2603070Y619508D02*
X2599350D01*
G01X2611440Y613050D02*
Y625550D01*
X2614540D01*
X2615780Y624925D01*
X2616710Y624092D01*
X2617485Y622842D01*
X2618105Y621383D01*
X2618260Y619300D01*
X2618105Y617217D01*
X2617485Y615758D01*
X2616710Y614508D01*
X2615780Y613675D01*
X2614540Y613050D01*
X2611440D01*
G01X2524950Y734250D02*
Y746750D01*
X2528670D01*
X2529910Y746125D01*
X2530840Y744667D01*
X2531150Y743000D01*
X2530840Y741333D01*
X2530065Y740083D01*
X2528670Y739458D01*
X2524950D01*
G01X2537350Y746750D02*
Y734250D01*
X2543550D01*
G01X2548975D02*
X2552850Y746750D01*
X2556725Y734250D01*
G01X2555330Y738625D02*
X2550370D01*
G01X2565250Y746750D02*
Y734250D01*
G01X2561685Y746750D02*
X2568815D01*
G01X2580750Y734250D02*
X2574550D01*
Y746750D01*
X2580750D01*
G01X2578270Y740708D02*
X2574550D01*
G01X2586640Y734250D02*
Y746750D01*
X2589740D01*
X2590980Y746125D01*
X2591910Y745292D01*
X2592685Y744042D01*
X2593305Y742583D01*
X2593460Y740500D01*
X2593305Y738417D01*
X2592685Y736958D01*
X2591910Y735708D01*
X2590980Y734875D01*
X2589740Y734250D01*
X2586640D01*
G01X2524950Y673650D02*
Y686150D01*
X2528670D01*
X2529910Y685525D01*
X2530840Y684067D01*
X2531150Y682400D01*
X2530840Y680733D01*
X2530065Y679483D01*
X2528670Y678858D01*
X2524950D01*
G01X2537350Y686150D02*
Y673650D01*
X2543550D01*
G01X2548975D02*
X2552850Y686150D01*
X2556725Y673650D01*
G01X2555330Y678025D02*
X2550370D01*
G01X2565250Y686150D02*
Y673650D01*
G01X2561685Y686150D02*
X2568815D01*
G01X2580750Y673650D02*
X2574550D01*
Y686150D01*
X2580750D01*
G01X2578270Y680108D02*
X2574550D01*
G01X2586640Y673650D02*
Y686150D01*
X2589740D01*
X2590980Y685525D01*
X2591910Y684692D01*
X2592685Y683442D01*
X2593305Y681983D01*
X2593460Y679900D01*
X2593305Y677817D01*
X2592685Y676358D01*
X2591910Y675108D01*
X2590980Y674275D01*
X2589740Y673650D01*
X2586640D01*
G01X2524950Y855450D02*
Y867950D01*
X2528670D01*
X2529910Y867325D01*
X2530840Y865867D01*
X2531150Y864200D01*
X2530840Y862533D01*
X2530065Y861283D01*
X2528670Y860658D01*
X2524950D01*
G01X2537350Y867950D02*
Y855450D01*
X2543550D01*
G01X2548975D02*
X2552850Y867950D01*
X2556725Y855450D01*
G01X2555330Y859825D02*
X2550370D01*
G01X2565250Y867950D02*
Y855450D01*
G01X2561685Y867950D02*
X2568815D01*
G01X2580750Y855450D02*
X2574550D01*
Y867950D01*
X2580750D01*
G01X2578270Y861908D02*
X2574550D01*
G01X2586640Y855450D02*
Y867950D01*
X2589740D01*
X2590980Y867325D01*
X2591910Y866492D01*
X2592685Y865242D01*
X2593305Y863783D01*
X2593460Y861700D01*
X2593305Y859617D01*
X2592685Y858158D01*
X2591910Y856908D01*
X2590980Y856075D01*
X2589740Y855450D01*
X2586640D01*
G01X2524950Y794850D02*
Y807350D01*
X2528670D01*
X2529910Y806725D01*
X2530840Y805267D01*
X2531150Y803600D01*
X2530840Y801933D01*
X2530065Y800683D01*
X2528670Y800058D01*
X2524950D01*
G01X2537350Y807350D02*
Y794850D01*
X2543550D01*
G01X2548975D02*
X2552850Y807350D01*
X2556725Y794850D01*
G01X2555330Y799225D02*
X2550370D01*
G01X2565250Y807350D02*
Y794850D01*
G01X2561685Y807350D02*
X2568815D01*
G01X2580750Y794850D02*
X2574550D01*
Y807350D01*
X2580750D01*
G01X2578270Y801308D02*
X2574550D01*
G01X2586640Y794850D02*
Y807350D01*
X2589740D01*
X2590980Y806725D01*
X2591910Y805892D01*
X2592685Y804642D01*
X2593305Y803183D01*
X2593460Y801100D01*
X2593305Y799017D01*
X2592685Y797558D01*
X2591910Y796308D01*
X2590980Y795475D01*
X2589740Y794850D01*
X2586640D01*
G01X2524950Y916050D02*
Y928550D01*
X2528670D01*
X2529910Y927925D01*
X2530840Y926467D01*
X2531150Y924800D01*
X2530840Y923133D01*
X2530065Y921883D01*
X2528670Y921258D01*
X2524950D01*
G01X2537350Y928550D02*
Y916050D01*
X2543550D01*
G01X2548975D02*
X2552850Y928550D01*
X2556725Y916050D01*
G01X2555330Y920425D02*
X2550370D01*
G01X2565250Y928550D02*
Y916050D01*
G01X2561685Y928550D02*
X2568815D01*
G01X2580750Y916050D02*
X2574550D01*
Y928550D01*
X2580750D01*
G01X2578270Y922508D02*
X2574550D01*
G01X2586640Y916050D02*
Y928550D01*
X2589740D01*
X2590980Y927925D01*
X2591910Y927092D01*
X2592685Y925842D01*
X2593305Y924383D01*
X2593460Y922300D01*
X2593305Y920217D01*
X2592685Y918758D01*
X2591910Y917508D01*
X2590980Y916675D01*
X2589740Y916050D01*
X2586640D01*
G01X2524950Y1037250D02*
Y1049750D01*
X2528670D01*
X2529910Y1049125D01*
X2530840Y1047667D01*
X2531150Y1046000D01*
X2530840Y1044333D01*
X2530065Y1043083D01*
X2528670Y1042458D01*
X2524950D01*
G01X2537350Y1049750D02*
Y1037250D01*
X2543550D01*
G01X2548975D02*
X2552850Y1049750D01*
X2556725Y1037250D01*
G01X2555330Y1041625D02*
X2550370D01*
G01X2565250Y1049750D02*
Y1037250D01*
G01X2561685Y1049750D02*
X2568815D01*
G01X2580750Y1037250D02*
X2574550D01*
Y1049750D01*
X2580750D01*
G01X2578270Y1043708D02*
X2574550D01*
G01X2586640Y1037250D02*
Y1049750D01*
X2589740D01*
X2590980Y1049125D01*
X2591910Y1048292D01*
X2592685Y1047042D01*
X2593305Y1045583D01*
X2593460Y1043500D01*
X2593305Y1041417D01*
X2592685Y1039958D01*
X2591910Y1038708D01*
X2590980Y1037875D01*
X2589740Y1037250D01*
X2586640D01*
G01X2524950Y976650D02*
Y989150D01*
X2528670D01*
X2529910Y988525D01*
X2530840Y987067D01*
X2531150Y985400D01*
X2530840Y983733D01*
X2530065Y982483D01*
X2528670Y981858D01*
X2524950D01*
G01X2537350Y989150D02*
Y976650D01*
X2543550D01*
G01X2548975D02*
X2552850Y989150D01*
X2556725Y976650D01*
G01X2555330Y981025D02*
X2550370D01*
G01X2565250Y989150D02*
Y976650D01*
G01X2561685Y989150D02*
X2568815D01*
G01X2580750Y976650D02*
X2574550D01*
Y989150D01*
X2580750D01*
G01X2578270Y983108D02*
X2574550D01*
G01X2586640Y976650D02*
Y989150D01*
X2589740D01*
X2590980Y988525D01*
X2591910Y987692D01*
X2592685Y986442D01*
X2593305Y984983D01*
X2593460Y982900D01*
X2593305Y980817D01*
X2592685Y979358D01*
X2591910Y978108D01*
X2590980Y977275D01*
X2589740Y976650D01*
X2586640D01*
G01X2524950Y1097850D02*
Y1110350D01*
X2528670D01*
X2529910Y1109725D01*
X2530840Y1108267D01*
X2531150Y1106600D01*
X2530840Y1104933D01*
X2530065Y1103683D01*
X2528670Y1103058D01*
X2524950D01*
G01X2537350Y1110350D02*
Y1097850D01*
X2543550D01*
G01X2548975D02*
X2552850Y1110350D01*
X2556725Y1097850D01*
G01X2555330Y1102225D02*
X2550370D01*
G01X2565250Y1110350D02*
Y1097850D01*
G01X2561685Y1110350D02*
X2568815D01*
G01X2580750Y1097850D02*
X2574550D01*
Y1110350D01*
X2580750D01*
G01X2578270Y1104308D02*
X2574550D01*
G01X2586640Y1097850D02*
Y1110350D01*
X2589740D01*
X2590980Y1109725D01*
X2591910Y1108892D01*
X2592685Y1107642D01*
X2593305Y1106183D01*
X2593460Y1104100D01*
X2593305Y1102017D01*
X2592685Y1100558D01*
X2591910Y1099308D01*
X2590980Y1098475D01*
X2589740Y1097850D01*
X2586640D01*
G01X2524950Y1219050D02*
Y1231550D01*
X2528670D01*
X2529910Y1230925D01*
X2530840Y1229467D01*
X2531150Y1227800D01*
X2530840Y1226133D01*
X2530065Y1224883D01*
X2528670Y1224258D01*
X2524950D01*
G01X2537350Y1231550D02*
Y1219050D01*
X2543550D01*
G01X2548975D02*
X2552850Y1231550D01*
X2556725Y1219050D01*
G01X2555330Y1223425D02*
X2550370D01*
G01X2565250Y1231550D02*
Y1219050D01*
G01X2561685Y1231550D02*
X2568815D01*
G01X2580750Y1219050D02*
X2574550D01*
Y1231550D01*
X2580750D01*
G01X2578270Y1225508D02*
X2574550D01*
G01X2586640Y1219050D02*
Y1231550D01*
X2589740D01*
X2590980Y1230925D01*
X2591910Y1230092D01*
X2592685Y1228842D01*
X2593305Y1227383D01*
X2593460Y1225300D01*
X2593305Y1223217D01*
X2592685Y1221758D01*
X2591910Y1220508D01*
X2590980Y1219675D01*
X2589740Y1219050D01*
X2586640D01*
G01X2524950Y1158450D02*
Y1170950D01*
X2528670D01*
X2529910Y1170325D01*
X2530840Y1168867D01*
X2531150Y1167200D01*
X2530840Y1165533D01*
X2530065Y1164283D01*
X2528670Y1163658D01*
X2524950D01*
G01X2537350Y1170950D02*
Y1158450D01*
X2543550D01*
G01X2548975D02*
X2552850Y1170950D01*
X2556725Y1158450D01*
G01X2555330Y1162825D02*
X2550370D01*
G01X2565250Y1170950D02*
Y1158450D01*
G01X2561685Y1170950D02*
X2568815D01*
G01X2580750Y1158450D02*
X2574550D01*
Y1170950D01*
X2580750D01*
G01X2578270Y1164908D02*
X2574550D01*
G01X2586640Y1158450D02*
Y1170950D01*
X2589740D01*
X2590980Y1170325D01*
X2591910Y1169492D01*
X2592685Y1168242D01*
X2593305Y1166783D01*
X2593460Y1164700D01*
X2593305Y1162617D01*
X2592685Y1161158D01*
X2591910Y1159908D01*
X2590980Y1159075D01*
X2589740Y1158450D01*
X2586640D01*
G01X2524950Y1279650D02*
Y1292150D01*
X2528670D01*
X2529910Y1291525D01*
X2530840Y1290067D01*
X2531150Y1288400D01*
X2530840Y1286733D01*
X2530065Y1285483D01*
X2528670Y1284858D01*
X2524950D01*
G01X2537350Y1292150D02*
Y1279650D01*
X2543550D01*
G01X2548975D02*
X2552850Y1292150D01*
X2556725Y1279650D01*
G01X2555330Y1284025D02*
X2550370D01*
G01X2565250Y1292150D02*
Y1279650D01*
G01X2561685Y1292150D02*
X2568815D01*
G01X2580750Y1279650D02*
X2574550D01*
Y1292150D01*
X2580750D01*
G01X2578270Y1286108D02*
X2574550D01*
G01X2586640Y1279650D02*
Y1292150D01*
X2589740D01*
X2590980Y1291525D01*
X2591910Y1290692D01*
X2592685Y1289442D01*
X2593305Y1287983D01*
X2593460Y1285900D01*
X2593305Y1283817D01*
X2592685Y1282358D01*
X2591910Y1281108D01*
X2590980Y1280275D01*
X2589740Y1279650D01*
X2586640D01*
G01X2524950Y1386150D02*
Y1398650D01*
X2528670D01*
X2529910Y1398025D01*
X2530840Y1396567D01*
X2531150Y1394900D01*
X2530840Y1393233D01*
X2530065Y1391983D01*
X2528670Y1391358D01*
X2524950D01*
G01X2537350Y1398650D02*
Y1386150D01*
X2543550D01*
G01X2548975D02*
X2552850Y1398650D01*
X2556725Y1386150D01*
G01X2555330Y1390525D02*
X2550370D01*
G01X2565250Y1398650D02*
Y1386150D01*
G01X2561685Y1398650D02*
X2568815D01*
G01X2580750Y1386150D02*
X2574550D01*
Y1398650D01*
X2580750D01*
G01X2578270Y1392608D02*
X2574550D01*
G01X2586640Y1386150D02*
Y1398650D01*
X2589740D01*
X2590980Y1398025D01*
X2591910Y1397192D01*
X2592685Y1395942D01*
X2593305Y1394483D01*
X2593460Y1392400D01*
X2593305Y1390317D01*
X2592685Y1388858D01*
X2591910Y1387608D01*
X2590980Y1386775D01*
X2589740Y1386150D01*
X2586640D01*
G01X2524950Y1340250D02*
Y1352750D01*
X2528670D01*
X2529910Y1352125D01*
X2530840Y1350667D01*
X2531150Y1349000D01*
X2530840Y1347333D01*
X2530065Y1346083D01*
X2528670Y1345458D01*
X2524950D01*
G01X2537350Y1352750D02*
Y1340250D01*
X2543550D01*
G01X2548975D02*
X2552850Y1352750D01*
X2556725Y1340250D01*
G01X2555330Y1344625D02*
X2550370D01*
G01X2565250Y1352750D02*
Y1340250D01*
G01X2561685Y1352750D02*
X2568815D01*
G01X2580750Y1340250D02*
X2574550D01*
Y1352750D01*
X2580750D01*
G01X2578270Y1346708D02*
X2574550D01*
G01X2586640Y1340250D02*
Y1352750D01*
X2589740D01*
X2590980Y1352125D01*
X2591910Y1351292D01*
X2592685Y1350042D01*
X2593305Y1348583D01*
X2593460Y1346500D01*
X2593305Y1344417D01*
X2592685Y1342958D01*
X2591910Y1341708D01*
X2590980Y1340875D01*
X2589740Y1340250D01*
X2586640D01*
G01X2661350Y188850D02*
Y201350D01*
X2659490Y198850D01*
G01Y188850D02*
X2663210D01*
G01X2658405Y138667D02*
X2659335Y139916D01*
X2660420Y140542D01*
X2661660Y140750D01*
X2663210Y140333D01*
X2664295Y139292D01*
X2664605Y138042D01*
X2664450Y136791D01*
X2663830Y135750D01*
X2660730Y133667D01*
X2659335Y132208D01*
X2658405Y130125D01*
X2658095Y128250D01*
X2664605D01*
G01X2622600Y1404900D02*
Y104200D01*
G01X2658405Y259867D02*
X2659335Y261116D01*
X2660420Y261742D01*
X2661660Y261950D01*
X2663210Y261533D01*
X2664295Y260492D01*
X2664605Y259242D01*
X2664450Y257991D01*
X2663830Y256950D01*
X2660730Y254867D01*
X2659335Y253408D01*
X2658405Y251325D01*
X2658095Y249450D01*
X2664605D01*
G01X2663210Y370650D02*
Y383150D01*
X2657475Y374192D01*
X2665225D01*
G01X2661350Y310050D02*
X2662435Y310258D01*
X2663675Y310883D01*
X2664450Y311925D01*
X2664760Y313383D01*
X2664450Y314841D01*
X2663520Y316092D01*
X2662125Y316717D01*
X2660575D01*
X2659645Y317133D01*
X2658870Y318175D01*
X2658560Y319633D01*
X2659025Y321092D01*
X2660110Y322133D01*
X2661350Y322550D01*
X2662590Y322133D01*
X2663675Y321092D01*
X2664140Y319633D01*
X2663830Y318175D01*
X2663055Y317133D01*
X2662125Y316717D01*
X2660575D01*
X2659180Y316092D01*
X2658250Y314841D01*
X2657940Y313383D01*
X2658250Y311925D01*
X2659025Y310883D01*
X2660265Y310258D01*
X2661350Y310050D01*
G01X2658405Y441667D02*
X2659335Y442916D01*
X2660420Y443542D01*
X2661660Y443750D01*
X2663210Y443333D01*
X2664295Y442292D01*
X2664605Y441042D01*
X2664450Y439791D01*
X2663830Y438750D01*
X2660730Y436667D01*
X2659335Y435208D01*
X2658405Y433125D01*
X2658095Y431250D01*
X2664605D01*
G01X2651740Y554950D02*
X2652670Y553491D01*
X2653910Y552658D01*
X2655305Y552450D01*
X2656545Y552658D01*
X2657785Y553700D01*
X2658560Y554950D01*
X2658715Y556200D01*
X2658405Y557658D01*
X2657320Y558700D01*
X2656235Y559117D01*
X2654840D01*
G01X2656235D02*
X2657165Y559742D01*
X2657940Y560783D01*
X2658250Y562033D01*
X2657940Y563283D01*
X2657165Y564325D01*
X2655770Y564950D01*
X2654375Y564742D01*
X2652980Y563908D01*
G01X2664605Y557658D02*
X2665690Y559117D01*
X2666620Y559950D01*
X2667860Y560367D01*
X2668945Y559950D01*
X2669720Y559117D01*
X2670340Y557867D01*
X2670495Y556408D01*
X2670340Y555158D01*
X2669720Y553908D01*
X2668790Y552867D01*
X2667705Y552450D01*
X2666465Y552867D01*
X2665380Y554116D01*
X2664760Y555992D01*
X2664605Y558075D01*
X2664915Y560783D01*
X2665380Y562242D01*
X2666155Y563700D01*
X2667240Y564742D01*
X2668325Y564950D01*
X2669410Y564533D01*
X2670185Y563492D01*
G01X2661350Y491850D02*
X2662435Y492058D01*
X2663675Y492683D01*
X2664450Y493725D01*
X2664760Y495183D01*
X2664450Y496641D01*
X2663520Y497892D01*
X2662125Y498517D01*
X2660575D01*
X2659645Y498933D01*
X2658870Y499975D01*
X2658560Y501433D01*
X2659025Y502892D01*
X2660110Y503933D01*
X2661350Y504350D01*
X2662590Y503933D01*
X2663675Y502892D01*
X2664140Y501433D01*
X2663830Y499975D01*
X2663055Y498933D01*
X2662125Y498517D01*
X2660575D01*
X2659180Y497892D01*
X2658250Y496641D01*
X2657940Y495183D01*
X2658250Y493725D01*
X2659025Y492683D01*
X2660265Y492058D01*
X2661350Y491850D01*
G01X2651740Y615550D02*
X2652670Y614091D01*
X2653910Y613258D01*
X2655305Y613050D01*
X2656545Y613258D01*
X2657785Y614300D01*
X2658560Y615550D01*
X2658715Y616800D01*
X2658405Y618258D01*
X2657320Y619300D01*
X2656235Y619717D01*
X2654840D01*
G01X2656235D02*
X2657165Y620342D01*
X2657940Y621383D01*
X2658250Y622633D01*
X2657940Y623883D01*
X2657165Y624925D01*
X2655770Y625550D01*
X2654375Y625342D01*
X2652980Y624508D01*
G01X2664605Y618258D02*
X2665690Y619717D01*
X2666620Y620550D01*
X2667860Y620967D01*
X2668945Y620550D01*
X2669720Y619717D01*
X2670340Y618467D01*
X2670495Y617008D01*
X2670340Y615758D01*
X2669720Y614508D01*
X2668790Y613467D01*
X2667705Y613050D01*
X2666465Y613467D01*
X2665380Y614716D01*
X2664760Y616592D01*
X2664605Y618675D01*
X2664915Y621383D01*
X2665380Y622842D01*
X2666155Y624300D01*
X2667240Y625342D01*
X2668325Y625550D01*
X2669410Y625133D01*
X2670185Y624092D01*
G01X2657010Y734250D02*
Y746750D01*
X2651275Y737792D01*
X2659025D01*
G01X2667550Y746750D02*
X2666310Y746333D01*
X2665380Y745292D01*
X2664760Y744042D01*
X2664295Y742375D01*
X2664140Y740500D01*
X2664295Y738625D01*
X2664760Y736958D01*
X2665380Y735708D01*
X2666310Y734667D01*
X2667550Y734250D01*
X2668790Y734667D01*
X2669720Y735708D01*
X2670340Y736958D01*
X2670805Y738625D01*
X2670960Y740500D01*
X2670805Y742375D01*
X2670340Y744042D01*
X2669720Y745292D01*
X2668790Y746333D01*
X2667550Y746750D01*
G01X2658405Y678858D02*
X2659490Y680317D01*
X2660420Y681150D01*
X2661660Y681567D01*
X2662745Y681150D01*
X2663520Y680317D01*
X2664140Y679067D01*
X2664295Y677608D01*
X2664140Y676358D01*
X2663520Y675108D01*
X2662590Y674067D01*
X2661505Y673650D01*
X2660265Y674067D01*
X2659180Y675316D01*
X2658560Y677192D01*
X2658405Y679275D01*
X2658715Y681983D01*
X2659180Y683442D01*
X2659955Y684900D01*
X2661040Y685942D01*
X2662125Y686150D01*
X2663210Y685733D01*
X2663985Y684692D01*
G01X2655150Y855450D02*
Y867950D01*
X2653290Y865450D01*
G01Y855450D02*
X2657010D01*
G01X2664605Y865867D02*
X2665535Y867116D01*
X2666620Y867742D01*
X2667860Y867950D01*
X2669410Y867533D01*
X2670495Y866492D01*
X2670805Y865242D01*
X2670650Y863991D01*
X2670030Y862950D01*
X2666930Y860867D01*
X2665535Y859408D01*
X2664605Y857325D01*
X2664295Y855450D01*
X2670805D01*
G01X2651740Y796725D02*
X2652670Y795683D01*
X2653755Y795058D01*
X2655150Y794850D01*
X2656545Y795267D01*
X2657630Y796100D01*
X2658405Y797558D01*
X2658560Y799225D01*
X2658250Y800892D01*
X2657475Y801933D01*
X2656390Y802767D01*
X2655305Y802975D01*
X2654220Y802767D01*
X2652825Y801933D01*
X2653290Y807350D01*
X2657475D01*
G01X2664605Y800058D02*
X2665690Y801517D01*
X2666620Y802350D01*
X2667860Y802767D01*
X2668945Y802350D01*
X2669720Y801517D01*
X2670340Y800267D01*
X2670495Y798808D01*
X2670340Y797558D01*
X2669720Y796308D01*
X2668790Y795267D01*
X2667705Y794850D01*
X2666465Y795267D01*
X2665380Y796516D01*
X2664760Y798392D01*
X2664605Y800475D01*
X2664915Y803183D01*
X2665380Y804642D01*
X2666155Y806100D01*
X2667240Y807142D01*
X2668325Y807350D01*
X2669410Y806933D01*
X2670185Y805892D01*
G01X2652205Y921258D02*
X2653290Y922717D01*
X2654220Y923550D01*
X2655460Y923967D01*
X2656545Y923550D01*
X2657320Y922717D01*
X2657940Y921467D01*
X2658095Y920008D01*
X2657940Y918758D01*
X2657320Y917508D01*
X2656390Y916467D01*
X2655305Y916050D01*
X2654065Y916467D01*
X2652980Y917716D01*
X2652360Y919592D01*
X2652205Y921675D01*
X2652515Y924383D01*
X2652980Y925842D01*
X2653755Y927300D01*
X2654840Y928342D01*
X2655925Y928550D01*
X2657010Y928133D01*
X2657785Y927092D01*
G01X2664605Y926467D02*
X2665535Y927716D01*
X2666620Y928342D01*
X2667860Y928550D01*
X2669410Y928133D01*
X2670495Y927092D01*
X2670805Y925842D01*
X2670650Y924591D01*
X2670030Y923550D01*
X2666930Y921467D01*
X2665535Y920008D01*
X2664605Y917925D01*
X2664295Y916050D01*
X2670805D01*
G01X2642750Y1037250D02*
Y1049750D01*
X2640890Y1047250D01*
G01Y1037250D02*
X2644610D01*
G01X2654840D02*
X2655150Y1039958D01*
X2655615Y1042250D01*
X2656235Y1044333D01*
X2657010Y1046625D01*
X2658250Y1049750D01*
X2652050D01*
G01X2667240Y1037250D02*
X2667550Y1039958D01*
X2668015Y1042250D01*
X2668635Y1044333D01*
X2669410Y1046625D01*
X2670650Y1049750D01*
X2664450D01*
G01X2677005Y1047667D02*
X2677935Y1048916D01*
X2679020Y1049542D01*
X2680260Y1049750D01*
X2681810Y1049333D01*
X2682895Y1048292D01*
X2683205Y1047042D01*
X2683050Y1045791D01*
X2682430Y1044750D01*
X2679330Y1042667D01*
X2677935Y1041208D01*
X2677005Y1039125D01*
X2676695Y1037250D01*
X2683205D01*
G01X2650810Y976650D02*
Y989150D01*
X2645075Y980192D01*
X2652825D01*
G01X2663210Y976650D02*
Y989150D01*
X2657475Y980192D01*
X2665225D01*
G01X2670340Y979150D02*
X2671270Y977691D01*
X2672510Y976858D01*
X2673905Y976650D01*
X2675145Y976858D01*
X2676385Y977900D01*
X2677160Y979150D01*
X2677315Y980400D01*
X2677005Y981858D01*
X2675920Y982900D01*
X2674835Y983317D01*
X2673440D01*
G01X2674835D02*
X2675765Y983942D01*
X2676540Y984983D01*
X2676850Y986233D01*
X2676540Y987483D01*
X2675765Y988525D01*
X2674370Y989150D01*
X2672975Y988942D01*
X2671580Y988108D01*
G01X2645540Y1099725D02*
X2646470Y1098683D01*
X2647555Y1098058D01*
X2648950Y1097850D01*
X2650345Y1098267D01*
X2651430Y1099100D01*
X2652205Y1100558D01*
X2652360Y1102225D01*
X2652050Y1103892D01*
X2651275Y1104933D01*
X2650190Y1105767D01*
X2649105Y1105975D01*
X2648020Y1105767D01*
X2646625Y1104933D01*
X2647090Y1110350D01*
X2651275D01*
G01X2658405Y1103058D02*
X2659490Y1104517D01*
X2660420Y1105350D01*
X2661660Y1105767D01*
X2662745Y1105350D01*
X2663520Y1104517D01*
X2664140Y1103267D01*
X2664295Y1101808D01*
X2664140Y1100558D01*
X2663520Y1099308D01*
X2662590Y1098267D01*
X2661505Y1097850D01*
X2660265Y1098267D01*
X2659180Y1099516D01*
X2658560Y1101392D01*
X2658405Y1103475D01*
X2658715Y1106183D01*
X2659180Y1107642D01*
X2659955Y1109100D01*
X2661040Y1110142D01*
X2662125Y1110350D01*
X2663210Y1109933D01*
X2663985Y1108892D01*
G01X2673750Y1097850D02*
X2674835Y1098058D01*
X2676075Y1098683D01*
X2676850Y1099725D01*
X2677160Y1101183D01*
X2676850Y1102641D01*
X2675920Y1103892D01*
X2674525Y1104517D01*
X2672975D01*
X2672045Y1104933D01*
X2671270Y1105975D01*
X2670960Y1107433D01*
X2671425Y1108892D01*
X2672510Y1109933D01*
X2673750Y1110350D01*
X2674990Y1109933D01*
X2676075Y1108892D01*
X2676540Y1107433D01*
X2676230Y1105975D01*
X2675455Y1104933D01*
X2674525Y1104517D01*
X2672975D01*
X2671580Y1103892D01*
X2670650Y1102641D01*
X2670340Y1101183D01*
X2670650Y1099725D01*
X2671425Y1098683D01*
X2672665Y1098058D01*
X2673750Y1097850D01*
G01X2639340Y1221550D02*
X2640270Y1220091D01*
X2641510Y1219258D01*
X2642905Y1219050D01*
X2644145Y1219258D01*
X2645385Y1220300D01*
X2646160Y1221550D01*
X2646315Y1222800D01*
X2646005Y1224258D01*
X2644920Y1225300D01*
X2643835Y1225717D01*
X2642440D01*
G01X2643835D02*
X2644765Y1226342D01*
X2645540Y1227383D01*
X2645850Y1228633D01*
X2645540Y1229883D01*
X2644765Y1230925D01*
X2643370Y1231550D01*
X2641975Y1231342D01*
X2640580Y1230508D01*
G01X2655150Y1219050D02*
Y1231550D01*
X2653290Y1229050D01*
G01Y1219050D02*
X2657010D01*
G01X2664915Y1220508D02*
X2666000Y1219467D01*
X2667240Y1219050D01*
X2668480Y1219467D01*
X2669565Y1220716D01*
X2670340Y1222592D01*
X2670650Y1224467D01*
Y1226758D01*
X2670340Y1228633D01*
X2669565Y1230300D01*
X2668635Y1231133D01*
X2667550Y1231550D01*
X2666310Y1231133D01*
X2665380Y1230300D01*
X2664760Y1229050D01*
X2664450Y1227383D01*
X2664760Y1225925D01*
X2665535Y1224467D01*
X2666465Y1223633D01*
X2667550Y1223425D01*
X2668790Y1223841D01*
X2669720Y1224883D01*
X2670650Y1226758D01*
G01X2676540Y1221550D02*
X2677470Y1220091D01*
X2678710Y1219258D01*
X2680105Y1219050D01*
X2681345Y1219258D01*
X2682585Y1220300D01*
X2683360Y1221550D01*
X2683515Y1222800D01*
X2683205Y1224258D01*
X2682120Y1225300D01*
X2681035Y1225717D01*
X2679640D01*
G01X2681035D02*
X2681965Y1226342D01*
X2682740Y1227383D01*
X2683050Y1228633D01*
X2682740Y1229883D01*
X2681965Y1230925D01*
X2680570Y1231550D01*
X2679175Y1231342D01*
X2677780Y1230508D01*
G01X2652205Y1168867D02*
X2653135Y1170116D01*
X2654220Y1170742D01*
X2655460Y1170950D01*
X2657010Y1170533D01*
X2658095Y1169492D01*
X2658405Y1168242D01*
X2658250Y1166991D01*
X2657630Y1165950D01*
X2654530Y1163867D01*
X2653135Y1162408D01*
X2652205Y1160325D01*
X2651895Y1158450D01*
X2658405D01*
G01X2664605Y1163658D02*
X2665690Y1165117D01*
X2666620Y1165950D01*
X2667860Y1166367D01*
X2668945Y1165950D01*
X2669720Y1165117D01*
X2670340Y1163867D01*
X2670495Y1162408D01*
X2670340Y1161158D01*
X2669720Y1159908D01*
X2668790Y1158867D01*
X2667705Y1158450D01*
X2666465Y1158867D01*
X2665380Y1160116D01*
X2664760Y1161992D01*
X2664605Y1164075D01*
X2664915Y1166783D01*
X2665380Y1168242D01*
X2666155Y1169700D01*
X2667240Y1170742D01*
X2668325Y1170950D01*
X2669410Y1170533D01*
X2670185Y1169492D01*
G01X2646005Y1290067D02*
X2646935Y1291316D01*
X2648020Y1291942D01*
X2649260Y1292150D01*
X2650810Y1291733D01*
X2651895Y1290692D01*
X2652205Y1289442D01*
X2652050Y1288191D01*
X2651430Y1287150D01*
X2648330Y1285067D01*
X2646935Y1283608D01*
X2646005Y1281525D01*
X2645695Y1279650D01*
X2652205D01*
G01X2658715Y1281108D02*
X2659800Y1280067D01*
X2661040Y1279650D01*
X2662280Y1280067D01*
X2663365Y1281316D01*
X2664140Y1283192D01*
X2664450Y1285067D01*
Y1287358D01*
X2664140Y1289233D01*
X2663365Y1290900D01*
X2662435Y1291733D01*
X2661350Y1292150D01*
X2660110Y1291733D01*
X2659180Y1290900D01*
X2658560Y1289650D01*
X2658250Y1287983D01*
X2658560Y1286525D01*
X2659335Y1285067D01*
X2660265Y1284233D01*
X2661350Y1284025D01*
X2662590Y1284441D01*
X2663520Y1285483D01*
X2664450Y1287358D01*
G01X2673750Y1292150D02*
X2672510Y1291733D01*
X2671580Y1290692D01*
X2670960Y1289442D01*
X2670495Y1287775D01*
X2670340Y1285900D01*
X2670495Y1284025D01*
X2670960Y1282358D01*
X2671580Y1281108D01*
X2672510Y1280067D01*
X2673750Y1279650D01*
X2674990Y1280067D01*
X2675920Y1281108D01*
X2676540Y1282358D01*
X2677005Y1284025D01*
X2677160Y1285900D01*
X2677005Y1287775D01*
X2676540Y1289442D01*
X2675920Y1290692D01*
X2674990Y1291733D01*
X2673750Y1292150D01*
G01X2648950Y1386150D02*
X2647710Y1386358D01*
X2646625Y1387191D01*
X2645695Y1388442D01*
X2645075Y1389900D01*
X2644765Y1391567D01*
Y1393233D01*
X2645075Y1394900D01*
X2645695Y1396358D01*
X2646625Y1397608D01*
X2647710Y1398442D01*
X2648950Y1398650D01*
X2650190Y1398442D01*
X2651275Y1397608D01*
X2652205Y1396358D01*
X2652825Y1394900D01*
X2653135Y1393233D01*
Y1391567D01*
X2652825Y1389900D01*
X2652205Y1388442D01*
X2651275Y1387191D01*
X2650190Y1386358D01*
X2648950Y1386150D01*
G01X2650190Y1389483D02*
X2652050Y1386150D01*
G01X2661350Y1398650D02*
Y1386150D01*
G01X2657785Y1398650D02*
X2664915D01*
G01X2673750Y1386150D02*
Y1391775D01*
X2670650Y1398650D01*
G01X2676850D02*
X2673750Y1391775D01*
G01X2652205Y1350667D02*
X2653135Y1351916D01*
X2654220Y1352542D01*
X2655460Y1352750D01*
X2657010Y1352333D01*
X2658095Y1351292D01*
X2658405Y1350042D01*
X2658250Y1348791D01*
X2657630Y1347750D01*
X2654530Y1345667D01*
X2653135Y1344208D01*
X2652205Y1342125D01*
X2651895Y1340250D01*
X2658405D01*
G01X2669410D02*
Y1352750D01*
X2663675Y1343792D01*
X2671425D01*
G01X0Y3937D02*
G03X3937Y0I3937J0D01*
G01X0Y3937D02*
G03X3937Y0I3937J0D01*
G01D02*
X779528D01*
G01X3937D02*
X779528D01*
G01X0Y1456693D02*
Y3937D01*
G01Y1456693D02*
Y3937D01*
G01X7874Y1460630D02*
X3937D01*
G01D02*
X7874D01*
G01X3937D02*
G03X0Y1456693I0J-3937D01*
G01X3937Y1460630D02*
G03X0Y1456693I0J-3937D01*
G01X72102Y264146D02*
X72502Y264546D01*
X72969Y264746D01*
X73502Y264813D01*
X74169Y264680D01*
X74636Y264346D01*
X74769Y263946D01*
X74702Y263546D01*
X74436Y263213D01*
X73102Y262546D01*
X72502Y262080D01*
X72102Y261413D01*
X71969Y260813D01*
X74769D01*
G01X76502Y261613D02*
X76902Y261146D01*
X77436Y260880D01*
X78036Y260813D01*
X78569Y260880D01*
X79102Y261213D01*
X79436Y261613D01*
X79502Y262013D01*
X79369Y262480D01*
X78902Y262813D01*
X78436Y262946D01*
X77836D01*
G01X78436D02*
X78836Y263146D01*
X79169Y263480D01*
X79302Y263880D01*
X79169Y264280D01*
X78836Y264613D01*
X78236Y264813D01*
X77636Y264746D01*
X77036Y264480D01*
G01X81302Y262480D02*
X81769Y262946D01*
X82169Y263213D01*
X82702Y263346D01*
X83169Y263213D01*
X83502Y262946D01*
X83769Y262546D01*
X83836Y262080D01*
X83769Y261680D01*
X83502Y261280D01*
X83102Y260946D01*
X82636Y260813D01*
X82102Y260946D01*
X81636Y261346D01*
X81369Y261946D01*
X81302Y262613D01*
X81436Y263480D01*
X81636Y263946D01*
X81969Y264413D01*
X82436Y264746D01*
X82902Y264813D01*
X83369Y264680D01*
X83702Y264346D01*
G01X87169Y260680D02*
X87036Y260746D01*
Y260880D01*
X87169Y260946D01*
X87302Y260880D01*
Y260746D01*
X87169Y260680D01*
G01X90502Y264146D02*
X90902Y264546D01*
X91369Y264746D01*
X91902Y264813D01*
X92569Y264680D01*
X93036Y264346D01*
X93169Y263946D01*
X93102Y263546D01*
X92836Y263213D01*
X91502Y262546D01*
X90902Y262080D01*
X90502Y261413D01*
X90369Y260813D01*
X93169D01*
G01X95102Y264146D02*
X95502Y264546D01*
X95969Y264746D01*
X96502Y264813D01*
X97169Y264680D01*
X97636Y264346D01*
X97769Y263946D01*
X97702Y263546D01*
X97436Y263213D01*
X96102Y262546D01*
X95502Y262080D01*
X95102Y261413D01*
X94969Y260813D01*
X97769D01*
G01X54763Y253600D02*
X55163Y253267D01*
X55630Y253067D01*
X56230Y253000D01*
X56830Y253133D01*
X57297Y253400D01*
X57630Y253867D01*
X57697Y254400D01*
X57563Y254933D01*
X57230Y255267D01*
X56763Y255533D01*
X56297Y255600D01*
X55830Y255533D01*
X55230Y255267D01*
X55430Y257000D01*
X57230D01*
G01X59363Y253600D02*
X59763Y253267D01*
X60230Y253067D01*
X60830Y253000D01*
X61430Y253133D01*
X61897Y253400D01*
X62230Y253867D01*
X62297Y254400D01*
X62163Y254933D01*
X61830Y255267D01*
X61363Y255533D01*
X60897Y255600D01*
X60430Y255533D01*
X59830Y255267D01*
X60030Y257000D01*
X61830D01*
G01X65297Y253000D02*
X65430Y253867D01*
X65630Y254600D01*
X65897Y255267D01*
X66230Y256000D01*
X66763Y257000D01*
X64097D01*
G01X70030Y252867D02*
X69897Y252933D01*
Y253067D01*
X70030Y253133D01*
X70163Y253067D01*
Y252933D01*
X70030Y252867D01*
G01X74630Y257000D02*
X74097Y256867D01*
X73697Y256533D01*
X73430Y256133D01*
X73230Y255600D01*
X73163Y255000D01*
X73230Y254400D01*
X73430Y253867D01*
X73697Y253467D01*
X74097Y253133D01*
X74630Y253000D01*
X75163Y253133D01*
X75563Y253467D01*
X75830Y253867D01*
X76030Y254400D01*
X76097Y255000D01*
X76030Y255600D01*
X75830Y256133D01*
X75563Y256533D01*
X75163Y256867D01*
X74630Y257000D01*
G01X78097Y253467D02*
X78563Y253133D01*
X79097Y253000D01*
X79630Y253133D01*
X80097Y253533D01*
X80430Y254133D01*
X80563Y254733D01*
Y255467D01*
X80430Y256067D01*
X80097Y256600D01*
X79697Y256867D01*
X79230Y257000D01*
X78697Y256867D01*
X78297Y256600D01*
X78030Y256200D01*
X77897Y255667D01*
X78030Y255200D01*
X78363Y254733D01*
X78763Y254467D01*
X79230Y254400D01*
X79763Y254533D01*
X80163Y254867D01*
X80563Y255467D01*
G01X54763Y706356D02*
X55163Y706023D01*
X55630Y705823D01*
X56230Y705756D01*
X56830Y705889D01*
X57297Y706156D01*
X57630Y706623D01*
X57697Y707156D01*
X57563Y707689D01*
X57230Y708023D01*
X56763Y708289D01*
X56297Y708356D01*
X55830Y708289D01*
X55230Y708023D01*
X55430Y709756D01*
X57230D01*
G01X59363Y706356D02*
X59763Y706023D01*
X60230Y705823D01*
X60830Y705756D01*
X61430Y705889D01*
X61897Y706156D01*
X62230Y706623D01*
X62297Y707156D01*
X62163Y707689D01*
X61830Y708023D01*
X61363Y708289D01*
X60897Y708356D01*
X60430Y708289D01*
X59830Y708023D01*
X60030Y709756D01*
X61830D01*
G01X65297Y705756D02*
X65430Y706623D01*
X65630Y707356D01*
X65897Y708023D01*
X66230Y708756D01*
X66763Y709756D01*
X64097D01*
G01X70030Y705623D02*
X69897Y705689D01*
Y705823D01*
X70030Y705889D01*
X70163Y705823D01*
Y705689D01*
X70030Y705623D01*
G01X74630Y709756D02*
X74097Y709623D01*
X73697Y709289D01*
X73430Y708889D01*
X73230Y708356D01*
X73163Y707756D01*
X73230Y707156D01*
X73430Y706623D01*
X73697Y706223D01*
X74097Y705889D01*
X74630Y705756D01*
X75163Y705889D01*
X75563Y706223D01*
X75830Y706623D01*
X76030Y707156D01*
X76097Y707756D01*
X76030Y708356D01*
X75830Y708889D01*
X75563Y709289D01*
X75163Y709623D01*
X74630Y709756D01*
G01X78097Y706223D02*
X78563Y705889D01*
X79097Y705756D01*
X79630Y705889D01*
X80097Y706289D01*
X80430Y706889D01*
X80563Y707489D01*
Y708223D01*
X80430Y708823D01*
X80097Y709356D01*
X79697Y709623D01*
X79230Y709756D01*
X78697Y709623D01*
X78297Y709356D01*
X78030Y708956D01*
X77897Y708423D01*
X78030Y707956D01*
X78363Y707489D01*
X78763Y707223D01*
X79230Y707156D01*
X79763Y707289D01*
X80163Y707623D01*
X80563Y708223D01*
G01X72102Y716902D02*
X72502Y717302D01*
X72969Y717502D01*
X73502Y717569D01*
X74169Y717436D01*
X74636Y717102D01*
X74769Y716702D01*
X74702Y716302D01*
X74436Y715969D01*
X73102Y715302D01*
X72502Y714836D01*
X72102Y714169D01*
X71969Y713569D01*
X74769D01*
G01X76502Y714369D02*
X76902Y713902D01*
X77436Y713636D01*
X78036Y713569D01*
X78569Y713636D01*
X79102Y713969D01*
X79436Y714369D01*
X79502Y714769D01*
X79369Y715236D01*
X78902Y715569D01*
X78436Y715702D01*
X77836D01*
G01X78436D02*
X78836Y715902D01*
X79169Y716236D01*
X79302Y716636D01*
X79169Y717036D01*
X78836Y717369D01*
X78236Y717569D01*
X77636Y717502D01*
X77036Y717236D01*
G01X81302Y715236D02*
X81769Y715702D01*
X82169Y715969D01*
X82702Y716102D01*
X83169Y715969D01*
X83502Y715702D01*
X83769Y715302D01*
X83836Y714836D01*
X83769Y714436D01*
X83502Y714036D01*
X83102Y713702D01*
X82636Y713569D01*
X82102Y713702D01*
X81636Y714102D01*
X81369Y714702D01*
X81302Y715369D01*
X81436Y716236D01*
X81636Y716702D01*
X81969Y717169D01*
X82436Y717502D01*
X82902Y717569D01*
X83369Y717436D01*
X83702Y717102D01*
G01X87169Y713436D02*
X87036Y713502D01*
Y713636D01*
X87169Y713702D01*
X87302Y713636D01*
Y713502D01*
X87169Y713436D01*
G01X90502Y716902D02*
X90902Y717302D01*
X91369Y717502D01*
X91902Y717569D01*
X92569Y717436D01*
X93036Y717102D01*
X93169Y716702D01*
X93102Y716302D01*
X92836Y715969D01*
X91502Y715302D01*
X90902Y714836D01*
X90502Y714169D01*
X90369Y713569D01*
X93169D01*
G01X95102Y716902D02*
X95502Y717302D01*
X95969Y717502D01*
X96502Y717569D01*
X97169Y717436D01*
X97636Y717102D01*
X97769Y716702D01*
X97702Y716302D01*
X97436Y715969D01*
X96102Y715302D01*
X95502Y714836D01*
X95102Y714169D01*
X94969Y713569D01*
X97769D01*
G01X72102Y1169657D02*
X72502Y1170057D01*
X72969Y1170257D01*
X73502Y1170324D01*
X74169Y1170191D01*
X74636Y1169857D01*
X74769Y1169457D01*
X74702Y1169057D01*
X74436Y1168724D01*
X73102Y1168057D01*
X72502Y1167591D01*
X72102Y1166924D01*
X71969Y1166324D01*
X74769D01*
G01X76502Y1167124D02*
X76902Y1166657D01*
X77436Y1166391D01*
X78036Y1166324D01*
X78569Y1166391D01*
X79102Y1166724D01*
X79436Y1167124D01*
X79502Y1167524D01*
X79369Y1167991D01*
X78902Y1168324D01*
X78436Y1168457D01*
X77836D01*
G01X78436D02*
X78836Y1168657D01*
X79169Y1168991D01*
X79302Y1169391D01*
X79169Y1169791D01*
X78836Y1170124D01*
X78236Y1170324D01*
X77636Y1170257D01*
X77036Y1169991D01*
G01X81302Y1167991D02*
X81769Y1168457D01*
X82169Y1168724D01*
X82702Y1168857D01*
X83169Y1168724D01*
X83502Y1168457D01*
X83769Y1168057D01*
X83836Y1167591D01*
X83769Y1167191D01*
X83502Y1166791D01*
X83102Y1166457D01*
X82636Y1166324D01*
X82102Y1166457D01*
X81636Y1166857D01*
X81369Y1167457D01*
X81302Y1168124D01*
X81436Y1168991D01*
X81636Y1169457D01*
X81969Y1169924D01*
X82436Y1170257D01*
X82902Y1170324D01*
X83369Y1170191D01*
X83702Y1169857D01*
G01X87169Y1166191D02*
X87036Y1166257D01*
Y1166391D01*
X87169Y1166457D01*
X87302Y1166391D01*
Y1166257D01*
X87169Y1166191D01*
G01X90502Y1169657D02*
X90902Y1170057D01*
X91369Y1170257D01*
X91902Y1170324D01*
X92569Y1170191D01*
X93036Y1169857D01*
X93169Y1169457D01*
X93102Y1169057D01*
X92836Y1168724D01*
X91502Y1168057D01*
X90902Y1167591D01*
X90502Y1166924D01*
X90369Y1166324D01*
X93169D01*
G01X95102Y1169657D02*
X95502Y1170057D01*
X95969Y1170257D01*
X96502Y1170324D01*
X97169Y1170191D01*
X97636Y1169857D01*
X97769Y1169457D01*
X97702Y1169057D01*
X97436Y1168724D01*
X96102Y1168057D01*
X95502Y1167591D01*
X95102Y1166924D01*
X94969Y1166324D01*
X97769D01*
G01X54763Y1159111D02*
X55163Y1158778D01*
X55630Y1158578D01*
X56230Y1158511D01*
X56830Y1158644D01*
X57297Y1158911D01*
X57630Y1159378D01*
X57697Y1159911D01*
X57563Y1160444D01*
X57230Y1160778D01*
X56763Y1161044D01*
X56297Y1161111D01*
X55830Y1161044D01*
X55230Y1160778D01*
X55430Y1162511D01*
X57230D01*
G01X59363Y1159111D02*
X59763Y1158778D01*
X60230Y1158578D01*
X60830Y1158511D01*
X61430Y1158644D01*
X61897Y1158911D01*
X62230Y1159378D01*
X62297Y1159911D01*
X62163Y1160444D01*
X61830Y1160778D01*
X61363Y1161044D01*
X60897Y1161111D01*
X60430Y1161044D01*
X59830Y1160778D01*
X60030Y1162511D01*
X61830D01*
G01X65297Y1158511D02*
X65430Y1159378D01*
X65630Y1160111D01*
X65897Y1160778D01*
X66230Y1161511D01*
X66763Y1162511D01*
X64097D01*
G01X70030Y1158378D02*
X69897Y1158444D01*
Y1158578D01*
X70030Y1158644D01*
X70163Y1158578D01*
Y1158444D01*
X70030Y1158378D01*
G01X74630Y1162511D02*
X74097Y1162378D01*
X73697Y1162044D01*
X73430Y1161644D01*
X73230Y1161111D01*
X73163Y1160511D01*
X73230Y1159911D01*
X73430Y1159378D01*
X73697Y1158978D01*
X74097Y1158644D01*
X74630Y1158511D01*
X75163Y1158644D01*
X75563Y1158978D01*
X75830Y1159378D01*
X76030Y1159911D01*
X76097Y1160511D01*
X76030Y1161111D01*
X75830Y1161644D01*
X75563Y1162044D01*
X75163Y1162378D01*
X74630Y1162511D01*
G01X78097Y1158978D02*
X78563Y1158644D01*
X79097Y1158511D01*
X79630Y1158644D01*
X80097Y1159044D01*
X80430Y1159644D01*
X80563Y1160244D01*
Y1160978D01*
X80430Y1161578D01*
X80097Y1162111D01*
X79697Y1162378D01*
X79230Y1162511D01*
X78697Y1162378D01*
X78297Y1162111D01*
X78030Y1161711D01*
X77897Y1161178D01*
X78030Y1160711D01*
X78363Y1160244D01*
X78763Y1159978D01*
X79230Y1159911D01*
X79763Y1160044D01*
X80163Y1160378D01*
X80563Y1160978D01*
G01X101378Y1519685D02*
G03X97441Y1515748I0J-3937D01*
G01X101378Y1519685D02*
G03X97441Y1515748I0J-3937D01*
G01D02*
Y1509055D01*
G01Y1515748D02*
Y1509055D01*
G01X93504Y1505118D02*
X67913D01*
G01X93504D02*
G03X97441Y1509055I0J3937D01*
G01X93504Y1505118D02*
G03X97441Y1509055I0J3937D01*
G01X67913Y1505118D02*
X93504D01*
G01X63976Y1515748D02*
G03X60039Y1519685I-3937J0D01*
G01X63976Y1515748D02*
G03X60039Y1519685I-3937J0D01*
G01X63976Y1509055D02*
Y1515748D01*
G01Y1509055D02*
G03X67913Y1505118I3937J0D01*
G01X63976Y1509055D02*
G03X67913Y1505118I3937J0D01*
G01X63976Y1515748D02*
Y1509055D01*
G01X7874Y1460630D02*
G03X11811Y1464567I0J3937D01*
G01X7874Y1460630D02*
G03X11811Y1464567I0J3937D01*
G01X15748Y1519685D02*
G03X11811Y1515748I0J-3937D01*
G01X15748Y1519685D02*
G03X11811Y1515748I0J-3937D01*
G01D02*
Y1464567D01*
G01Y1515748D02*
Y1464567D01*
G01X60039Y1519685D02*
X15748D01*
G01X60039D02*
X15748D01*
G01X166334Y262709D02*
Y266709D01*
X167668D01*
X168201Y266509D01*
X168601Y266242D01*
X168934Y265842D01*
X169201Y265376D01*
X169268Y264709D01*
X169201Y264042D01*
X168934Y263576D01*
X168601Y263176D01*
X168201Y262909D01*
X167668Y262709D01*
X166334D01*
G01X171468D02*
Y265376D01*
G01Y264842D02*
X171801Y265109D01*
X172134Y265309D01*
X172601Y265376D01*
X172934Y265309D01*
X173334Y265109D01*
G01X177001Y265376D02*
Y262709D01*
G01Y266442D02*
X176868Y266509D01*
Y266642D01*
X177001Y266709D01*
X177134Y266642D01*
Y266509D01*
X177001Y266442D01*
G01X181601Y262709D02*
Y266709D01*
G01X186201Y262709D02*
Y266709D01*
G01X195001Y262709D02*
Y266109D01*
X195134Y266442D01*
X195401Y266642D01*
X195801Y266709D01*
X196201Y266576D01*
X196401Y266242D01*
G01X195601Y265109D02*
X194268D01*
G01X199001Y264509D02*
X201134D01*
X200934Y264976D01*
X200601Y265242D01*
X200134Y265376D01*
X199668Y265309D01*
X199268Y265109D01*
X199001Y264642D01*
X198868Y264242D01*
Y263842D01*
X199001Y263442D01*
X199334Y263042D01*
X199734Y262776D01*
X200201Y262709D01*
X200668Y262842D01*
X201134Y263242D01*
G01X205801Y262709D02*
Y265376D01*
G01Y264909D02*
X205534Y265176D01*
X205134Y265309D01*
X204668Y265376D01*
X204201Y265242D01*
X203801Y264976D01*
X203534Y264576D01*
X203401Y264042D01*
X203534Y263509D01*
X203801Y263109D01*
X204201Y262842D01*
X204668Y262709D01*
X205134Y262776D01*
X205534Y262976D01*
X205801Y263242D01*
G01X209201Y266709D02*
Y262709D01*
G01X208268Y265376D02*
X210134D01*
G01X212668D02*
Y263509D01*
X212934Y263042D01*
X213334Y262776D01*
X213801Y262709D01*
X214268Y262776D01*
X214668Y263042D01*
X214934Y263509D01*
G01Y262709D02*
Y265376D01*
G01X217468Y262709D02*
Y265376D01*
G01Y264842D02*
X217801Y265109D01*
X218134Y265309D01*
X218601Y265376D01*
X218934Y265309D01*
X219334Y265109D01*
G01X222001Y264509D02*
X224134D01*
X223934Y264976D01*
X223601Y265242D01*
X223134Y265376D01*
X222668Y265309D01*
X222268Y265109D01*
X222001Y264642D01*
X221868Y264242D01*
Y263842D01*
X222001Y263442D01*
X222334Y263042D01*
X222734Y262776D01*
X223201Y262709D01*
X223668Y262842D01*
X224134Y263242D01*
G01X172797Y220552D02*
Y224552D01*
X170330Y221685D01*
X173664D01*
G01X175130Y221352D02*
X175530Y220885D01*
X176064Y220619D01*
X176664Y220552D01*
X177197Y220619D01*
X177730Y220952D01*
X178064Y221352D01*
X178130Y221752D01*
X177997Y222219D01*
X177530Y222552D01*
X177064Y222685D01*
X176464D01*
G01X177064D02*
X177464Y222885D01*
X177797Y223219D01*
X177930Y223619D01*
X177797Y224019D01*
X177464Y224352D01*
X176864Y224552D01*
X176264Y224485D01*
X175664Y224219D01*
G01X179730Y221352D02*
X180130Y220885D01*
X180664Y220619D01*
X181264Y220552D01*
X181797Y220619D01*
X182330Y220952D01*
X182664Y221352D01*
X182730Y221752D01*
X182597Y222219D01*
X182130Y222552D01*
X181664Y222685D01*
X181064D01*
G01X181664D02*
X182064Y222885D01*
X182397Y223219D01*
X182530Y223619D01*
X182397Y224019D01*
X182064Y224352D01*
X181464Y224552D01*
X180864Y224485D01*
X180264Y224219D01*
G01X185797Y220419D02*
X185664Y220485D01*
Y220619D01*
X185797Y220685D01*
X185930Y220619D01*
Y220485D01*
X185797Y220419D01*
G01X190397Y224552D02*
X189864Y224419D01*
X189464Y224085D01*
X189197Y223685D01*
X188997Y223152D01*
X188930Y222552D01*
X188997Y221952D01*
X189197Y221419D01*
X189464Y221019D01*
X189864Y220685D01*
X190397Y220552D01*
X190930Y220685D01*
X191330Y221019D01*
X191597Y221419D01*
X191797Y221952D01*
X191864Y222552D01*
X191797Y223152D01*
X191597Y223685D01*
X191330Y224085D01*
X190930Y224419D01*
X190397Y224552D01*
G01X194997Y220552D02*
X195464Y220619D01*
X195997Y220819D01*
X196330Y221152D01*
X196464Y221619D01*
X196330Y222085D01*
X195930Y222485D01*
X195330Y222685D01*
X194664D01*
X194264Y222819D01*
X193930Y223152D01*
X193797Y223619D01*
X193997Y224085D01*
X194464Y224419D01*
X194997Y224552D01*
X195530Y224419D01*
X195997Y224085D01*
X196197Y223619D01*
X196064Y223152D01*
X195730Y222819D01*
X195330Y222685D01*
X194664D01*
X194064Y222485D01*
X193664Y222085D01*
X193530Y221619D01*
X193664Y221152D01*
X193997Y220819D01*
X194530Y220619D01*
X194997Y220552D01*
G01X141181Y277843D02*
G03X148106Y264712I37662J11471D01*
G01X141181Y277843D02*
G03X148106Y264712I37662J11471D01*
G01X141181Y277843D02*
G03X121220I-9980J-3040D01*
G01X114295Y264712D02*
G03X121220Y277843I-30737J24602D01*
G01X141181D02*
G03X121220I-9980J-3040D01*
G01X114295Y264712D02*
G03X121220Y277843I-30737J24601D01*
G01X114295Y264712D02*
G03X148106I16905J-13531D01*
G01X114295D02*
G03X148106I16905J-13531D01*
G01X172889Y304876D02*
X173289Y305276D01*
X173756Y305476D01*
X174289Y305543D01*
X174956Y305410D01*
X175423Y305076D01*
X175556Y304676D01*
X175489Y304276D01*
X175223Y303943D01*
X173889Y303276D01*
X173289Y302810D01*
X172889Y302143D01*
X172756Y301543D01*
X175556D01*
G01X178756Y305543D02*
X178223Y305410D01*
X177823Y305076D01*
X177556Y304676D01*
X177356Y304143D01*
X177289Y303543D01*
X177356Y302943D01*
X177556Y302410D01*
X177823Y302010D01*
X178223Y301676D01*
X178756Y301543D01*
X179289Y301676D01*
X179689Y302010D01*
X179956Y302410D01*
X180156Y302943D01*
X180223Y303543D01*
X180156Y304143D01*
X179956Y304676D01*
X179689Y305076D01*
X179289Y305410D01*
X178756Y305543D01*
G01X183356Y301543D02*
X183823Y301610D01*
X184356Y301810D01*
X184689Y302143D01*
X184823Y302610D01*
X184689Y303076D01*
X184289Y303476D01*
X183689Y303676D01*
X183023D01*
X182623Y303810D01*
X182289Y304143D01*
X182156Y304610D01*
X182356Y305076D01*
X182823Y305410D01*
X183356Y305543D01*
X183889Y305410D01*
X184356Y305076D01*
X184556Y304610D01*
X184423Y304143D01*
X184089Y303810D01*
X183689Y303676D01*
X183023D01*
X182423Y303476D01*
X182023Y303076D01*
X181889Y302610D01*
X182023Y302143D01*
X182356Y301810D01*
X182889Y301610D01*
X183356Y301543D01*
G01X187956Y301410D02*
X187823Y301476D01*
Y301610D01*
X187956Y301676D01*
X188089Y301610D01*
Y301476D01*
X187956Y301410D01*
G01X191289Y303210D02*
X191756Y303676D01*
X192156Y303943D01*
X192689Y304076D01*
X193156Y303943D01*
X193489Y303676D01*
X193756Y303276D01*
X193823Y302810D01*
X193756Y302410D01*
X193489Y302010D01*
X193089Y301676D01*
X192623Y301543D01*
X192089Y301676D01*
X191623Y302076D01*
X191356Y302676D01*
X191289Y303343D01*
X191423Y304210D01*
X191623Y304676D01*
X191956Y305143D01*
X192423Y305476D01*
X192889Y305543D01*
X193356Y305410D01*
X193689Y305076D01*
G01X195889Y303210D02*
X196356Y303676D01*
X196756Y303943D01*
X197289Y304076D01*
X197756Y303943D01*
X198089Y303676D01*
X198356Y303276D01*
X198423Y302810D01*
X198356Y302410D01*
X198089Y302010D01*
X197689Y301676D01*
X197223Y301543D01*
X196689Y301676D01*
X196223Y302076D01*
X195956Y302676D01*
X195889Y303343D01*
X196023Y304210D01*
X196223Y304676D01*
X196556Y305143D01*
X197023Y305476D01*
X197489Y305543D01*
X197956Y305410D01*
X198289Y305076D01*
G01X172797Y673308D02*
Y677308D01*
X170330Y674441D01*
X173664D01*
G01X175130Y674108D02*
X175530Y673641D01*
X176064Y673375D01*
X176664Y673308D01*
X177197Y673375D01*
X177730Y673708D01*
X178064Y674108D01*
X178130Y674508D01*
X177997Y674975D01*
X177530Y675308D01*
X177064Y675441D01*
X176464D01*
G01X177064D02*
X177464Y675641D01*
X177797Y675975D01*
X177930Y676375D01*
X177797Y676775D01*
X177464Y677108D01*
X176864Y677308D01*
X176264Y677241D01*
X175664Y676975D01*
G01X179730Y674108D02*
X180130Y673641D01*
X180664Y673375D01*
X181264Y673308D01*
X181797Y673375D01*
X182330Y673708D01*
X182664Y674108D01*
X182730Y674508D01*
X182597Y674975D01*
X182130Y675308D01*
X181664Y675441D01*
X181064D01*
G01X181664D02*
X182064Y675641D01*
X182397Y675975D01*
X182530Y676375D01*
X182397Y676775D01*
X182064Y677108D01*
X181464Y677308D01*
X180864Y677241D01*
X180264Y676975D01*
G01X185797Y673175D02*
X185664Y673241D01*
Y673375D01*
X185797Y673441D01*
X185930Y673375D01*
Y673241D01*
X185797Y673175D01*
G01X190397Y677308D02*
X189864Y677175D01*
X189464Y676841D01*
X189197Y676441D01*
X188997Y675908D01*
X188930Y675308D01*
X188997Y674708D01*
X189197Y674175D01*
X189464Y673775D01*
X189864Y673441D01*
X190397Y673308D01*
X190930Y673441D01*
X191330Y673775D01*
X191597Y674175D01*
X191797Y674708D01*
X191864Y675308D01*
X191797Y675908D01*
X191597Y676441D01*
X191330Y676841D01*
X190930Y677175D01*
X190397Y677308D01*
G01X194997Y673308D02*
X195464Y673375D01*
X195997Y673575D01*
X196330Y673908D01*
X196464Y674375D01*
X196330Y674841D01*
X195930Y675241D01*
X195330Y675441D01*
X194664D01*
X194264Y675575D01*
X193930Y675908D01*
X193797Y676375D01*
X193997Y676841D01*
X194464Y677175D01*
X194997Y677308D01*
X195530Y677175D01*
X195997Y676841D01*
X196197Y676375D01*
X196064Y675908D01*
X195730Y675575D01*
X195330Y675441D01*
X194664D01*
X194064Y675241D01*
X193664Y674841D01*
X193530Y674375D01*
X193664Y673908D01*
X193997Y673575D01*
X194530Y673375D01*
X194997Y673308D01*
G01X172889Y757632D02*
X173289Y758032D01*
X173756Y758232D01*
X174289Y758299D01*
X174956Y758166D01*
X175423Y757832D01*
X175556Y757432D01*
X175489Y757032D01*
X175223Y756699D01*
X173889Y756032D01*
X173289Y755566D01*
X172889Y754899D01*
X172756Y754299D01*
X175556D01*
G01X178756Y758299D02*
X178223Y758166D01*
X177823Y757832D01*
X177556Y757432D01*
X177356Y756899D01*
X177289Y756299D01*
X177356Y755699D01*
X177556Y755166D01*
X177823Y754766D01*
X178223Y754432D01*
X178756Y754299D01*
X179289Y754432D01*
X179689Y754766D01*
X179956Y755166D01*
X180156Y755699D01*
X180223Y756299D01*
X180156Y756899D01*
X179956Y757432D01*
X179689Y757832D01*
X179289Y758166D01*
X178756Y758299D01*
G01X183356Y754299D02*
X183823Y754366D01*
X184356Y754566D01*
X184689Y754899D01*
X184823Y755366D01*
X184689Y755832D01*
X184289Y756232D01*
X183689Y756432D01*
X183023D01*
X182623Y756566D01*
X182289Y756899D01*
X182156Y757366D01*
X182356Y757832D01*
X182823Y758166D01*
X183356Y758299D01*
X183889Y758166D01*
X184356Y757832D01*
X184556Y757366D01*
X184423Y756899D01*
X184089Y756566D01*
X183689Y756432D01*
X183023D01*
X182423Y756232D01*
X182023Y755832D01*
X181889Y755366D01*
X182023Y754899D01*
X182356Y754566D01*
X182889Y754366D01*
X183356Y754299D01*
G01X187956Y754166D02*
X187823Y754232D01*
Y754366D01*
X187956Y754432D01*
X188089Y754366D01*
Y754232D01*
X187956Y754166D01*
G01X191289Y755966D02*
X191756Y756432D01*
X192156Y756699D01*
X192689Y756832D01*
X193156Y756699D01*
X193489Y756432D01*
X193756Y756032D01*
X193823Y755566D01*
X193756Y755166D01*
X193489Y754766D01*
X193089Y754432D01*
X192623Y754299D01*
X192089Y754432D01*
X191623Y754832D01*
X191356Y755432D01*
X191289Y756099D01*
X191423Y756966D01*
X191623Y757432D01*
X191956Y757899D01*
X192423Y758232D01*
X192889Y758299D01*
X193356Y758166D01*
X193689Y757832D01*
G01X195889Y755966D02*
X196356Y756432D01*
X196756Y756699D01*
X197289Y756832D01*
X197756Y756699D01*
X198089Y756432D01*
X198356Y756032D01*
X198423Y755566D01*
X198356Y755166D01*
X198089Y754766D01*
X197689Y754432D01*
X197223Y754299D01*
X196689Y754432D01*
X196223Y754832D01*
X195956Y755432D01*
X195889Y756099D01*
X196023Y756966D01*
X196223Y757432D01*
X196556Y757899D01*
X197023Y758232D01*
X197489Y758299D01*
X197956Y758166D01*
X198289Y757832D01*
G01X166334Y715465D02*
Y719465D01*
X167668D01*
X168201Y719265D01*
X168601Y718998D01*
X168934Y718598D01*
X169201Y718132D01*
X169268Y717465D01*
X169201Y716798D01*
X168934Y716332D01*
X168601Y715932D01*
X168201Y715665D01*
X167668Y715465D01*
X166334D01*
G01X171468D02*
Y718132D01*
G01Y717598D02*
X171801Y717865D01*
X172134Y718065D01*
X172601Y718132D01*
X172934Y718065D01*
X173334Y717865D01*
G01X177001Y718132D02*
Y715465D01*
G01Y719198D02*
X176868Y719265D01*
Y719398D01*
X177001Y719465D01*
X177134Y719398D01*
Y719265D01*
X177001Y719198D01*
G01X181601Y715465D02*
Y719465D01*
G01X186201Y715465D02*
Y719465D01*
G01X195001Y715465D02*
Y718865D01*
X195134Y719198D01*
X195401Y719398D01*
X195801Y719465D01*
X196201Y719332D01*
X196401Y718998D01*
G01X195601Y717865D02*
X194268D01*
G01X199001Y717265D02*
X201134D01*
X200934Y717732D01*
X200601Y717998D01*
X200134Y718132D01*
X199668Y718065D01*
X199268Y717865D01*
X199001Y717398D01*
X198868Y716998D01*
Y716598D01*
X199001Y716198D01*
X199334Y715798D01*
X199734Y715532D01*
X200201Y715465D01*
X200668Y715598D01*
X201134Y715998D01*
G01X205801Y715465D02*
Y718132D01*
G01Y717665D02*
X205534Y717932D01*
X205134Y718065D01*
X204668Y718132D01*
X204201Y717998D01*
X203801Y717732D01*
X203534Y717332D01*
X203401Y716798D01*
X203534Y716265D01*
X203801Y715865D01*
X204201Y715598D01*
X204668Y715465D01*
X205134Y715532D01*
X205534Y715732D01*
X205801Y715998D01*
G01X209201Y719465D02*
Y715465D01*
G01X208268Y718132D02*
X210134D01*
G01X212668D02*
Y716265D01*
X212934Y715798D01*
X213334Y715532D01*
X213801Y715465D01*
X214268Y715532D01*
X214668Y715798D01*
X214934Y716265D01*
G01Y715465D02*
Y718132D01*
G01X217468Y715465D02*
Y718132D01*
G01Y717598D02*
X217801Y717865D01*
X218134Y718065D01*
X218601Y718132D01*
X218934Y718065D01*
X219334Y717865D01*
G01X222001Y717265D02*
X224134D01*
X223934Y717732D01*
X223601Y717998D01*
X223134Y718132D01*
X222668Y718065D01*
X222268Y717865D01*
X222001Y717398D01*
X221868Y716998D01*
Y716598D01*
X222001Y716198D01*
X222334Y715798D01*
X222734Y715532D01*
X223201Y715465D01*
X223668Y715598D01*
X224134Y715998D01*
G01X141181Y730599D02*
G03X148106Y717468I37662J11471D01*
G01X141181Y730599D02*
G03X148106Y717468I37662J11471D01*
G01X141181Y730599D02*
G03X121220I-9980J-3040D01*
G01X114295Y717468D02*
G03X121220Y730599I-30737J24601D01*
G01X141181D02*
G03X121220I-9980J-3040D01*
G01X114295Y717468D02*
G03X121220Y730599I-30737J24601D01*
G01X114295Y717468D02*
G03X148106I16905J-13531D01*
G01X114295D02*
G03X148106I16905J-13531D01*
G01X172797Y1126063D02*
Y1130063D01*
X170330Y1127196D01*
X173664D01*
G01X175130Y1126863D02*
X175530Y1126396D01*
X176064Y1126130D01*
X176664Y1126063D01*
X177197Y1126130D01*
X177730Y1126463D01*
X178064Y1126863D01*
X178130Y1127263D01*
X177997Y1127730D01*
X177530Y1128063D01*
X177064Y1128196D01*
X176464D01*
G01X177064D02*
X177464Y1128396D01*
X177797Y1128730D01*
X177930Y1129130D01*
X177797Y1129530D01*
X177464Y1129863D01*
X176864Y1130063D01*
X176264Y1129996D01*
X175664Y1129730D01*
G01X179730Y1126863D02*
X180130Y1126396D01*
X180664Y1126130D01*
X181264Y1126063D01*
X181797Y1126130D01*
X182330Y1126463D01*
X182664Y1126863D01*
X182730Y1127263D01*
X182597Y1127730D01*
X182130Y1128063D01*
X181664Y1128196D01*
X181064D01*
G01X181664D02*
X182064Y1128396D01*
X182397Y1128730D01*
X182530Y1129130D01*
X182397Y1129530D01*
X182064Y1129863D01*
X181464Y1130063D01*
X180864Y1129996D01*
X180264Y1129730D01*
G01X185797Y1125930D02*
X185664Y1125996D01*
Y1126130D01*
X185797Y1126196D01*
X185930Y1126130D01*
Y1125996D01*
X185797Y1125930D01*
G01X190397Y1130063D02*
X189864Y1129930D01*
X189464Y1129596D01*
X189197Y1129196D01*
X188997Y1128663D01*
X188930Y1128063D01*
X188997Y1127463D01*
X189197Y1126930D01*
X189464Y1126530D01*
X189864Y1126196D01*
X190397Y1126063D01*
X190930Y1126196D01*
X191330Y1126530D01*
X191597Y1126930D01*
X191797Y1127463D01*
X191864Y1128063D01*
X191797Y1128663D01*
X191597Y1129196D01*
X191330Y1129596D01*
X190930Y1129930D01*
X190397Y1130063D01*
G01X194997Y1126063D02*
X195464Y1126130D01*
X195997Y1126330D01*
X196330Y1126663D01*
X196464Y1127130D01*
X196330Y1127596D01*
X195930Y1127996D01*
X195330Y1128196D01*
X194664D01*
X194264Y1128330D01*
X193930Y1128663D01*
X193797Y1129130D01*
X193997Y1129596D01*
X194464Y1129930D01*
X194997Y1130063D01*
X195530Y1129930D01*
X195997Y1129596D01*
X196197Y1129130D01*
X196064Y1128663D01*
X195730Y1128330D01*
X195330Y1128196D01*
X194664D01*
X194064Y1127996D01*
X193664Y1127596D01*
X193530Y1127130D01*
X193664Y1126663D01*
X193997Y1126330D01*
X194530Y1126130D01*
X194997Y1126063D01*
G01X114295Y1170224D02*
G03X148106I16905J-13531D01*
G01X114295D02*
G03X148106I16905J-13531D01*
G01X166334Y1168220D02*
Y1172220D01*
X167668D01*
X168201Y1172020D01*
X168601Y1171753D01*
X168934Y1171353D01*
X169201Y1170887D01*
X169268Y1170220D01*
X169201Y1169553D01*
X168934Y1169087D01*
X168601Y1168687D01*
X168201Y1168420D01*
X167668Y1168220D01*
X166334D01*
G01X171468D02*
Y1170887D01*
G01Y1170353D02*
X171801Y1170620D01*
X172134Y1170820D01*
X172601Y1170887D01*
X172934Y1170820D01*
X173334Y1170620D01*
G01X177001Y1170887D02*
Y1168220D01*
G01Y1171953D02*
X176868Y1172020D01*
Y1172153D01*
X177001Y1172220D01*
X177134Y1172153D01*
Y1172020D01*
X177001Y1171953D01*
G01X181601Y1168220D02*
Y1172220D01*
G01X186201Y1168220D02*
Y1172220D01*
G01X195001Y1168220D02*
Y1171620D01*
X195134Y1171953D01*
X195401Y1172153D01*
X195801Y1172220D01*
X196201Y1172087D01*
X196401Y1171753D01*
G01X195601Y1170620D02*
X194268D01*
G01X199001Y1170020D02*
X201134D01*
X200934Y1170487D01*
X200601Y1170753D01*
X200134Y1170887D01*
X199668Y1170820D01*
X199268Y1170620D01*
X199001Y1170153D01*
X198868Y1169753D01*
Y1169353D01*
X199001Y1168953D01*
X199334Y1168553D01*
X199734Y1168287D01*
X200201Y1168220D01*
X200668Y1168353D01*
X201134Y1168753D01*
G01X205801Y1168220D02*
Y1170887D01*
G01Y1170420D02*
X205534Y1170687D01*
X205134Y1170820D01*
X204668Y1170887D01*
X204201Y1170753D01*
X203801Y1170487D01*
X203534Y1170087D01*
X203401Y1169553D01*
X203534Y1169020D01*
X203801Y1168620D01*
X204201Y1168353D01*
X204668Y1168220D01*
X205134Y1168287D01*
X205534Y1168487D01*
X205801Y1168753D01*
G01X209201Y1172220D02*
Y1168220D01*
G01X208268Y1170887D02*
X210134D01*
G01X212668D02*
Y1169020D01*
X212934Y1168553D01*
X213334Y1168287D01*
X213801Y1168220D01*
X214268Y1168287D01*
X214668Y1168553D01*
X214934Y1169020D01*
G01Y1168220D02*
Y1170887D01*
G01X217468Y1168220D02*
Y1170887D01*
G01Y1170353D02*
X217801Y1170620D01*
X218134Y1170820D01*
X218601Y1170887D01*
X218934Y1170820D01*
X219334Y1170620D01*
G01X222001Y1170020D02*
X224134D01*
X223934Y1170487D01*
X223601Y1170753D01*
X223134Y1170887D01*
X222668Y1170820D01*
X222268Y1170620D01*
X222001Y1170153D01*
X221868Y1169753D01*
Y1169353D01*
X222001Y1168953D01*
X222334Y1168553D01*
X222734Y1168287D01*
X223201Y1168220D01*
X223668Y1168353D01*
X224134Y1168753D01*
G01X172889Y1210387D02*
X173289Y1210787D01*
X173756Y1210987D01*
X174289Y1211054D01*
X174956Y1210921D01*
X175423Y1210587D01*
X175556Y1210187D01*
X175489Y1209787D01*
X175223Y1209454D01*
X173889Y1208787D01*
X173289Y1208321D01*
X172889Y1207654D01*
X172756Y1207054D01*
X175556D01*
G01X178756Y1211054D02*
X178223Y1210921D01*
X177823Y1210587D01*
X177556Y1210187D01*
X177356Y1209654D01*
X177289Y1209054D01*
X177356Y1208454D01*
X177556Y1207921D01*
X177823Y1207521D01*
X178223Y1207187D01*
X178756Y1207054D01*
X179289Y1207187D01*
X179689Y1207521D01*
X179956Y1207921D01*
X180156Y1208454D01*
X180223Y1209054D01*
X180156Y1209654D01*
X179956Y1210187D01*
X179689Y1210587D01*
X179289Y1210921D01*
X178756Y1211054D01*
G01X183356Y1207054D02*
X183823Y1207121D01*
X184356Y1207321D01*
X184689Y1207654D01*
X184823Y1208121D01*
X184689Y1208587D01*
X184289Y1208987D01*
X183689Y1209187D01*
X183023D01*
X182623Y1209321D01*
X182289Y1209654D01*
X182156Y1210121D01*
X182356Y1210587D01*
X182823Y1210921D01*
X183356Y1211054D01*
X183889Y1210921D01*
X184356Y1210587D01*
X184556Y1210121D01*
X184423Y1209654D01*
X184089Y1209321D01*
X183689Y1209187D01*
X183023D01*
X182423Y1208987D01*
X182023Y1208587D01*
X181889Y1208121D01*
X182023Y1207654D01*
X182356Y1207321D01*
X182889Y1207121D01*
X183356Y1207054D01*
G01X187956Y1206921D02*
X187823Y1206987D01*
Y1207121D01*
X187956Y1207187D01*
X188089Y1207121D01*
Y1206987D01*
X187956Y1206921D01*
G01X191289Y1208721D02*
X191756Y1209187D01*
X192156Y1209454D01*
X192689Y1209587D01*
X193156Y1209454D01*
X193489Y1209187D01*
X193756Y1208787D01*
X193823Y1208321D01*
X193756Y1207921D01*
X193489Y1207521D01*
X193089Y1207187D01*
X192623Y1207054D01*
X192089Y1207187D01*
X191623Y1207587D01*
X191356Y1208187D01*
X191289Y1208854D01*
X191423Y1209721D01*
X191623Y1210187D01*
X191956Y1210654D01*
X192423Y1210987D01*
X192889Y1211054D01*
X193356Y1210921D01*
X193689Y1210587D01*
G01X195889Y1208721D02*
X196356Y1209187D01*
X196756Y1209454D01*
X197289Y1209587D01*
X197756Y1209454D01*
X198089Y1209187D01*
X198356Y1208787D01*
X198423Y1208321D01*
X198356Y1207921D01*
X198089Y1207521D01*
X197689Y1207187D01*
X197223Y1207054D01*
X196689Y1207187D01*
X196223Y1207587D01*
X195956Y1208187D01*
X195889Y1208854D01*
X196023Y1209721D01*
X196223Y1210187D01*
X196556Y1210654D01*
X197023Y1210987D01*
X197489Y1211054D01*
X197956Y1210921D01*
X198289Y1210587D01*
G01X141181Y1183355D02*
G03X148106Y1170224I37662J11471D01*
G01X141181Y1183355D02*
G03X148106Y1170224I37662J11471D01*
G01X141181Y1183355D02*
G03X121220I-9980J-3040D01*
G01X141181D02*
G03X121220I-9980J-3040D01*
G01X114295Y1170224D02*
G03X121220Y1183355I-30737J24602D01*
G01X114295Y1170224D02*
G03X121220Y1183355I-30737J24601D01*
G01X280709Y1519685D02*
X101378D01*
G01X280709D02*
X101378D01*
G01X269552Y1301147D02*
Y1305147D01*
X271152D01*
X271685Y1304947D01*
X272085Y1304480D01*
X272218Y1303947D01*
X272085Y1303414D01*
X271752Y1303014D01*
X271152Y1302814D01*
X269552D01*
G01X274552Y1301147D02*
Y1303814D01*
G01Y1303280D02*
X274885Y1303547D01*
X275218Y1303747D01*
X275685Y1303814D01*
X276018Y1303747D01*
X276418Y1303547D01*
G01X279085Y1302947D02*
X281218D01*
X281018Y1303414D01*
X280685Y1303680D01*
X280218Y1303814D01*
X279752Y1303747D01*
X279352Y1303547D01*
X279085Y1303080D01*
X278952Y1302680D01*
Y1302280D01*
X279085Y1301880D01*
X279418Y1301480D01*
X279818Y1301214D01*
X280285Y1301147D01*
X280752Y1301280D01*
X281218Y1301680D01*
G01X283685Y1301614D02*
X284018Y1301347D01*
X284485Y1301147D01*
X284885D01*
X285285Y1301280D01*
X285552Y1301480D01*
X285685Y1301747D01*
X285618Y1302147D01*
X285352Y1302347D01*
X284152Y1302747D01*
X283885Y1303214D01*
X284018Y1303547D01*
X284285Y1303747D01*
X284685Y1303814D01*
X285085Y1303747D01*
X285485Y1303547D01*
G01X288285Y1301614D02*
X288618Y1301347D01*
X289085Y1301147D01*
X289485D01*
X289885Y1301280D01*
X290152Y1301480D01*
X290285Y1301747D01*
X290218Y1302147D01*
X289952Y1302347D01*
X288752Y1302747D01*
X288485Y1303214D01*
X288618Y1303547D01*
X288885Y1303747D01*
X289285Y1303814D01*
X289685Y1303747D01*
X290085Y1303547D01*
G01X293018Y1302480D02*
X294752D01*
G01X298085Y1301147D02*
Y1304547D01*
X298218Y1304880D01*
X298485Y1305080D01*
X298885Y1305147D01*
X299285Y1305014D01*
X299485Y1304680D01*
G01X298685Y1303547D02*
X297352D01*
G01X303085Y1303814D02*
Y1301147D01*
G01Y1304880D02*
X302952Y1304947D01*
Y1305080D01*
X303085Y1305147D01*
X303218Y1305080D01*
Y1304947D01*
X303085Y1304880D01*
G01X307685Y1305147D02*
Y1301147D01*
G01X306752Y1303814D02*
X308618D01*
G01X315552Y1301147D02*
Y1305147D01*
X317152D01*
X317685Y1304947D01*
X318085Y1304480D01*
X318218Y1303947D01*
X318085Y1303414D01*
X317752Y1303014D01*
X317152Y1302814D01*
X315552D01*
G01X321485Y1305147D02*
Y1301147D01*
G01X319952Y1305147D02*
X323018D01*
G01X324685Y1301147D02*
Y1305147D01*
G01X327485D02*
Y1301147D01*
G01Y1303147D02*
X324685D01*
G01X334152Y1301147D02*
Y1305147D01*
G01X336285Y1303814D02*
X334152Y1302280D01*
G01X335018Y1302880D02*
X336418Y1301147D01*
G01X338885Y1302947D02*
X341018D01*
X340818Y1303414D01*
X340485Y1303680D01*
X340018Y1303814D01*
X339552Y1303747D01*
X339152Y1303547D01*
X338885Y1303080D01*
X338752Y1302680D01*
Y1302280D01*
X338885Y1301880D01*
X339218Y1301480D01*
X339618Y1301214D01*
X340085Y1301147D01*
X340552Y1301280D01*
X341018Y1301680D01*
G01X343485Y1302947D02*
X345618D01*
X345418Y1303414D01*
X345085Y1303680D01*
X344618Y1303814D01*
X344152Y1303747D01*
X343752Y1303547D01*
X343485Y1303080D01*
X343352Y1302680D01*
Y1302280D01*
X343485Y1301880D01*
X343818Y1301480D01*
X344218Y1301214D01*
X344685Y1301147D01*
X345152Y1301280D01*
X345618Y1301680D01*
G01X347885Y1299814D02*
Y1303814D01*
G01Y1303214D02*
X348218Y1303547D01*
X348552Y1303747D01*
X349085Y1303814D01*
X349552Y1303747D01*
X350018Y1303414D01*
X350218Y1302947D01*
X350285Y1302480D01*
X350218Y1302014D01*
X350018Y1301547D01*
X349618Y1301280D01*
X349085Y1301147D01*
X348618Y1301214D01*
X348152Y1301414D01*
X347885Y1301680D01*
G01X357152Y1301147D02*
Y1305147D01*
G01Y1303214D02*
X357485Y1303547D01*
X357818Y1303747D01*
X358352Y1303814D01*
X358752Y1303747D01*
X359218Y1303480D01*
X359418Y1303080D01*
Y1301147D01*
G01X362885D02*
X362485Y1301214D01*
X362085Y1301480D01*
X361818Y1301947D01*
X361685Y1302480D01*
X361818Y1303014D01*
X362085Y1303480D01*
X362485Y1303747D01*
X362885Y1303814D01*
X363285Y1303747D01*
X363685Y1303480D01*
X363952Y1303014D01*
X364018Y1302480D01*
X363952Y1301947D01*
X363685Y1301480D01*
X363285Y1301214D01*
X362885Y1301147D01*
G01X367485D02*
Y1305147D01*
G01X371085Y1302947D02*
X373218D01*
X373018Y1303414D01*
X372685Y1303680D01*
X372218Y1303814D01*
X371752Y1303747D01*
X371352Y1303547D01*
X371085Y1303080D01*
X370952Y1302680D01*
Y1302280D01*
X371085Y1301880D01*
X371418Y1301480D01*
X371818Y1301214D01*
X372285Y1301147D01*
X372752Y1301280D01*
X373218Y1301680D01*
G01X380285Y1301614D02*
X380618Y1301347D01*
X381085Y1301147D01*
X381485D01*
X381885Y1301280D01*
X382152Y1301480D01*
X382285Y1301747D01*
X382218Y1302147D01*
X381952Y1302347D01*
X380752Y1302747D01*
X380485Y1303214D01*
X380618Y1303547D01*
X380885Y1303747D01*
X381285Y1303814D01*
X381685Y1303747D01*
X382085Y1303547D01*
G01X385885Y1303814D02*
Y1301147D01*
G01Y1304880D02*
X385752Y1304947D01*
Y1305080D01*
X385885Y1305147D01*
X386018Y1305080D01*
Y1304947D01*
X385885Y1304880D01*
G01X389485Y1303814D02*
X391485D01*
X389485Y1301147D01*
X391485D01*
G01X394085Y1302947D02*
X396218D01*
X396018Y1303414D01*
X395685Y1303680D01*
X395218Y1303814D01*
X394752Y1303747D01*
X394352Y1303547D01*
X394085Y1303080D01*
X393952Y1302680D01*
Y1302280D01*
X394085Y1301880D01*
X394418Y1301480D01*
X394818Y1301214D01*
X395285Y1301147D01*
X395752Y1301280D01*
X396218Y1301680D01*
G01X404285Y1305147D02*
Y1301147D01*
G01X403352Y1303814D02*
X405218D01*
G01X408885Y1301147D02*
X408485Y1301214D01*
X408085Y1301480D01*
X407818Y1301947D01*
X407685Y1302480D01*
X407818Y1303014D01*
X408085Y1303480D01*
X408485Y1303747D01*
X408885Y1303814D01*
X409285Y1303747D01*
X409685Y1303480D01*
X409952Y1303014D01*
X410018Y1302480D01*
X409952Y1301947D01*
X409685Y1301480D01*
X409285Y1301214D01*
X408885Y1301147D01*
G01X413485D02*
Y1305147D01*
G01X417085Y1302947D02*
X419218D01*
X419018Y1303414D01*
X418685Y1303680D01*
X418218Y1303814D01*
X417752Y1303747D01*
X417352Y1303547D01*
X417085Y1303080D01*
X416952Y1302680D01*
Y1302280D01*
X417085Y1301880D01*
X417418Y1301480D01*
X417818Y1301214D01*
X418285Y1301147D01*
X418752Y1301280D01*
X419218Y1301680D01*
G01X421752Y1301147D02*
Y1303814D01*
G01Y1303280D02*
X422085Y1303547D01*
X422418Y1303747D01*
X422885Y1303814D01*
X423218Y1303747D01*
X423618Y1303547D01*
G01X428485Y1301147D02*
Y1303814D01*
G01Y1303347D02*
X428218Y1303614D01*
X427818Y1303747D01*
X427352Y1303814D01*
X426885Y1303680D01*
X426485Y1303414D01*
X426218Y1303014D01*
X426085Y1302480D01*
X426218Y1301947D01*
X426485Y1301547D01*
X426885Y1301280D01*
X427352Y1301147D01*
X427818Y1301214D01*
X428218Y1301414D01*
X428485Y1301680D01*
G01X430752Y1301147D02*
Y1303814D01*
G01Y1303147D02*
X431018Y1303480D01*
X431418Y1303747D01*
X431952Y1303814D01*
X432418Y1303747D01*
X432818Y1303480D01*
X433018Y1303014D01*
Y1301147D01*
G01X437552Y1303480D02*
X437085Y1303747D01*
X436685Y1303814D01*
X436152Y1303680D01*
X435752Y1303414D01*
X435485Y1302947D01*
X435418Y1302480D01*
X435485Y1302014D01*
X435752Y1301614D01*
X436152Y1301280D01*
X436685Y1301147D01*
X437152Y1301280D01*
X437552Y1301547D01*
G01X440085Y1302947D02*
X442218D01*
X442018Y1303414D01*
X441685Y1303680D01*
X441218Y1303814D01*
X440752Y1303747D01*
X440352Y1303547D01*
X440085Y1303080D01*
X439952Y1302680D01*
Y1302280D01*
X440085Y1301880D01*
X440418Y1301480D01*
X440818Y1301214D01*
X441285Y1301147D01*
X441752Y1301280D01*
X442218Y1301680D01*
G01X449552Y1302480D02*
X451152D01*
G01X450285Y1303347D02*
Y1301614D01*
G01X453685Y1301014D02*
X456085Y1305147D01*
G01X458618Y1302480D02*
X460352D01*
G01X462818Y1304480D02*
X463218Y1304880D01*
X463685Y1305080D01*
X464218Y1305147D01*
X464885Y1305014D01*
X465352Y1304680D01*
X465485Y1304280D01*
X465418Y1303880D01*
X465152Y1303547D01*
X463818Y1302880D01*
X463218Y1302414D01*
X462818Y1301747D01*
X462685Y1301147D01*
X465485D01*
G01X471285D02*
Y1303814D01*
G01Y1303080D02*
X471485Y1303414D01*
X471818Y1303680D01*
X472285Y1303814D01*
X472752Y1303680D01*
X473085Y1303414D01*
X473285Y1303080D01*
Y1301147D01*
G01Y1303080D02*
X473485Y1303414D01*
X473818Y1303680D01*
X474285Y1303814D01*
X474752Y1303680D01*
X475085Y1303414D01*
X475285Y1303014D01*
Y1301147D01*
G01X477885Y1303814D02*
Y1301147D01*
G01Y1304880D02*
X477752Y1304947D01*
Y1305080D01*
X477885Y1305147D01*
X478018Y1305080D01*
Y1304947D01*
X477885Y1304880D01*
G01X482485Y1301147D02*
Y1305147D01*
G01X486085Y1301614D02*
X486418Y1301347D01*
X486885Y1301147D01*
X487285D01*
X487685Y1301280D01*
X487952Y1301480D01*
X488085Y1301747D01*
X488018Y1302147D01*
X487752Y1302347D01*
X486552Y1302747D01*
X486285Y1303214D01*
X486418Y1303547D01*
X486685Y1303747D01*
X487085Y1303814D01*
X487485Y1303747D01*
X487885Y1303547D01*
G01X290255Y1354272D02*
X487855D01*
Y1316672D01*
X290255D01*
Y1354272D01*
G01X284646Y1515748D02*
G03X280709Y1519685I-3937J0D01*
G01X284646Y1515748D02*
G03X280709Y1519685I-3937J0D01*
G01X284646Y1500000D02*
Y1515748D01*
G01Y1500000D02*
G03X288583Y1496063I3937J0D01*
G01X493307D02*
X288583D01*
G01X284646Y1500000D02*
G03X288583Y1496063I3937J0D01*
G01X493307D02*
X288583D01*
G01X284646Y1515748D02*
Y1500000D01*
G01X302795Y253600D02*
X303195Y253267D01*
X303662Y253067D01*
X304262Y253000D01*
X304862Y253133D01*
X305329Y253400D01*
X305662Y253867D01*
X305729Y254400D01*
X305595Y254933D01*
X305262Y255267D01*
X304795Y255533D01*
X304329Y255600D01*
X303862Y255533D01*
X303262Y255267D01*
X303462Y257000D01*
X305262D01*
G01X307395Y253600D02*
X307795Y253267D01*
X308262Y253067D01*
X308862Y253000D01*
X309462Y253133D01*
X309929Y253400D01*
X310262Y253867D01*
X310329Y254400D01*
X310195Y254933D01*
X309862Y255267D01*
X309395Y255533D01*
X308929Y255600D01*
X308462Y255533D01*
X307862Y255267D01*
X308062Y257000D01*
X309862D01*
G01X313329Y253000D02*
X313462Y253867D01*
X313662Y254600D01*
X313929Y255267D01*
X314262Y256000D01*
X314795Y257000D01*
X312129D01*
G01X318062Y252867D02*
X317929Y252933D01*
Y253067D01*
X318062Y253133D01*
X318195Y253067D01*
Y252933D01*
X318062Y252867D01*
G01X322662Y257000D02*
X322129Y256867D01*
X321729Y256533D01*
X321462Y256133D01*
X321262Y255600D01*
X321195Y255000D01*
X321262Y254400D01*
X321462Y253867D01*
X321729Y253467D01*
X322129Y253133D01*
X322662Y253000D01*
X323195Y253133D01*
X323595Y253467D01*
X323862Y253867D01*
X324062Y254400D01*
X324129Y255000D01*
X324062Y255600D01*
X323862Y256133D01*
X323595Y256533D01*
X323195Y256867D01*
X322662Y257000D01*
G01X326129Y253467D02*
X326595Y253133D01*
X327129Y253000D01*
X327662Y253133D01*
X328129Y253533D01*
X328462Y254133D01*
X328595Y254733D01*
Y255467D01*
X328462Y256067D01*
X328129Y256600D01*
X327729Y256867D01*
X327262Y257000D01*
X326729Y256867D01*
X326329Y256600D01*
X326062Y256200D01*
X325929Y255667D01*
X326062Y255200D01*
X326395Y254733D01*
X326795Y254467D01*
X327262Y254400D01*
X327795Y254533D01*
X328195Y254867D01*
X328595Y255467D01*
G01X320134Y264146D02*
X320534Y264546D01*
X321001Y264746D01*
X321534Y264813D01*
X322201Y264680D01*
X322668Y264346D01*
X322801Y263946D01*
X322734Y263546D01*
X322468Y263213D01*
X321134Y262546D01*
X320534Y262080D01*
X320134Y261413D01*
X320001Y260813D01*
X322801D01*
G01X324534Y261613D02*
X324934Y261146D01*
X325468Y260880D01*
X326068Y260813D01*
X326601Y260880D01*
X327134Y261213D01*
X327468Y261613D01*
X327534Y262013D01*
X327401Y262480D01*
X326934Y262813D01*
X326468Y262946D01*
X325868D01*
G01X326468D02*
X326868Y263146D01*
X327201Y263480D01*
X327334Y263880D01*
X327201Y264280D01*
X326868Y264613D01*
X326268Y264813D01*
X325668Y264746D01*
X325068Y264480D01*
G01X329334Y262480D02*
X329801Y262946D01*
X330201Y263213D01*
X330734Y263346D01*
X331201Y263213D01*
X331534Y262946D01*
X331801Y262546D01*
X331868Y262080D01*
X331801Y261680D01*
X331534Y261280D01*
X331134Y260946D01*
X330668Y260813D01*
X330134Y260946D01*
X329668Y261346D01*
X329401Y261946D01*
X329334Y262613D01*
X329468Y263480D01*
X329668Y263946D01*
X330001Y264413D01*
X330468Y264746D01*
X330934Y264813D01*
X331401Y264680D01*
X331734Y264346D01*
G01X335201Y260680D02*
X335068Y260746D01*
Y260880D01*
X335201Y260946D01*
X335334Y260880D01*
Y260746D01*
X335201Y260680D01*
G01X338534Y264146D02*
X338934Y264546D01*
X339401Y264746D01*
X339934Y264813D01*
X340601Y264680D01*
X341068Y264346D01*
X341201Y263946D01*
X341134Y263546D01*
X340868Y263213D01*
X339534Y262546D01*
X338934Y262080D01*
X338534Y261413D01*
X338401Y260813D01*
X341201D01*
G01X343134Y264146D02*
X343534Y264546D01*
X344001Y264746D01*
X344534Y264813D01*
X345201Y264680D01*
X345668Y264346D01*
X345801Y263946D01*
X345734Y263546D01*
X345468Y263213D01*
X344134Y262546D01*
X343534Y262080D01*
X343134Y261413D01*
X343001Y260813D01*
X345801D01*
G01X389213Y277843D02*
G03X369252I-9981J-3040D01*
G01X389213D02*
G03X369252I-9981J-3040D01*
G01X362327Y264712D02*
G03X369252Y277843I-30737J24602D01*
G01X362327Y264712D02*
G03X369252Y277843I-30737J24602D01*
G01X362327Y264712D02*
G03X396138I16905J-13531D01*
G01X362327D02*
G03X396138I16905J-13531D01*
G01X302795Y706356D02*
X303195Y706023D01*
X303662Y705823D01*
X304262Y705756D01*
X304862Y705889D01*
X305329Y706156D01*
X305662Y706623D01*
X305729Y707156D01*
X305595Y707689D01*
X305262Y708023D01*
X304795Y708289D01*
X304329Y708356D01*
X303862Y708289D01*
X303262Y708023D01*
X303462Y709756D01*
X305262D01*
G01X307395Y706356D02*
X307795Y706023D01*
X308262Y705823D01*
X308862Y705756D01*
X309462Y705889D01*
X309929Y706156D01*
X310262Y706623D01*
X310329Y707156D01*
X310195Y707689D01*
X309862Y708023D01*
X309395Y708289D01*
X308929Y708356D01*
X308462Y708289D01*
X307862Y708023D01*
X308062Y709756D01*
X309862D01*
G01X313329Y705756D02*
X313462Y706623D01*
X313662Y707356D01*
X313929Y708023D01*
X314262Y708756D01*
X314795Y709756D01*
X312129D01*
G01X318062Y705623D02*
X317929Y705689D01*
Y705823D01*
X318062Y705889D01*
X318195Y705823D01*
Y705689D01*
X318062Y705623D01*
G01X322662Y709756D02*
X322129Y709623D01*
X321729Y709289D01*
X321462Y708889D01*
X321262Y708356D01*
X321195Y707756D01*
X321262Y707156D01*
X321462Y706623D01*
X321729Y706223D01*
X322129Y705889D01*
X322662Y705756D01*
X323195Y705889D01*
X323595Y706223D01*
X323862Y706623D01*
X324062Y707156D01*
X324129Y707756D01*
X324062Y708356D01*
X323862Y708889D01*
X323595Y709289D01*
X323195Y709623D01*
X322662Y709756D01*
G01X326129Y706223D02*
X326595Y705889D01*
X327129Y705756D01*
X327662Y705889D01*
X328129Y706289D01*
X328462Y706889D01*
X328595Y707489D01*
Y708223D01*
X328462Y708823D01*
X328129Y709356D01*
X327729Y709623D01*
X327262Y709756D01*
X326729Y709623D01*
X326329Y709356D01*
X326062Y708956D01*
X325929Y708423D01*
X326062Y707956D01*
X326395Y707489D01*
X326795Y707223D01*
X327262Y707156D01*
X327795Y707289D01*
X328195Y707623D01*
X328595Y708223D01*
G01X320134Y716902D02*
X320534Y717302D01*
X321001Y717502D01*
X321534Y717569D01*
X322201Y717436D01*
X322668Y717102D01*
X322801Y716702D01*
X322734Y716302D01*
X322468Y715969D01*
X321134Y715302D01*
X320534Y714836D01*
X320134Y714169D01*
X320001Y713569D01*
X322801D01*
G01X324534Y714369D02*
X324934Y713902D01*
X325468Y713636D01*
X326068Y713569D01*
X326601Y713636D01*
X327134Y713969D01*
X327468Y714369D01*
X327534Y714769D01*
X327401Y715236D01*
X326934Y715569D01*
X326468Y715702D01*
X325868D01*
G01X326468D02*
X326868Y715902D01*
X327201Y716236D01*
X327334Y716636D01*
X327201Y717036D01*
X326868Y717369D01*
X326268Y717569D01*
X325668Y717502D01*
X325068Y717236D01*
G01X329334Y715236D02*
X329801Y715702D01*
X330201Y715969D01*
X330734Y716102D01*
X331201Y715969D01*
X331534Y715702D01*
X331801Y715302D01*
X331868Y714836D01*
X331801Y714436D01*
X331534Y714036D01*
X331134Y713702D01*
X330668Y713569D01*
X330134Y713702D01*
X329668Y714102D01*
X329401Y714702D01*
X329334Y715369D01*
X329468Y716236D01*
X329668Y716702D01*
X330001Y717169D01*
X330468Y717502D01*
X330934Y717569D01*
X331401Y717436D01*
X331734Y717102D01*
G01X335201Y713436D02*
X335068Y713502D01*
Y713636D01*
X335201Y713702D01*
X335334Y713636D01*
Y713502D01*
X335201Y713436D01*
G01X338534Y716902D02*
X338934Y717302D01*
X339401Y717502D01*
X339934Y717569D01*
X340601Y717436D01*
X341068Y717102D01*
X341201Y716702D01*
X341134Y716302D01*
X340868Y715969D01*
X339534Y715302D01*
X338934Y714836D01*
X338534Y714169D01*
X338401Y713569D01*
X341201D01*
G01X343134Y716902D02*
X343534Y717302D01*
X344001Y717502D01*
X344534Y717569D01*
X345201Y717436D01*
X345668Y717102D01*
X345801Y716702D01*
X345734Y716302D01*
X345468Y715969D01*
X344134Y715302D01*
X343534Y714836D01*
X343134Y714169D01*
X343001Y713569D01*
X345801D01*
G01X389213Y730599D02*
G03X369252I-9981J-3040D01*
G01X389213D02*
G03X369252I-9981J-3040D01*
G01X362327Y717468D02*
G03X369252Y730599I-30737J24602D01*
G01X362327Y717468D02*
G03X369252Y730599I-30737J24602D01*
G01X362327Y717468D02*
G03X396138I16905J-13531D01*
G01X362327D02*
G03X396138I16905J-13531D01*
G01X362327Y1170224D02*
G03X396138I16905J-13531D01*
G01X362327D02*
G03X396138I16905J-13531D01*
G01X302795Y1159111D02*
X303195Y1158778D01*
X303662Y1158578D01*
X304262Y1158511D01*
X304862Y1158644D01*
X305329Y1158911D01*
X305662Y1159378D01*
X305729Y1159911D01*
X305595Y1160444D01*
X305262Y1160778D01*
X304795Y1161044D01*
X304329Y1161111D01*
X303862Y1161044D01*
X303262Y1160778D01*
X303462Y1162511D01*
X305262D01*
G01X307395Y1159111D02*
X307795Y1158778D01*
X308262Y1158578D01*
X308862Y1158511D01*
X309462Y1158644D01*
X309929Y1158911D01*
X310262Y1159378D01*
X310329Y1159911D01*
X310195Y1160444D01*
X309862Y1160778D01*
X309395Y1161044D01*
X308929Y1161111D01*
X308462Y1161044D01*
X307862Y1160778D01*
X308062Y1162511D01*
X309862D01*
G01X313329Y1158511D02*
X313462Y1159378D01*
X313662Y1160111D01*
X313929Y1160778D01*
X314262Y1161511D01*
X314795Y1162511D01*
X312129D01*
G01X318062Y1158378D02*
X317929Y1158444D01*
Y1158578D01*
X318062Y1158644D01*
X318195Y1158578D01*
Y1158444D01*
X318062Y1158378D01*
G01X322662Y1162511D02*
X322129Y1162378D01*
X321729Y1162044D01*
X321462Y1161644D01*
X321262Y1161111D01*
X321195Y1160511D01*
X321262Y1159911D01*
X321462Y1159378D01*
X321729Y1158978D01*
X322129Y1158644D01*
X322662Y1158511D01*
X323195Y1158644D01*
X323595Y1158978D01*
X323862Y1159378D01*
X324062Y1159911D01*
X324129Y1160511D01*
X324062Y1161111D01*
X323862Y1161644D01*
X323595Y1162044D01*
X323195Y1162378D01*
X322662Y1162511D01*
G01X326129Y1158978D02*
X326595Y1158644D01*
X327129Y1158511D01*
X327662Y1158644D01*
X328129Y1159044D01*
X328462Y1159644D01*
X328595Y1160244D01*
Y1160978D01*
X328462Y1161578D01*
X328129Y1162111D01*
X327729Y1162378D01*
X327262Y1162511D01*
X326729Y1162378D01*
X326329Y1162111D01*
X326062Y1161711D01*
X325929Y1161178D01*
X326062Y1160711D01*
X326395Y1160244D01*
X326795Y1159978D01*
X327262Y1159911D01*
X327795Y1160044D01*
X328195Y1160378D01*
X328595Y1160978D01*
G01X320134Y1169657D02*
X320534Y1170057D01*
X321001Y1170257D01*
X321534Y1170324D01*
X322201Y1170191D01*
X322668Y1169857D01*
X322801Y1169457D01*
X322734Y1169057D01*
X322468Y1168724D01*
X321134Y1168057D01*
X320534Y1167591D01*
X320134Y1166924D01*
X320001Y1166324D01*
X322801D01*
G01X324534Y1167124D02*
X324934Y1166657D01*
X325468Y1166391D01*
X326068Y1166324D01*
X326601Y1166391D01*
X327134Y1166724D01*
X327468Y1167124D01*
X327534Y1167524D01*
X327401Y1167991D01*
X326934Y1168324D01*
X326468Y1168457D01*
X325868D01*
G01X326468D02*
X326868Y1168657D01*
X327201Y1168991D01*
X327334Y1169391D01*
X327201Y1169791D01*
X326868Y1170124D01*
X326268Y1170324D01*
X325668Y1170257D01*
X325068Y1169991D01*
G01X329334Y1167991D02*
X329801Y1168457D01*
X330201Y1168724D01*
X330734Y1168857D01*
X331201Y1168724D01*
X331534Y1168457D01*
X331801Y1168057D01*
X331868Y1167591D01*
X331801Y1167191D01*
X331534Y1166791D01*
X331134Y1166457D01*
X330668Y1166324D01*
X330134Y1166457D01*
X329668Y1166857D01*
X329401Y1167457D01*
X329334Y1168124D01*
X329468Y1168991D01*
X329668Y1169457D01*
X330001Y1169924D01*
X330468Y1170257D01*
X330934Y1170324D01*
X331401Y1170191D01*
X331734Y1169857D01*
G01X335201Y1166191D02*
X335068Y1166257D01*
Y1166391D01*
X335201Y1166457D01*
X335334Y1166391D01*
Y1166257D01*
X335201Y1166191D01*
G01X338534Y1169657D02*
X338934Y1170057D01*
X339401Y1170257D01*
X339934Y1170324D01*
X340601Y1170191D01*
X341068Y1169857D01*
X341201Y1169457D01*
X341134Y1169057D01*
X340868Y1168724D01*
X339534Y1168057D01*
X338934Y1167591D01*
X338534Y1166924D01*
X338401Y1166324D01*
X341201D01*
G01X343134Y1169657D02*
X343534Y1170057D01*
X344001Y1170257D01*
X344534Y1170324D01*
X345201Y1170191D01*
X345668Y1169857D01*
X345801Y1169457D01*
X345734Y1169057D01*
X345468Y1168724D01*
X344134Y1168057D01*
X343534Y1167591D01*
X343134Y1166924D01*
X343001Y1166324D01*
X345801D01*
G01X389213Y1183355D02*
G03X369252I-9981J-3040D01*
G01X389213D02*
G03X369252I-9981J-3040D01*
G01X362327Y1170224D02*
G03X369252Y1183355I-30737J24602D01*
G01X362327Y1170224D02*
G03X369252Y1183355I-30737J24602D01*
G01X388160Y1306547D02*
Y1316247D01*
X393160Y1311247D01*
X383160D01*
X388160Y1316247D01*
G01X322441Y1503937D02*
G03Y1496063I0J-3937D01*
G01X459449Y1503937D02*
X322441D01*
G01X459449D02*
X322441D01*
G01D02*
G03Y1496063I0J-3937D01*
G01X296457Y1519685D02*
G03X292520Y1515748I0J-3937D01*
G01X296457Y1519685D02*
X485433D01*
G01X296457D02*
G03X292520Y1515748I0J-3937D01*
G01X296457Y1519685D02*
X485433D01*
G01X304331Y1503937D02*
X292520D01*
G01Y1515748D02*
Y1503937D01*
G01X304331D02*
X292520D01*
G01Y1515748D02*
Y1503937D01*
G01X304331Y1496063D02*
G03Y1503937I0J3937D01*
G01Y1496063D02*
G03Y1503937I0J3937D01*
G01X420829Y220552D02*
Y224552D01*
X418362Y221685D01*
X421696D01*
G01X423162Y221352D02*
X423562Y220885D01*
X424096Y220619D01*
X424696Y220552D01*
X425229Y220619D01*
X425762Y220952D01*
X426096Y221352D01*
X426162Y221752D01*
X426029Y222219D01*
X425562Y222552D01*
X425096Y222685D01*
X424496D01*
G01X425096D02*
X425496Y222885D01*
X425829Y223219D01*
X425962Y223619D01*
X425829Y224019D01*
X425496Y224352D01*
X424896Y224552D01*
X424296Y224485D01*
X423696Y224219D01*
G01X427762Y221352D02*
X428162Y220885D01*
X428696Y220619D01*
X429296Y220552D01*
X429829Y220619D01*
X430362Y220952D01*
X430696Y221352D01*
X430762Y221752D01*
X430629Y222219D01*
X430162Y222552D01*
X429696Y222685D01*
X429096D01*
G01X429696D02*
X430096Y222885D01*
X430429Y223219D01*
X430562Y223619D01*
X430429Y224019D01*
X430096Y224352D01*
X429496Y224552D01*
X428896Y224485D01*
X428296Y224219D01*
G01X433829Y220419D02*
X433696Y220485D01*
Y220619D01*
X433829Y220685D01*
X433962Y220619D01*
Y220485D01*
X433829Y220419D01*
G01X438429Y224552D02*
X437896Y224419D01*
X437496Y224085D01*
X437229Y223685D01*
X437029Y223152D01*
X436962Y222552D01*
X437029Y221952D01*
X437229Y221419D01*
X437496Y221019D01*
X437896Y220685D01*
X438429Y220552D01*
X438962Y220685D01*
X439362Y221019D01*
X439629Y221419D01*
X439829Y221952D01*
X439896Y222552D01*
X439829Y223152D01*
X439629Y223685D01*
X439362Y224085D01*
X438962Y224419D01*
X438429Y224552D01*
G01X443029Y220552D02*
X443496Y220619D01*
X444029Y220819D01*
X444362Y221152D01*
X444496Y221619D01*
X444362Y222085D01*
X443962Y222485D01*
X443362Y222685D01*
X442696D01*
X442296Y222819D01*
X441962Y223152D01*
X441829Y223619D01*
X442029Y224085D01*
X442496Y224419D01*
X443029Y224552D01*
X443562Y224419D01*
X444029Y224085D01*
X444229Y223619D01*
X444096Y223152D01*
X443762Y222819D01*
X443362Y222685D01*
X442696D01*
X442096Y222485D01*
X441696Y222085D01*
X441562Y221619D01*
X441696Y221152D01*
X442029Y220819D01*
X442562Y220619D01*
X443029Y220552D01*
G01X414366Y262709D02*
Y266709D01*
X415700D01*
X416233Y266509D01*
X416633Y266242D01*
X416966Y265842D01*
X417233Y265376D01*
X417300Y264709D01*
X417233Y264042D01*
X416966Y263576D01*
X416633Y263176D01*
X416233Y262909D01*
X415700Y262709D01*
X414366D01*
G01X419500D02*
Y265376D01*
G01Y264842D02*
X419833Y265109D01*
X420166Y265309D01*
X420633Y265376D01*
X420966Y265309D01*
X421366Y265109D01*
G01X425033Y265376D02*
Y262709D01*
G01Y266442D02*
X424900Y266509D01*
Y266642D01*
X425033Y266709D01*
X425166Y266642D01*
Y266509D01*
X425033Y266442D01*
G01X429633Y262709D02*
Y266709D01*
G01X434233Y262709D02*
Y266709D01*
G01X443033Y262709D02*
Y266109D01*
X443166Y266442D01*
X443433Y266642D01*
X443833Y266709D01*
X444233Y266576D01*
X444433Y266242D01*
G01X443633Y265109D02*
X442300D01*
G01X447033Y264509D02*
X449166D01*
X448966Y264976D01*
X448633Y265242D01*
X448166Y265376D01*
X447700Y265309D01*
X447300Y265109D01*
X447033Y264642D01*
X446900Y264242D01*
Y263842D01*
X447033Y263442D01*
X447366Y263042D01*
X447766Y262776D01*
X448233Y262709D01*
X448700Y262842D01*
X449166Y263242D01*
G01X453833Y262709D02*
Y265376D01*
G01Y264909D02*
X453566Y265176D01*
X453166Y265309D01*
X452700Y265376D01*
X452233Y265242D01*
X451833Y264976D01*
X451566Y264576D01*
X451433Y264042D01*
X451566Y263509D01*
X451833Y263109D01*
X452233Y262842D01*
X452700Y262709D01*
X453166Y262776D01*
X453566Y262976D01*
X453833Y263242D01*
G01X457233Y266709D02*
Y262709D01*
G01X456300Y265376D02*
X458166D01*
G01X460700D02*
Y263509D01*
X460966Y263042D01*
X461366Y262776D01*
X461833Y262709D01*
X462300Y262776D01*
X462700Y263042D01*
X462966Y263509D01*
G01Y262709D02*
Y265376D01*
G01X465500Y262709D02*
Y265376D01*
G01Y264842D02*
X465833Y265109D01*
X466166Y265309D01*
X466633Y265376D01*
X466966Y265309D01*
X467366Y265109D01*
G01X470033Y264509D02*
X472166D01*
X471966Y264976D01*
X471633Y265242D01*
X471166Y265376D01*
X470700Y265309D01*
X470300Y265109D01*
X470033Y264642D01*
X469900Y264242D01*
Y263842D01*
X470033Y263442D01*
X470366Y263042D01*
X470766Y262776D01*
X471233Y262709D01*
X471700Y262842D01*
X472166Y263242D01*
G01X389213Y277843D02*
G03X396138Y264712I37662J11471D01*
G01X389213Y277843D02*
G03X396138Y264712I37662J11470D01*
G01X420921Y304876D02*
X421321Y305276D01*
X421788Y305476D01*
X422321Y305543D01*
X422988Y305410D01*
X423455Y305076D01*
X423588Y304676D01*
X423521Y304276D01*
X423255Y303943D01*
X421921Y303276D01*
X421321Y302810D01*
X420921Y302143D01*
X420788Y301543D01*
X423588D01*
G01X426788Y305543D02*
X426255Y305410D01*
X425855Y305076D01*
X425588Y304676D01*
X425388Y304143D01*
X425321Y303543D01*
X425388Y302943D01*
X425588Y302410D01*
X425855Y302010D01*
X426255Y301676D01*
X426788Y301543D01*
X427321Y301676D01*
X427721Y302010D01*
X427988Y302410D01*
X428188Y302943D01*
X428255Y303543D01*
X428188Y304143D01*
X427988Y304676D01*
X427721Y305076D01*
X427321Y305410D01*
X426788Y305543D01*
G01X431388Y301543D02*
X431855Y301610D01*
X432388Y301810D01*
X432721Y302143D01*
X432855Y302610D01*
X432721Y303076D01*
X432321Y303476D01*
X431721Y303676D01*
X431055D01*
X430655Y303810D01*
X430321Y304143D01*
X430188Y304610D01*
X430388Y305076D01*
X430855Y305410D01*
X431388Y305543D01*
X431921Y305410D01*
X432388Y305076D01*
X432588Y304610D01*
X432455Y304143D01*
X432121Y303810D01*
X431721Y303676D01*
X431055D01*
X430455Y303476D01*
X430055Y303076D01*
X429921Y302610D01*
X430055Y302143D01*
X430388Y301810D01*
X430921Y301610D01*
X431388Y301543D01*
G01X435988Y301410D02*
X435855Y301476D01*
Y301610D01*
X435988Y301676D01*
X436121Y301610D01*
Y301476D01*
X435988Y301410D01*
G01X439321Y303210D02*
X439788Y303676D01*
X440188Y303943D01*
X440721Y304076D01*
X441188Y303943D01*
X441521Y303676D01*
X441788Y303276D01*
X441855Y302810D01*
X441788Y302410D01*
X441521Y302010D01*
X441121Y301676D01*
X440655Y301543D01*
X440121Y301676D01*
X439655Y302076D01*
X439388Y302676D01*
X439321Y303343D01*
X439455Y304210D01*
X439655Y304676D01*
X439988Y305143D01*
X440455Y305476D01*
X440921Y305543D01*
X441388Y305410D01*
X441721Y305076D01*
G01X443921Y303210D02*
X444388Y303676D01*
X444788Y303943D01*
X445321Y304076D01*
X445788Y303943D01*
X446121Y303676D01*
X446388Y303276D01*
X446455Y302810D01*
X446388Y302410D01*
X446121Y302010D01*
X445721Y301676D01*
X445255Y301543D01*
X444721Y301676D01*
X444255Y302076D01*
X443988Y302676D01*
X443921Y303343D01*
X444055Y304210D01*
X444255Y304676D01*
X444588Y305143D01*
X445055Y305476D01*
X445521Y305543D01*
X445988Y305410D01*
X446321Y305076D01*
G01X420829Y673308D02*
Y677308D01*
X418362Y674441D01*
X421696D01*
G01X423162Y674108D02*
X423562Y673641D01*
X424096Y673375D01*
X424696Y673308D01*
X425229Y673375D01*
X425762Y673708D01*
X426096Y674108D01*
X426162Y674508D01*
X426029Y674975D01*
X425562Y675308D01*
X425096Y675441D01*
X424496D01*
G01X425096D02*
X425496Y675641D01*
X425829Y675975D01*
X425962Y676375D01*
X425829Y676775D01*
X425496Y677108D01*
X424896Y677308D01*
X424296Y677241D01*
X423696Y676975D01*
G01X427762Y674108D02*
X428162Y673641D01*
X428696Y673375D01*
X429296Y673308D01*
X429829Y673375D01*
X430362Y673708D01*
X430696Y674108D01*
X430762Y674508D01*
X430629Y674975D01*
X430162Y675308D01*
X429696Y675441D01*
X429096D01*
G01X429696D02*
X430096Y675641D01*
X430429Y675975D01*
X430562Y676375D01*
X430429Y676775D01*
X430096Y677108D01*
X429496Y677308D01*
X428896Y677241D01*
X428296Y676975D01*
G01X433829Y673175D02*
X433696Y673241D01*
Y673375D01*
X433829Y673441D01*
X433962Y673375D01*
Y673241D01*
X433829Y673175D01*
G01X438429Y677308D02*
X437896Y677175D01*
X437496Y676841D01*
X437229Y676441D01*
X437029Y675908D01*
X436962Y675308D01*
X437029Y674708D01*
X437229Y674175D01*
X437496Y673775D01*
X437896Y673441D01*
X438429Y673308D01*
X438962Y673441D01*
X439362Y673775D01*
X439629Y674175D01*
X439829Y674708D01*
X439896Y675308D01*
X439829Y675908D01*
X439629Y676441D01*
X439362Y676841D01*
X438962Y677175D01*
X438429Y677308D01*
G01X443029Y673308D02*
X443496Y673375D01*
X444029Y673575D01*
X444362Y673908D01*
X444496Y674375D01*
X444362Y674841D01*
X443962Y675241D01*
X443362Y675441D01*
X442696D01*
X442296Y675575D01*
X441962Y675908D01*
X441829Y676375D01*
X442029Y676841D01*
X442496Y677175D01*
X443029Y677308D01*
X443562Y677175D01*
X444029Y676841D01*
X444229Y676375D01*
X444096Y675908D01*
X443762Y675575D01*
X443362Y675441D01*
X442696D01*
X442096Y675241D01*
X441696Y674841D01*
X441562Y674375D01*
X441696Y673908D01*
X442029Y673575D01*
X442562Y673375D01*
X443029Y673308D01*
G01X420921Y757632D02*
X421321Y758032D01*
X421788Y758232D01*
X422321Y758299D01*
X422988Y758166D01*
X423455Y757832D01*
X423588Y757432D01*
X423521Y757032D01*
X423255Y756699D01*
X421921Y756032D01*
X421321Y755566D01*
X420921Y754899D01*
X420788Y754299D01*
X423588D01*
G01X426788Y758299D02*
X426255Y758166D01*
X425855Y757832D01*
X425588Y757432D01*
X425388Y756899D01*
X425321Y756299D01*
X425388Y755699D01*
X425588Y755166D01*
X425855Y754766D01*
X426255Y754432D01*
X426788Y754299D01*
X427321Y754432D01*
X427721Y754766D01*
X427988Y755166D01*
X428188Y755699D01*
X428255Y756299D01*
X428188Y756899D01*
X427988Y757432D01*
X427721Y757832D01*
X427321Y758166D01*
X426788Y758299D01*
G01X431388Y754299D02*
X431855Y754366D01*
X432388Y754566D01*
X432721Y754899D01*
X432855Y755366D01*
X432721Y755832D01*
X432321Y756232D01*
X431721Y756432D01*
X431055D01*
X430655Y756566D01*
X430321Y756899D01*
X430188Y757366D01*
X430388Y757832D01*
X430855Y758166D01*
X431388Y758299D01*
X431921Y758166D01*
X432388Y757832D01*
X432588Y757366D01*
X432455Y756899D01*
X432121Y756566D01*
X431721Y756432D01*
X431055D01*
X430455Y756232D01*
X430055Y755832D01*
X429921Y755366D01*
X430055Y754899D01*
X430388Y754566D01*
X430921Y754366D01*
X431388Y754299D01*
G01X435988Y754166D02*
X435855Y754232D01*
Y754366D01*
X435988Y754432D01*
X436121Y754366D01*
Y754232D01*
X435988Y754166D01*
G01X439321Y755966D02*
X439788Y756432D01*
X440188Y756699D01*
X440721Y756832D01*
X441188Y756699D01*
X441521Y756432D01*
X441788Y756032D01*
X441855Y755566D01*
X441788Y755166D01*
X441521Y754766D01*
X441121Y754432D01*
X440655Y754299D01*
X440121Y754432D01*
X439655Y754832D01*
X439388Y755432D01*
X439321Y756099D01*
X439455Y756966D01*
X439655Y757432D01*
X439988Y757899D01*
X440455Y758232D01*
X440921Y758299D01*
X441388Y758166D01*
X441721Y757832D01*
G01X443921Y755966D02*
X444388Y756432D01*
X444788Y756699D01*
X445321Y756832D01*
X445788Y756699D01*
X446121Y756432D01*
X446388Y756032D01*
X446455Y755566D01*
X446388Y755166D01*
X446121Y754766D01*
X445721Y754432D01*
X445255Y754299D01*
X444721Y754432D01*
X444255Y754832D01*
X443988Y755432D01*
X443921Y756099D01*
X444055Y756966D01*
X444255Y757432D01*
X444588Y757899D01*
X445055Y758232D01*
X445521Y758299D01*
X445988Y758166D01*
X446321Y757832D01*
G01X414366Y715465D02*
Y719465D01*
X415700D01*
X416233Y719265D01*
X416633Y718998D01*
X416966Y718598D01*
X417233Y718132D01*
X417300Y717465D01*
X417233Y716798D01*
X416966Y716332D01*
X416633Y715932D01*
X416233Y715665D01*
X415700Y715465D01*
X414366D01*
G01X419500D02*
Y718132D01*
G01Y717598D02*
X419833Y717865D01*
X420166Y718065D01*
X420633Y718132D01*
X420966Y718065D01*
X421366Y717865D01*
G01X425033Y718132D02*
Y715465D01*
G01Y719198D02*
X424900Y719265D01*
Y719398D01*
X425033Y719465D01*
X425166Y719398D01*
Y719265D01*
X425033Y719198D01*
G01X429633Y715465D02*
Y719465D01*
G01X434233Y715465D02*
Y719465D01*
G01X443033Y715465D02*
Y718865D01*
X443166Y719198D01*
X443433Y719398D01*
X443833Y719465D01*
X444233Y719332D01*
X444433Y718998D01*
G01X443633Y717865D02*
X442300D01*
G01X447033Y717265D02*
X449166D01*
X448966Y717732D01*
X448633Y717998D01*
X448166Y718132D01*
X447700Y718065D01*
X447300Y717865D01*
X447033Y717398D01*
X446900Y716998D01*
Y716598D01*
X447033Y716198D01*
X447366Y715798D01*
X447766Y715532D01*
X448233Y715465D01*
X448700Y715598D01*
X449166Y715998D01*
G01X453833Y715465D02*
Y718132D01*
G01Y717665D02*
X453566Y717932D01*
X453166Y718065D01*
X452700Y718132D01*
X452233Y717998D01*
X451833Y717732D01*
X451566Y717332D01*
X451433Y716798D01*
X451566Y716265D01*
X451833Y715865D01*
X452233Y715598D01*
X452700Y715465D01*
X453166Y715532D01*
X453566Y715732D01*
X453833Y715998D01*
G01X457233Y719465D02*
Y715465D01*
G01X456300Y718132D02*
X458166D01*
G01X460700D02*
Y716265D01*
X460966Y715798D01*
X461366Y715532D01*
X461833Y715465D01*
X462300Y715532D01*
X462700Y715798D01*
X462966Y716265D01*
G01Y715465D02*
Y718132D01*
G01X465500Y715465D02*
Y718132D01*
G01Y717598D02*
X465833Y717865D01*
X466166Y718065D01*
X466633Y718132D01*
X466966Y718065D01*
X467366Y717865D01*
G01X470033Y717265D02*
X472166D01*
X471966Y717732D01*
X471633Y717998D01*
X471166Y718132D01*
X470700Y718065D01*
X470300Y717865D01*
X470033Y717398D01*
X469900Y716998D01*
Y716598D01*
X470033Y716198D01*
X470366Y715798D01*
X470766Y715532D01*
X471233Y715465D01*
X471700Y715598D01*
X472166Y715998D01*
G01X389213Y730599D02*
G03X396138Y717468I37662J11471D01*
G01X389213Y730599D02*
G03X396138Y717468I37662J11470D01*
G01X420829Y1126063D02*
Y1130063D01*
X418362Y1127196D01*
X421696D01*
G01X423162Y1126863D02*
X423562Y1126396D01*
X424096Y1126130D01*
X424696Y1126063D01*
X425229Y1126130D01*
X425762Y1126463D01*
X426096Y1126863D01*
X426162Y1127263D01*
X426029Y1127730D01*
X425562Y1128063D01*
X425096Y1128196D01*
X424496D01*
G01X425096D02*
X425496Y1128396D01*
X425829Y1128730D01*
X425962Y1129130D01*
X425829Y1129530D01*
X425496Y1129863D01*
X424896Y1130063D01*
X424296Y1129996D01*
X423696Y1129730D01*
G01X427762Y1126863D02*
X428162Y1126396D01*
X428696Y1126130D01*
X429296Y1126063D01*
X429829Y1126130D01*
X430362Y1126463D01*
X430696Y1126863D01*
X430762Y1127263D01*
X430629Y1127730D01*
X430162Y1128063D01*
X429696Y1128196D01*
X429096D01*
G01X429696D02*
X430096Y1128396D01*
X430429Y1128730D01*
X430562Y1129130D01*
X430429Y1129530D01*
X430096Y1129863D01*
X429496Y1130063D01*
X428896Y1129996D01*
X428296Y1129730D01*
G01X433829Y1125930D02*
X433696Y1125996D01*
Y1126130D01*
X433829Y1126196D01*
X433962Y1126130D01*
Y1125996D01*
X433829Y1125930D01*
G01X438429Y1130063D02*
X437896Y1129930D01*
X437496Y1129596D01*
X437229Y1129196D01*
X437029Y1128663D01*
X436962Y1128063D01*
X437029Y1127463D01*
X437229Y1126930D01*
X437496Y1126530D01*
X437896Y1126196D01*
X438429Y1126063D01*
X438962Y1126196D01*
X439362Y1126530D01*
X439629Y1126930D01*
X439829Y1127463D01*
X439896Y1128063D01*
X439829Y1128663D01*
X439629Y1129196D01*
X439362Y1129596D01*
X438962Y1129930D01*
X438429Y1130063D01*
G01X443029Y1126063D02*
X443496Y1126130D01*
X444029Y1126330D01*
X444362Y1126663D01*
X444496Y1127130D01*
X444362Y1127596D01*
X443962Y1127996D01*
X443362Y1128196D01*
X442696D01*
X442296Y1128330D01*
X441962Y1128663D01*
X441829Y1129130D01*
X442029Y1129596D01*
X442496Y1129930D01*
X443029Y1130063D01*
X443562Y1129930D01*
X444029Y1129596D01*
X444229Y1129130D01*
X444096Y1128663D01*
X443762Y1128330D01*
X443362Y1128196D01*
X442696D01*
X442096Y1127996D01*
X441696Y1127596D01*
X441562Y1127130D01*
X441696Y1126663D01*
X442029Y1126330D01*
X442562Y1126130D01*
X443029Y1126063D01*
G01X420921Y1210387D02*
X421321Y1210787D01*
X421788Y1210987D01*
X422321Y1211054D01*
X422988Y1210921D01*
X423455Y1210587D01*
X423588Y1210187D01*
X423521Y1209787D01*
X423255Y1209454D01*
X421921Y1208787D01*
X421321Y1208321D01*
X420921Y1207654D01*
X420788Y1207054D01*
X423588D01*
G01X426788Y1211054D02*
X426255Y1210921D01*
X425855Y1210587D01*
X425588Y1210187D01*
X425388Y1209654D01*
X425321Y1209054D01*
X425388Y1208454D01*
X425588Y1207921D01*
X425855Y1207521D01*
X426255Y1207187D01*
X426788Y1207054D01*
X427321Y1207187D01*
X427721Y1207521D01*
X427988Y1207921D01*
X428188Y1208454D01*
X428255Y1209054D01*
X428188Y1209654D01*
X427988Y1210187D01*
X427721Y1210587D01*
X427321Y1210921D01*
X426788Y1211054D01*
G01X431388Y1207054D02*
X431855Y1207121D01*
X432388Y1207321D01*
X432721Y1207654D01*
X432855Y1208121D01*
X432721Y1208587D01*
X432321Y1208987D01*
X431721Y1209187D01*
X431055D01*
X430655Y1209321D01*
X430321Y1209654D01*
X430188Y1210121D01*
X430388Y1210587D01*
X430855Y1210921D01*
X431388Y1211054D01*
X431921Y1210921D01*
X432388Y1210587D01*
X432588Y1210121D01*
X432455Y1209654D01*
X432121Y1209321D01*
X431721Y1209187D01*
X431055D01*
X430455Y1208987D01*
X430055Y1208587D01*
X429921Y1208121D01*
X430055Y1207654D01*
X430388Y1207321D01*
X430921Y1207121D01*
X431388Y1207054D01*
G01X435988Y1206921D02*
X435855Y1206987D01*
Y1207121D01*
X435988Y1207187D01*
X436121Y1207121D01*
Y1206987D01*
X435988Y1206921D01*
G01X439321Y1208721D02*
X439788Y1209187D01*
X440188Y1209454D01*
X440721Y1209587D01*
X441188Y1209454D01*
X441521Y1209187D01*
X441788Y1208787D01*
X441855Y1208321D01*
X441788Y1207921D01*
X441521Y1207521D01*
X441121Y1207187D01*
X440655Y1207054D01*
X440121Y1207187D01*
X439655Y1207587D01*
X439388Y1208187D01*
X439321Y1208854D01*
X439455Y1209721D01*
X439655Y1210187D01*
X439988Y1210654D01*
X440455Y1210987D01*
X440921Y1211054D01*
X441388Y1210921D01*
X441721Y1210587D01*
G01X443921Y1208721D02*
X444388Y1209187D01*
X444788Y1209454D01*
X445321Y1209587D01*
X445788Y1209454D01*
X446121Y1209187D01*
X446388Y1208787D01*
X446455Y1208321D01*
X446388Y1207921D01*
X446121Y1207521D01*
X445721Y1207187D01*
X445255Y1207054D01*
X444721Y1207187D01*
X444255Y1207587D01*
X443988Y1208187D01*
X443921Y1208854D01*
X444055Y1209721D01*
X444255Y1210187D01*
X444588Y1210654D01*
X445055Y1210987D01*
X445521Y1211054D01*
X445988Y1210921D01*
X446321Y1210587D01*
G01X414366Y1168220D02*
Y1172220D01*
X415700D01*
X416233Y1172020D01*
X416633Y1171753D01*
X416966Y1171353D01*
X417233Y1170887D01*
X417300Y1170220D01*
X417233Y1169553D01*
X416966Y1169087D01*
X416633Y1168687D01*
X416233Y1168420D01*
X415700Y1168220D01*
X414366D01*
G01X419500D02*
Y1170887D01*
G01Y1170353D02*
X419833Y1170620D01*
X420166Y1170820D01*
X420633Y1170887D01*
X420966Y1170820D01*
X421366Y1170620D01*
G01X425033Y1170887D02*
Y1168220D01*
G01Y1171953D02*
X424900Y1172020D01*
Y1172153D01*
X425033Y1172220D01*
X425166Y1172153D01*
Y1172020D01*
X425033Y1171953D01*
G01X429633Y1168220D02*
Y1172220D01*
G01X434233Y1168220D02*
Y1172220D01*
G01X443033Y1168220D02*
Y1171620D01*
X443166Y1171953D01*
X443433Y1172153D01*
X443833Y1172220D01*
X444233Y1172087D01*
X444433Y1171753D01*
G01X443633Y1170620D02*
X442300D01*
G01X447033Y1170020D02*
X449166D01*
X448966Y1170487D01*
X448633Y1170753D01*
X448166Y1170887D01*
X447700Y1170820D01*
X447300Y1170620D01*
X447033Y1170153D01*
X446900Y1169753D01*
Y1169353D01*
X447033Y1168953D01*
X447366Y1168553D01*
X447766Y1168287D01*
X448233Y1168220D01*
X448700Y1168353D01*
X449166Y1168753D01*
G01X453833Y1168220D02*
Y1170887D01*
G01Y1170420D02*
X453566Y1170687D01*
X453166Y1170820D01*
X452700Y1170887D01*
X452233Y1170753D01*
X451833Y1170487D01*
X451566Y1170087D01*
X451433Y1169553D01*
X451566Y1169020D01*
X451833Y1168620D01*
X452233Y1168353D01*
X452700Y1168220D01*
X453166Y1168287D01*
X453566Y1168487D01*
X453833Y1168753D01*
G01X457233Y1172220D02*
Y1168220D01*
G01X456300Y1170887D02*
X458166D01*
G01X460700D02*
Y1169020D01*
X460966Y1168553D01*
X461366Y1168287D01*
X461833Y1168220D01*
X462300Y1168287D01*
X462700Y1168553D01*
X462966Y1169020D01*
G01Y1168220D02*
Y1170887D01*
G01X465500Y1168220D02*
Y1170887D01*
G01Y1170353D02*
X465833Y1170620D01*
X466166Y1170820D01*
X466633Y1170887D01*
X466966Y1170820D01*
X467366Y1170620D01*
G01X470033Y1170020D02*
X472166D01*
X471966Y1170487D01*
X471633Y1170753D01*
X471166Y1170887D01*
X470700Y1170820D01*
X470300Y1170620D01*
X470033Y1170153D01*
X469900Y1169753D01*
Y1169353D01*
X470033Y1168953D01*
X470366Y1168553D01*
X470766Y1168287D01*
X471233Y1168220D01*
X471700Y1168353D01*
X472166Y1168753D01*
G01X389213Y1183355D02*
G03X396138Y1170224I37662J11471D01*
G01X389213Y1183355D02*
G03X396138Y1170224I37662J11470D01*
G01X477559Y1503937D02*
G03Y1496063I0J-3937D01*
G01X459449D02*
G03Y1503937I0J3937D01*
G01X489370D02*
X477559D01*
G01D02*
G03Y1496063I0J-3937D01*
G01X459449D02*
G03Y1503937I0J3937D01*
G01X489370D02*
X477559D01*
G01X550826Y253600D02*
X551226Y253267D01*
X551693Y253067D01*
X552293Y253000D01*
X552893Y253133D01*
X553360Y253400D01*
X553693Y253867D01*
X553760Y254400D01*
X553626Y254933D01*
X553293Y255267D01*
X552826Y255533D01*
X552360Y255600D01*
X551893Y255533D01*
X551293Y255267D01*
X551493Y257000D01*
X553293D01*
G01X555426Y253600D02*
X555826Y253267D01*
X556293Y253067D01*
X556893Y253000D01*
X557493Y253133D01*
X557960Y253400D01*
X558293Y253867D01*
X558360Y254400D01*
X558226Y254933D01*
X557893Y255267D01*
X557426Y255533D01*
X556960Y255600D01*
X556493Y255533D01*
X555893Y255267D01*
X556093Y257000D01*
X557893D01*
G01X561360Y253000D02*
X561493Y253867D01*
X561693Y254600D01*
X561960Y255267D01*
X562293Y256000D01*
X562826Y257000D01*
X560160D01*
G01X566093Y252867D02*
X565960Y252933D01*
Y253067D01*
X566093Y253133D01*
X566226Y253067D01*
Y252933D01*
X566093Y252867D01*
G01X570693Y257000D02*
X570160Y256867D01*
X569760Y256533D01*
X569493Y256133D01*
X569293Y255600D01*
X569226Y255000D01*
X569293Y254400D01*
X569493Y253867D01*
X569760Y253467D01*
X570160Y253133D01*
X570693Y253000D01*
X571226Y253133D01*
X571626Y253467D01*
X571893Y253867D01*
X572093Y254400D01*
X572160Y255000D01*
X572093Y255600D01*
X571893Y256133D01*
X571626Y256533D01*
X571226Y256867D01*
X570693Y257000D01*
G01X574160Y253467D02*
X574626Y253133D01*
X575160Y253000D01*
X575693Y253133D01*
X576160Y253533D01*
X576493Y254133D01*
X576626Y254733D01*
Y255467D01*
X576493Y256067D01*
X576160Y256600D01*
X575760Y256867D01*
X575293Y257000D01*
X574760Y256867D01*
X574360Y256600D01*
X574093Y256200D01*
X573960Y255667D01*
X574093Y255200D01*
X574426Y254733D01*
X574826Y254467D01*
X575293Y254400D01*
X575826Y254533D01*
X576226Y254867D01*
X576626Y255467D01*
G01X568165Y264146D02*
X568565Y264546D01*
X569032Y264746D01*
X569565Y264813D01*
X570232Y264680D01*
X570699Y264346D01*
X570832Y263946D01*
X570765Y263546D01*
X570499Y263213D01*
X569165Y262546D01*
X568565Y262080D01*
X568165Y261413D01*
X568032Y260813D01*
X570832D01*
G01X572565Y261613D02*
X572965Y261146D01*
X573499Y260880D01*
X574099Y260813D01*
X574632Y260880D01*
X575165Y261213D01*
X575499Y261613D01*
X575565Y262013D01*
X575432Y262480D01*
X574965Y262813D01*
X574499Y262946D01*
X573899D01*
G01X574499D02*
X574899Y263146D01*
X575232Y263480D01*
X575365Y263880D01*
X575232Y264280D01*
X574899Y264613D01*
X574299Y264813D01*
X573699Y264746D01*
X573099Y264480D01*
G01X577365Y262480D02*
X577832Y262946D01*
X578232Y263213D01*
X578765Y263346D01*
X579232Y263213D01*
X579565Y262946D01*
X579832Y262546D01*
X579899Y262080D01*
X579832Y261680D01*
X579565Y261280D01*
X579165Y260946D01*
X578699Y260813D01*
X578165Y260946D01*
X577699Y261346D01*
X577432Y261946D01*
X577365Y262613D01*
X577499Y263480D01*
X577699Y263946D01*
X578032Y264413D01*
X578499Y264746D01*
X578965Y264813D01*
X579432Y264680D01*
X579765Y264346D01*
G01X583232Y260680D02*
X583099Y260746D01*
Y260880D01*
X583232Y260946D01*
X583365Y260880D01*
Y260746D01*
X583232Y260680D01*
G01X586565Y264146D02*
X586965Y264546D01*
X587432Y264746D01*
X587965Y264813D01*
X588632Y264680D01*
X589099Y264346D01*
X589232Y263946D01*
X589165Y263546D01*
X588899Y263213D01*
X587565Y262546D01*
X586965Y262080D01*
X586565Y261413D01*
X586432Y260813D01*
X589232D01*
G01X591165Y264146D02*
X591565Y264546D01*
X592032Y264746D01*
X592565Y264813D01*
X593232Y264680D01*
X593699Y264346D01*
X593832Y263946D01*
X593765Y263546D01*
X593499Y263213D01*
X592165Y262546D01*
X591565Y262080D01*
X591165Y261413D01*
X591032Y260813D01*
X593832D01*
G01X550826Y706356D02*
X551226Y706023D01*
X551693Y705823D01*
X552293Y705756D01*
X552893Y705889D01*
X553360Y706156D01*
X553693Y706623D01*
X553760Y707156D01*
X553626Y707689D01*
X553293Y708023D01*
X552826Y708289D01*
X552360Y708356D01*
X551893Y708289D01*
X551293Y708023D01*
X551493Y709756D01*
X553293D01*
G01X555426Y706356D02*
X555826Y706023D01*
X556293Y705823D01*
X556893Y705756D01*
X557493Y705889D01*
X557960Y706156D01*
X558293Y706623D01*
X558360Y707156D01*
X558226Y707689D01*
X557893Y708023D01*
X557426Y708289D01*
X556960Y708356D01*
X556493Y708289D01*
X555893Y708023D01*
X556093Y709756D01*
X557893D01*
G01X561360Y705756D02*
X561493Y706623D01*
X561693Y707356D01*
X561960Y708023D01*
X562293Y708756D01*
X562826Y709756D01*
X560160D01*
G01X566093Y705623D02*
X565960Y705689D01*
Y705823D01*
X566093Y705889D01*
X566226Y705823D01*
Y705689D01*
X566093Y705623D01*
G01X570693Y709756D02*
X570160Y709623D01*
X569760Y709289D01*
X569493Y708889D01*
X569293Y708356D01*
X569226Y707756D01*
X569293Y707156D01*
X569493Y706623D01*
X569760Y706223D01*
X570160Y705889D01*
X570693Y705756D01*
X571226Y705889D01*
X571626Y706223D01*
X571893Y706623D01*
X572093Y707156D01*
X572160Y707756D01*
X572093Y708356D01*
X571893Y708889D01*
X571626Y709289D01*
X571226Y709623D01*
X570693Y709756D01*
G01X574160Y706223D02*
X574626Y705889D01*
X575160Y705756D01*
X575693Y705889D01*
X576160Y706289D01*
X576493Y706889D01*
X576626Y707489D01*
Y708223D01*
X576493Y708823D01*
X576160Y709356D01*
X575760Y709623D01*
X575293Y709756D01*
X574760Y709623D01*
X574360Y709356D01*
X574093Y708956D01*
X573960Y708423D01*
X574093Y707956D01*
X574426Y707489D01*
X574826Y707223D01*
X575293Y707156D01*
X575826Y707289D01*
X576226Y707623D01*
X576626Y708223D01*
G01X568165Y716902D02*
X568565Y717302D01*
X569032Y717502D01*
X569565Y717569D01*
X570232Y717436D01*
X570699Y717102D01*
X570832Y716702D01*
X570765Y716302D01*
X570499Y715969D01*
X569165Y715302D01*
X568565Y714836D01*
X568165Y714169D01*
X568032Y713569D01*
X570832D01*
G01X572565Y714369D02*
X572965Y713902D01*
X573499Y713636D01*
X574099Y713569D01*
X574632Y713636D01*
X575165Y713969D01*
X575499Y714369D01*
X575565Y714769D01*
X575432Y715236D01*
X574965Y715569D01*
X574499Y715702D01*
X573899D01*
G01X574499D02*
X574899Y715902D01*
X575232Y716236D01*
X575365Y716636D01*
X575232Y717036D01*
X574899Y717369D01*
X574299Y717569D01*
X573699Y717502D01*
X573099Y717236D01*
G01X577365Y715236D02*
X577832Y715702D01*
X578232Y715969D01*
X578765Y716102D01*
X579232Y715969D01*
X579565Y715702D01*
X579832Y715302D01*
X579899Y714836D01*
X579832Y714436D01*
X579565Y714036D01*
X579165Y713702D01*
X578699Y713569D01*
X578165Y713702D01*
X577699Y714102D01*
X577432Y714702D01*
X577365Y715369D01*
X577499Y716236D01*
X577699Y716702D01*
X578032Y717169D01*
X578499Y717502D01*
X578965Y717569D01*
X579432Y717436D01*
X579765Y717102D01*
G01X583232Y713436D02*
X583099Y713502D01*
Y713636D01*
X583232Y713702D01*
X583365Y713636D01*
Y713502D01*
X583232Y713436D01*
G01X586565Y716902D02*
X586965Y717302D01*
X587432Y717502D01*
X587965Y717569D01*
X588632Y717436D01*
X589099Y717102D01*
X589232Y716702D01*
X589165Y716302D01*
X588899Y715969D01*
X587565Y715302D01*
X586965Y714836D01*
X586565Y714169D01*
X586432Y713569D01*
X589232D01*
G01X591165Y716902D02*
X591565Y717302D01*
X592032Y717502D01*
X592565Y717569D01*
X593232Y717436D01*
X593699Y717102D01*
X593832Y716702D01*
X593765Y716302D01*
X593499Y715969D01*
X592165Y715302D01*
X591565Y714836D01*
X591165Y714169D01*
X591032Y713569D01*
X593832D01*
G01X550826Y1159111D02*
X551226Y1158778D01*
X551693Y1158578D01*
X552293Y1158511D01*
X552893Y1158644D01*
X553360Y1158911D01*
X553693Y1159378D01*
X553760Y1159911D01*
X553626Y1160444D01*
X553293Y1160778D01*
X552826Y1161044D01*
X552360Y1161111D01*
X551893Y1161044D01*
X551293Y1160778D01*
X551493Y1162511D01*
X553293D01*
G01X555426Y1159111D02*
X555826Y1158778D01*
X556293Y1158578D01*
X556893Y1158511D01*
X557493Y1158644D01*
X557960Y1158911D01*
X558293Y1159378D01*
X558360Y1159911D01*
X558226Y1160444D01*
X557893Y1160778D01*
X557426Y1161044D01*
X556960Y1161111D01*
X556493Y1161044D01*
X555893Y1160778D01*
X556093Y1162511D01*
X557893D01*
G01X561360Y1158511D02*
X561493Y1159378D01*
X561693Y1160111D01*
X561960Y1160778D01*
X562293Y1161511D01*
X562826Y1162511D01*
X560160D01*
G01X566093Y1158378D02*
X565960Y1158444D01*
Y1158578D01*
X566093Y1158644D01*
X566226Y1158578D01*
Y1158444D01*
X566093Y1158378D01*
G01X570693Y1162511D02*
X570160Y1162378D01*
X569760Y1162044D01*
X569493Y1161644D01*
X569293Y1161111D01*
X569226Y1160511D01*
X569293Y1159911D01*
X569493Y1159378D01*
X569760Y1158978D01*
X570160Y1158644D01*
X570693Y1158511D01*
X571226Y1158644D01*
X571626Y1158978D01*
X571893Y1159378D01*
X572093Y1159911D01*
X572160Y1160511D01*
X572093Y1161111D01*
X571893Y1161644D01*
X571626Y1162044D01*
X571226Y1162378D01*
X570693Y1162511D01*
G01X574160Y1158978D02*
X574626Y1158644D01*
X575160Y1158511D01*
X575693Y1158644D01*
X576160Y1159044D01*
X576493Y1159644D01*
X576626Y1160244D01*
Y1160978D01*
X576493Y1161578D01*
X576160Y1162111D01*
X575760Y1162378D01*
X575293Y1162511D01*
X574760Y1162378D01*
X574360Y1162111D01*
X574093Y1161711D01*
X573960Y1161178D01*
X574093Y1160711D01*
X574426Y1160244D01*
X574826Y1159978D01*
X575293Y1159911D01*
X575826Y1160044D01*
X576226Y1160378D01*
X576626Y1160978D01*
G01X568165Y1169657D02*
X568565Y1170057D01*
X569032Y1170257D01*
X569565Y1170324D01*
X570232Y1170191D01*
X570699Y1169857D01*
X570832Y1169457D01*
X570765Y1169057D01*
X570499Y1168724D01*
X569165Y1168057D01*
X568565Y1167591D01*
X568165Y1166924D01*
X568032Y1166324D01*
X570832D01*
G01X572565Y1167124D02*
X572965Y1166657D01*
X573499Y1166391D01*
X574099Y1166324D01*
X574632Y1166391D01*
X575165Y1166724D01*
X575499Y1167124D01*
X575565Y1167524D01*
X575432Y1167991D01*
X574965Y1168324D01*
X574499Y1168457D01*
X573899D01*
G01X574499D02*
X574899Y1168657D01*
X575232Y1168991D01*
X575365Y1169391D01*
X575232Y1169791D01*
X574899Y1170124D01*
X574299Y1170324D01*
X573699Y1170257D01*
X573099Y1169991D01*
G01X577365Y1167991D02*
X577832Y1168457D01*
X578232Y1168724D01*
X578765Y1168857D01*
X579232Y1168724D01*
X579565Y1168457D01*
X579832Y1168057D01*
X579899Y1167591D01*
X579832Y1167191D01*
X579565Y1166791D01*
X579165Y1166457D01*
X578699Y1166324D01*
X578165Y1166457D01*
X577699Y1166857D01*
X577432Y1167457D01*
X577365Y1168124D01*
X577499Y1168991D01*
X577699Y1169457D01*
X578032Y1169924D01*
X578499Y1170257D01*
X578965Y1170324D01*
X579432Y1170191D01*
X579765Y1169857D01*
G01X583232Y1166191D02*
X583099Y1166257D01*
Y1166391D01*
X583232Y1166457D01*
X583365Y1166391D01*
Y1166257D01*
X583232Y1166191D01*
G01X586565Y1169657D02*
X586965Y1170057D01*
X587432Y1170257D01*
X587965Y1170324D01*
X588632Y1170191D01*
X589099Y1169857D01*
X589232Y1169457D01*
X589165Y1169057D01*
X588899Y1168724D01*
X587565Y1168057D01*
X586965Y1167591D01*
X586565Y1166924D01*
X586432Y1166324D01*
X589232D01*
G01X591165Y1169657D02*
X591565Y1170057D01*
X592032Y1170257D01*
X592565Y1170324D01*
X593232Y1170191D01*
X593699Y1169857D01*
X593832Y1169457D01*
X593765Y1169057D01*
X593499Y1168724D01*
X592165Y1168057D01*
X591565Y1167591D01*
X591165Y1166924D01*
X591032Y1166324D01*
X593832D01*
G01X489370Y1515748D02*
G03X485433Y1519685I-3937J0D01*
G01X489370Y1515748D02*
G03X485433Y1519685I-3937J0D01*
G01X501181D02*
G03X497244Y1515748I0J-3937D01*
G01X680512Y1519685D02*
X501181D01*
G01D02*
G03X497244Y1515748I0J-3937D01*
G01X680512Y1519685D02*
X501181D01*
G01X489370Y1515748D02*
Y1503937D01*
G01X493307Y1496063D02*
G03X497244Y1500000I0J3937D01*
G01Y1515748D02*
Y1500000D01*
G01X489370Y1515748D02*
Y1503937D01*
G01X493307Y1496063D02*
G03X497244Y1500000I0J3937D01*
G01Y1515748D02*
Y1500000D01*
G01X668860Y220552D02*
Y224552D01*
X666393Y221685D01*
X669727D01*
G01X671193Y221352D02*
X671593Y220885D01*
X672127Y220619D01*
X672727Y220552D01*
X673260Y220619D01*
X673793Y220952D01*
X674127Y221352D01*
X674193Y221752D01*
X674060Y222219D01*
X673593Y222552D01*
X673127Y222685D01*
X672527D01*
G01X673127D02*
X673527Y222885D01*
X673860Y223219D01*
X673993Y223619D01*
X673860Y224019D01*
X673527Y224352D01*
X672927Y224552D01*
X672327Y224485D01*
X671727Y224219D01*
G01X675793Y221352D02*
X676193Y220885D01*
X676727Y220619D01*
X677327Y220552D01*
X677860Y220619D01*
X678393Y220952D01*
X678727Y221352D01*
X678793Y221752D01*
X678660Y222219D01*
X678193Y222552D01*
X677727Y222685D01*
X677127D01*
G01X677727D02*
X678127Y222885D01*
X678460Y223219D01*
X678593Y223619D01*
X678460Y224019D01*
X678127Y224352D01*
X677527Y224552D01*
X676927Y224485D01*
X676327Y224219D01*
G01X681860Y220419D02*
X681727Y220485D01*
Y220619D01*
X681860Y220685D01*
X681993Y220619D01*
Y220485D01*
X681860Y220419D01*
G01X686460Y224552D02*
X685927Y224419D01*
X685527Y224085D01*
X685260Y223685D01*
X685060Y223152D01*
X684993Y222552D01*
X685060Y221952D01*
X685260Y221419D01*
X685527Y221019D01*
X685927Y220685D01*
X686460Y220552D01*
X686993Y220685D01*
X687393Y221019D01*
X687660Y221419D01*
X687860Y221952D01*
X687927Y222552D01*
X687860Y223152D01*
X687660Y223685D01*
X687393Y224085D01*
X686993Y224419D01*
X686460Y224552D01*
G01X691060Y220552D02*
X691527Y220619D01*
X692060Y220819D01*
X692393Y221152D01*
X692527Y221619D01*
X692393Y222085D01*
X691993Y222485D01*
X691393Y222685D01*
X690727D01*
X690327Y222819D01*
X689993Y223152D01*
X689860Y223619D01*
X690060Y224085D01*
X690527Y224419D01*
X691060Y224552D01*
X691593Y224419D01*
X692060Y224085D01*
X692260Y223619D01*
X692127Y223152D01*
X691793Y222819D01*
X691393Y222685D01*
X690727D01*
X690127Y222485D01*
X689727Y222085D01*
X689593Y221619D01*
X689727Y221152D01*
X690060Y220819D01*
X690593Y220619D01*
X691060Y220552D01*
G01X662397Y262709D02*
Y266709D01*
X663731D01*
X664264Y266509D01*
X664664Y266242D01*
X664997Y265842D01*
X665264Y265376D01*
X665331Y264709D01*
X665264Y264042D01*
X664997Y263576D01*
X664664Y263176D01*
X664264Y262909D01*
X663731Y262709D01*
X662397D01*
G01X667531D02*
Y265376D01*
G01Y264842D02*
X667864Y265109D01*
X668197Y265309D01*
X668664Y265376D01*
X668997Y265309D01*
X669397Y265109D01*
G01X673064Y265376D02*
Y262709D01*
G01Y266442D02*
X672931Y266509D01*
Y266642D01*
X673064Y266709D01*
X673197Y266642D01*
Y266509D01*
X673064Y266442D01*
G01X677664Y262709D02*
Y266709D01*
G01X682264Y262709D02*
Y266709D01*
G01X691064Y262709D02*
Y266109D01*
X691197Y266442D01*
X691464Y266642D01*
X691864Y266709D01*
X692264Y266576D01*
X692464Y266242D01*
G01X691664Y265109D02*
X690331D01*
G01X695064Y264509D02*
X697197D01*
X696997Y264976D01*
X696664Y265242D01*
X696197Y265376D01*
X695731Y265309D01*
X695331Y265109D01*
X695064Y264642D01*
X694931Y264242D01*
Y263842D01*
X695064Y263442D01*
X695397Y263042D01*
X695797Y262776D01*
X696264Y262709D01*
X696731Y262842D01*
X697197Y263242D01*
G01X701864Y262709D02*
Y265376D01*
G01Y264909D02*
X701597Y265176D01*
X701197Y265309D01*
X700731Y265376D01*
X700264Y265242D01*
X699864Y264976D01*
X699597Y264576D01*
X699464Y264042D01*
X699597Y263509D01*
X699864Y263109D01*
X700264Y262842D01*
X700731Y262709D01*
X701197Y262776D01*
X701597Y262976D01*
X701864Y263242D01*
G01X705264Y266709D02*
Y262709D01*
G01X704331Y265376D02*
X706197D01*
G01X708731D02*
Y263509D01*
X708997Y263042D01*
X709397Y262776D01*
X709864Y262709D01*
X710331Y262776D01*
X710731Y263042D01*
X710997Y263509D01*
G01Y262709D02*
Y265376D01*
G01X713531Y262709D02*
Y265376D01*
G01Y264842D02*
X713864Y265109D01*
X714197Y265309D01*
X714664Y265376D01*
X714997Y265309D01*
X715397Y265109D01*
G01X718064Y264509D02*
X720197D01*
X719997Y264976D01*
X719664Y265242D01*
X719197Y265376D01*
X718731Y265309D01*
X718331Y265109D01*
X718064Y264642D01*
X717931Y264242D01*
Y263842D01*
X718064Y263442D01*
X718397Y263042D01*
X718797Y262776D01*
X719264Y262709D01*
X719731Y262842D01*
X720197Y263242D01*
G01X637244Y277843D02*
G03X644169Y264712I37662J11471D01*
G01X637244Y277843D02*
G03X644169Y264712I37662J11471D01*
G01X637244Y277843D02*
G03X617283I-9980J-3040D01*
G01X610358Y264712D02*
G03X617283Y277843I-30737J24602D01*
G01X637244D02*
G03X617283I-9980J-3040D01*
G01X610358Y264712D02*
G03X617283Y277843I-30737J24601D01*
G01X610358Y264712D02*
G03X644169I16906J-13531D01*
G01X610358D02*
G03X644169I16906J-13531D01*
G01X668952Y304876D02*
X669352Y305276D01*
X669819Y305476D01*
X670352Y305543D01*
X671019Y305410D01*
X671486Y305076D01*
X671619Y304676D01*
X671552Y304276D01*
X671286Y303943D01*
X669952Y303276D01*
X669352Y302810D01*
X668952Y302143D01*
X668819Y301543D01*
X671619D01*
G01X674819Y305543D02*
X674286Y305410D01*
X673886Y305076D01*
X673619Y304676D01*
X673419Y304143D01*
X673352Y303543D01*
X673419Y302943D01*
X673619Y302410D01*
X673886Y302010D01*
X674286Y301676D01*
X674819Y301543D01*
X675352Y301676D01*
X675752Y302010D01*
X676019Y302410D01*
X676219Y302943D01*
X676286Y303543D01*
X676219Y304143D01*
X676019Y304676D01*
X675752Y305076D01*
X675352Y305410D01*
X674819Y305543D01*
G01X679419Y301543D02*
X679886Y301610D01*
X680419Y301810D01*
X680752Y302143D01*
X680886Y302610D01*
X680752Y303076D01*
X680352Y303476D01*
X679752Y303676D01*
X679086D01*
X678686Y303810D01*
X678352Y304143D01*
X678219Y304610D01*
X678419Y305076D01*
X678886Y305410D01*
X679419Y305543D01*
X679952Y305410D01*
X680419Y305076D01*
X680619Y304610D01*
X680486Y304143D01*
X680152Y303810D01*
X679752Y303676D01*
X679086D01*
X678486Y303476D01*
X678086Y303076D01*
X677952Y302610D01*
X678086Y302143D01*
X678419Y301810D01*
X678952Y301610D01*
X679419Y301543D01*
G01X684019Y301410D02*
X683886Y301476D01*
Y301610D01*
X684019Y301676D01*
X684152Y301610D01*
Y301476D01*
X684019Y301410D01*
G01X687352Y303210D02*
X687819Y303676D01*
X688219Y303943D01*
X688752Y304076D01*
X689219Y303943D01*
X689552Y303676D01*
X689819Y303276D01*
X689886Y302810D01*
X689819Y302410D01*
X689552Y302010D01*
X689152Y301676D01*
X688686Y301543D01*
X688152Y301676D01*
X687686Y302076D01*
X687419Y302676D01*
X687352Y303343D01*
X687486Y304210D01*
X687686Y304676D01*
X688019Y305143D01*
X688486Y305476D01*
X688952Y305543D01*
X689419Y305410D01*
X689752Y305076D01*
G01X691952Y303210D02*
X692419Y303676D01*
X692819Y303943D01*
X693352Y304076D01*
X693819Y303943D01*
X694152Y303676D01*
X694419Y303276D01*
X694486Y302810D01*
X694419Y302410D01*
X694152Y302010D01*
X693752Y301676D01*
X693286Y301543D01*
X692752Y301676D01*
X692286Y302076D01*
X692019Y302676D01*
X691952Y303343D01*
X692086Y304210D01*
X692286Y304676D01*
X692619Y305143D01*
X693086Y305476D01*
X693552Y305543D01*
X694019Y305410D01*
X694352Y305076D01*
G01X670807Y372497D02*
X671207Y372164D01*
X671674Y371964D01*
X672274Y371897D01*
X672874Y372030D01*
X673341Y372297D01*
X673674Y372764D01*
X673741Y373297D01*
X673607Y373830D01*
X673274Y374164D01*
X672807Y374430D01*
X672341Y374497D01*
X671874Y374430D01*
X671274Y374164D01*
X671474Y375897D01*
X673274D01*
G01X675407Y372497D02*
X675807Y372164D01*
X676274Y371964D01*
X676874Y371897D01*
X677474Y372030D01*
X677941Y372297D01*
X678274Y372764D01*
X678341Y373297D01*
X678207Y373830D01*
X677874Y374164D01*
X677407Y374430D01*
X676941Y374497D01*
X676474Y374430D01*
X675874Y374164D01*
X676074Y375897D01*
X677874D01*
G01X681341Y371897D02*
X681474Y372764D01*
X681674Y373497D01*
X681941Y374164D01*
X682274Y374897D01*
X682807Y375897D01*
X680141D01*
G01X686074Y371764D02*
X685941Y371830D01*
Y371964D01*
X686074Y372030D01*
X686207Y371964D01*
Y371830D01*
X686074Y371764D01*
G01X690674Y375897D02*
X690141Y375764D01*
X689741Y375430D01*
X689474Y375030D01*
X689274Y374497D01*
X689207Y373897D01*
X689274Y373297D01*
X689474Y372764D01*
X689741Y372364D01*
X690141Y372030D01*
X690674Y371897D01*
X691207Y372030D01*
X691607Y372364D01*
X691874Y372764D01*
X692074Y373297D01*
X692141Y373897D01*
X692074Y374497D01*
X691874Y375030D01*
X691607Y375430D01*
X691207Y375764D01*
X690674Y375897D01*
G01X694141Y372364D02*
X694607Y372030D01*
X695141Y371897D01*
X695674Y372030D01*
X696141Y372430D01*
X696474Y373030D01*
X696607Y373630D01*
Y374364D01*
X696474Y374964D01*
X696141Y375497D01*
X695741Y375764D01*
X695274Y375897D01*
X694741Y375764D01*
X694341Y375497D01*
X694074Y375097D01*
X693941Y374564D01*
X694074Y374097D01*
X694407Y373630D01*
X694807Y373364D01*
X695274Y373297D01*
X695807Y373430D01*
X696207Y373764D01*
X696607Y374364D01*
G01X668860Y673308D02*
Y677308D01*
X666393Y674441D01*
X669727D01*
G01X671193Y674108D02*
X671593Y673641D01*
X672127Y673375D01*
X672727Y673308D01*
X673260Y673375D01*
X673793Y673708D01*
X674127Y674108D01*
X674193Y674508D01*
X674060Y674975D01*
X673593Y675308D01*
X673127Y675441D01*
X672527D01*
G01X673127D02*
X673527Y675641D01*
X673860Y675975D01*
X673993Y676375D01*
X673860Y676775D01*
X673527Y677108D01*
X672927Y677308D01*
X672327Y677241D01*
X671727Y676975D01*
G01X675793Y674108D02*
X676193Y673641D01*
X676727Y673375D01*
X677327Y673308D01*
X677860Y673375D01*
X678393Y673708D01*
X678727Y674108D01*
X678793Y674508D01*
X678660Y674975D01*
X678193Y675308D01*
X677727Y675441D01*
X677127D01*
G01X677727D02*
X678127Y675641D01*
X678460Y675975D01*
X678593Y676375D01*
X678460Y676775D01*
X678127Y677108D01*
X677527Y677308D01*
X676927Y677241D01*
X676327Y676975D01*
G01X681860Y673175D02*
X681727Y673241D01*
Y673375D01*
X681860Y673441D01*
X681993Y673375D01*
Y673241D01*
X681860Y673175D01*
G01X686460Y677308D02*
X685927Y677175D01*
X685527Y676841D01*
X685260Y676441D01*
X685060Y675908D01*
X684993Y675308D01*
X685060Y674708D01*
X685260Y674175D01*
X685527Y673775D01*
X685927Y673441D01*
X686460Y673308D01*
X686993Y673441D01*
X687393Y673775D01*
X687660Y674175D01*
X687860Y674708D01*
X687927Y675308D01*
X687860Y675908D01*
X687660Y676441D01*
X687393Y676841D01*
X686993Y677175D01*
X686460Y677308D01*
G01X691060Y673308D02*
X691527Y673375D01*
X692060Y673575D01*
X692393Y673908D01*
X692527Y674375D01*
X692393Y674841D01*
X691993Y675241D01*
X691393Y675441D01*
X690727D01*
X690327Y675575D01*
X689993Y675908D01*
X689860Y676375D01*
X690060Y676841D01*
X690527Y677175D01*
X691060Y677308D01*
X691593Y677175D01*
X692060Y676841D01*
X692260Y676375D01*
X692127Y675908D01*
X691793Y675575D01*
X691393Y675441D01*
X690727D01*
X690127Y675241D01*
X689727Y674841D01*
X689593Y674375D01*
X689727Y673908D01*
X690060Y673575D01*
X690593Y673375D01*
X691060Y673308D01*
G01X668952Y757632D02*
X669352Y758032D01*
X669819Y758232D01*
X670352Y758299D01*
X671019Y758166D01*
X671486Y757832D01*
X671619Y757432D01*
X671552Y757032D01*
X671286Y756699D01*
X669952Y756032D01*
X669352Y755566D01*
X668952Y754899D01*
X668819Y754299D01*
X671619D01*
G01X674819Y758299D02*
X674286Y758166D01*
X673886Y757832D01*
X673619Y757432D01*
X673419Y756899D01*
X673352Y756299D01*
X673419Y755699D01*
X673619Y755166D01*
X673886Y754766D01*
X674286Y754432D01*
X674819Y754299D01*
X675352Y754432D01*
X675752Y754766D01*
X676019Y755166D01*
X676219Y755699D01*
X676286Y756299D01*
X676219Y756899D01*
X676019Y757432D01*
X675752Y757832D01*
X675352Y758166D01*
X674819Y758299D01*
G01X679419Y754299D02*
X679886Y754366D01*
X680419Y754566D01*
X680752Y754899D01*
X680886Y755366D01*
X680752Y755832D01*
X680352Y756232D01*
X679752Y756432D01*
X679086D01*
X678686Y756566D01*
X678352Y756899D01*
X678219Y757366D01*
X678419Y757832D01*
X678886Y758166D01*
X679419Y758299D01*
X679952Y758166D01*
X680419Y757832D01*
X680619Y757366D01*
X680486Y756899D01*
X680152Y756566D01*
X679752Y756432D01*
X679086D01*
X678486Y756232D01*
X678086Y755832D01*
X677952Y755366D01*
X678086Y754899D01*
X678419Y754566D01*
X678952Y754366D01*
X679419Y754299D01*
G01X684019Y754166D02*
X683886Y754232D01*
Y754366D01*
X684019Y754432D01*
X684152Y754366D01*
Y754232D01*
X684019Y754166D01*
G01X687352Y755966D02*
X687819Y756432D01*
X688219Y756699D01*
X688752Y756832D01*
X689219Y756699D01*
X689552Y756432D01*
X689819Y756032D01*
X689886Y755566D01*
X689819Y755166D01*
X689552Y754766D01*
X689152Y754432D01*
X688686Y754299D01*
X688152Y754432D01*
X687686Y754832D01*
X687419Y755432D01*
X687352Y756099D01*
X687486Y756966D01*
X687686Y757432D01*
X688019Y757899D01*
X688486Y758232D01*
X688952Y758299D01*
X689419Y758166D01*
X689752Y757832D01*
G01X691952Y755966D02*
X692419Y756432D01*
X692819Y756699D01*
X693352Y756832D01*
X693819Y756699D01*
X694152Y756432D01*
X694419Y756032D01*
X694486Y755566D01*
X694419Y755166D01*
X694152Y754766D01*
X693752Y754432D01*
X693286Y754299D01*
X692752Y754432D01*
X692286Y754832D01*
X692019Y755432D01*
X691952Y756099D01*
X692086Y756966D01*
X692286Y757432D01*
X692619Y757899D01*
X693086Y758232D01*
X693552Y758299D01*
X694019Y758166D01*
X694352Y757832D01*
G01X662397Y715465D02*
Y719465D01*
X663731D01*
X664264Y719265D01*
X664664Y718998D01*
X664997Y718598D01*
X665264Y718132D01*
X665331Y717465D01*
X665264Y716798D01*
X664997Y716332D01*
X664664Y715932D01*
X664264Y715665D01*
X663731Y715465D01*
X662397D01*
G01X667531D02*
Y718132D01*
G01Y717598D02*
X667864Y717865D01*
X668197Y718065D01*
X668664Y718132D01*
X668997Y718065D01*
X669397Y717865D01*
G01X673064Y718132D02*
Y715465D01*
G01Y719198D02*
X672931Y719265D01*
Y719398D01*
X673064Y719465D01*
X673197Y719398D01*
Y719265D01*
X673064Y719198D01*
G01X677664Y715465D02*
Y719465D01*
G01X682264Y715465D02*
Y719465D01*
G01X691064Y715465D02*
Y718865D01*
X691197Y719198D01*
X691464Y719398D01*
X691864Y719465D01*
X692264Y719332D01*
X692464Y718998D01*
G01X691664Y717865D02*
X690331D01*
G01X695064Y717265D02*
X697197D01*
X696997Y717732D01*
X696664Y717998D01*
X696197Y718132D01*
X695731Y718065D01*
X695331Y717865D01*
X695064Y717398D01*
X694931Y716998D01*
Y716598D01*
X695064Y716198D01*
X695397Y715798D01*
X695797Y715532D01*
X696264Y715465D01*
X696731Y715598D01*
X697197Y715998D01*
G01X701864Y715465D02*
Y718132D01*
G01Y717665D02*
X701597Y717932D01*
X701197Y718065D01*
X700731Y718132D01*
X700264Y717998D01*
X699864Y717732D01*
X699597Y717332D01*
X699464Y716798D01*
X699597Y716265D01*
X699864Y715865D01*
X700264Y715598D01*
X700731Y715465D01*
X701197Y715532D01*
X701597Y715732D01*
X701864Y715998D01*
G01X705264Y719465D02*
Y715465D01*
G01X704331Y718132D02*
X706197D01*
G01X708731D02*
Y716265D01*
X708997Y715798D01*
X709397Y715532D01*
X709864Y715465D01*
X710331Y715532D01*
X710731Y715798D01*
X710997Y716265D01*
G01Y715465D02*
Y718132D01*
G01X713531Y715465D02*
Y718132D01*
G01Y717598D02*
X713864Y717865D01*
X714197Y718065D01*
X714664Y718132D01*
X714997Y718065D01*
X715397Y717865D01*
G01X718064Y717265D02*
X720197D01*
X719997Y717732D01*
X719664Y717998D01*
X719197Y718132D01*
X718731Y718065D01*
X718331Y717865D01*
X718064Y717398D01*
X717931Y716998D01*
Y716598D01*
X718064Y716198D01*
X718397Y715798D01*
X718797Y715532D01*
X719264Y715465D01*
X719731Y715598D01*
X720197Y715998D01*
G01X637244Y730599D02*
G03X644169Y717468I37662J11471D01*
G01X637244Y730599D02*
G03X644169Y717468I37662J11471D01*
G01X637244Y730599D02*
G03X617283I-9980J-3040D01*
G01X610358Y717468D02*
G03X617283Y730599I-30737J24601D01*
G01X637244D02*
G03X617283I-9980J-3040D01*
G01X610358Y717468D02*
G03X617283Y730599I-30737J24601D01*
G01X610358Y717468D02*
G03X644169I16906J-13531D01*
G01X610358D02*
G03X644169I16906J-13531D01*
G01X670807Y805568D02*
X671207Y805235D01*
X671674Y805035D01*
X672274Y804968D01*
X672874Y805101D01*
X673341Y805368D01*
X673674Y805835D01*
X673741Y806368D01*
X673607Y806901D01*
X673274Y807235D01*
X672807Y807501D01*
X672341Y807568D01*
X671874Y807501D01*
X671274Y807235D01*
X671474Y808968D01*
X673274D01*
G01X675407Y805568D02*
X675807Y805235D01*
X676274Y805035D01*
X676874Y804968D01*
X677474Y805101D01*
X677941Y805368D01*
X678274Y805835D01*
X678341Y806368D01*
X678207Y806901D01*
X677874Y807235D01*
X677407Y807501D01*
X676941Y807568D01*
X676474Y807501D01*
X675874Y807235D01*
X676074Y808968D01*
X677874D01*
G01X681341Y804968D02*
X681474Y805835D01*
X681674Y806568D01*
X681941Y807235D01*
X682274Y807968D01*
X682807Y808968D01*
X680141D01*
G01X686074Y804835D02*
X685941Y804901D01*
Y805035D01*
X686074Y805101D01*
X686207Y805035D01*
Y804901D01*
X686074Y804835D01*
G01X690674Y808968D02*
X690141Y808835D01*
X689741Y808501D01*
X689474Y808101D01*
X689274Y807568D01*
X689207Y806968D01*
X689274Y806368D01*
X689474Y805835D01*
X689741Y805435D01*
X690141Y805101D01*
X690674Y804968D01*
X691207Y805101D01*
X691607Y805435D01*
X691874Y805835D01*
X692074Y806368D01*
X692141Y806968D01*
X692074Y807568D01*
X691874Y808101D01*
X691607Y808501D01*
X691207Y808835D01*
X690674Y808968D01*
G01X694141Y805435D02*
X694607Y805101D01*
X695141Y804968D01*
X695674Y805101D01*
X696141Y805501D01*
X696474Y806101D01*
X696607Y806701D01*
Y807435D01*
X696474Y808035D01*
X696141Y808568D01*
X695741Y808835D01*
X695274Y808968D01*
X694741Y808835D01*
X694341Y808568D01*
X694074Y808168D01*
X693941Y807635D01*
X694074Y807168D01*
X694407Y806701D01*
X694807Y806435D01*
X695274Y806368D01*
X695807Y806501D01*
X696207Y806835D01*
X696607Y807435D01*
G01X668860Y1126063D02*
Y1130063D01*
X666393Y1127196D01*
X669727D01*
G01X671193Y1126863D02*
X671593Y1126396D01*
X672127Y1126130D01*
X672727Y1126063D01*
X673260Y1126130D01*
X673793Y1126463D01*
X674127Y1126863D01*
X674193Y1127263D01*
X674060Y1127730D01*
X673593Y1128063D01*
X673127Y1128196D01*
X672527D01*
G01X673127D02*
X673527Y1128396D01*
X673860Y1128730D01*
X673993Y1129130D01*
X673860Y1129530D01*
X673527Y1129863D01*
X672927Y1130063D01*
X672327Y1129996D01*
X671727Y1129730D01*
G01X675793Y1126863D02*
X676193Y1126396D01*
X676727Y1126130D01*
X677327Y1126063D01*
X677860Y1126130D01*
X678393Y1126463D01*
X678727Y1126863D01*
X678793Y1127263D01*
X678660Y1127730D01*
X678193Y1128063D01*
X677727Y1128196D01*
X677127D01*
G01X677727D02*
X678127Y1128396D01*
X678460Y1128730D01*
X678593Y1129130D01*
X678460Y1129530D01*
X678127Y1129863D01*
X677527Y1130063D01*
X676927Y1129996D01*
X676327Y1129730D01*
G01X681860Y1125930D02*
X681727Y1125996D01*
Y1126130D01*
X681860Y1126196D01*
X681993Y1126130D01*
Y1125996D01*
X681860Y1125930D01*
G01X686460Y1130063D02*
X685927Y1129930D01*
X685527Y1129596D01*
X685260Y1129196D01*
X685060Y1128663D01*
X684993Y1128063D01*
X685060Y1127463D01*
X685260Y1126930D01*
X685527Y1126530D01*
X685927Y1126196D01*
X686460Y1126063D01*
X686993Y1126196D01*
X687393Y1126530D01*
X687660Y1126930D01*
X687860Y1127463D01*
X687927Y1128063D01*
X687860Y1128663D01*
X687660Y1129196D01*
X687393Y1129596D01*
X686993Y1129930D01*
X686460Y1130063D01*
G01X691060Y1126063D02*
X691527Y1126130D01*
X692060Y1126330D01*
X692393Y1126663D01*
X692527Y1127130D01*
X692393Y1127596D01*
X691993Y1127996D01*
X691393Y1128196D01*
X690727D01*
X690327Y1128330D01*
X689993Y1128663D01*
X689860Y1129130D01*
X690060Y1129596D01*
X690527Y1129930D01*
X691060Y1130063D01*
X691593Y1129930D01*
X692060Y1129596D01*
X692260Y1129130D01*
X692127Y1128663D01*
X691793Y1128330D01*
X691393Y1128196D01*
X690727D01*
X690127Y1127996D01*
X689727Y1127596D01*
X689593Y1127130D01*
X689727Y1126663D01*
X690060Y1126330D01*
X690593Y1126130D01*
X691060Y1126063D01*
G01X610358Y1170224D02*
G03X644169I16906J-13531D01*
G01X610358D02*
G03X644169I16906J-13531D01*
G01X668952Y1210387D02*
X669352Y1210787D01*
X669819Y1210987D01*
X670352Y1211054D01*
X671019Y1210921D01*
X671486Y1210587D01*
X671619Y1210187D01*
X671552Y1209787D01*
X671286Y1209454D01*
X669952Y1208787D01*
X669352Y1208321D01*
X668952Y1207654D01*
X668819Y1207054D01*
X671619D01*
G01X674819Y1211054D02*
X674286Y1210921D01*
X673886Y1210587D01*
X673619Y1210187D01*
X673419Y1209654D01*
X673352Y1209054D01*
X673419Y1208454D01*
X673619Y1207921D01*
X673886Y1207521D01*
X674286Y1207187D01*
X674819Y1207054D01*
X675352Y1207187D01*
X675752Y1207521D01*
X676019Y1207921D01*
X676219Y1208454D01*
X676286Y1209054D01*
X676219Y1209654D01*
X676019Y1210187D01*
X675752Y1210587D01*
X675352Y1210921D01*
X674819Y1211054D01*
G01X679419Y1207054D02*
X679886Y1207121D01*
X680419Y1207321D01*
X680752Y1207654D01*
X680886Y1208121D01*
X680752Y1208587D01*
X680352Y1208987D01*
X679752Y1209187D01*
X679086D01*
X678686Y1209321D01*
X678352Y1209654D01*
X678219Y1210121D01*
X678419Y1210587D01*
X678886Y1210921D01*
X679419Y1211054D01*
X679952Y1210921D01*
X680419Y1210587D01*
X680619Y1210121D01*
X680486Y1209654D01*
X680152Y1209321D01*
X679752Y1209187D01*
X679086D01*
X678486Y1208987D01*
X678086Y1208587D01*
X677952Y1208121D01*
X678086Y1207654D01*
X678419Y1207321D01*
X678952Y1207121D01*
X679419Y1207054D01*
G01X684019Y1206921D02*
X683886Y1206987D01*
Y1207121D01*
X684019Y1207187D01*
X684152Y1207121D01*
Y1206987D01*
X684019Y1206921D01*
G01X687352Y1208721D02*
X687819Y1209187D01*
X688219Y1209454D01*
X688752Y1209587D01*
X689219Y1209454D01*
X689552Y1209187D01*
X689819Y1208787D01*
X689886Y1208321D01*
X689819Y1207921D01*
X689552Y1207521D01*
X689152Y1207187D01*
X688686Y1207054D01*
X688152Y1207187D01*
X687686Y1207587D01*
X687419Y1208187D01*
X687352Y1208854D01*
X687486Y1209721D01*
X687686Y1210187D01*
X688019Y1210654D01*
X688486Y1210987D01*
X688952Y1211054D01*
X689419Y1210921D01*
X689752Y1210587D01*
G01X691952Y1208721D02*
X692419Y1209187D01*
X692819Y1209454D01*
X693352Y1209587D01*
X693819Y1209454D01*
X694152Y1209187D01*
X694419Y1208787D01*
X694486Y1208321D01*
X694419Y1207921D01*
X694152Y1207521D01*
X693752Y1207187D01*
X693286Y1207054D01*
X692752Y1207187D01*
X692286Y1207587D01*
X692019Y1208187D01*
X691952Y1208854D01*
X692086Y1209721D01*
X692286Y1210187D01*
X692619Y1210654D01*
X693086Y1210987D01*
X693552Y1211054D01*
X694019Y1210921D01*
X694352Y1210587D01*
G01X662397Y1168220D02*
Y1172220D01*
X663731D01*
X664264Y1172020D01*
X664664Y1171753D01*
X664997Y1171353D01*
X665264Y1170887D01*
X665331Y1170220D01*
X665264Y1169553D01*
X664997Y1169087D01*
X664664Y1168687D01*
X664264Y1168420D01*
X663731Y1168220D01*
X662397D01*
G01X667531D02*
Y1170887D01*
G01Y1170353D02*
X667864Y1170620D01*
X668197Y1170820D01*
X668664Y1170887D01*
X668997Y1170820D01*
X669397Y1170620D01*
G01X673064Y1170887D02*
Y1168220D01*
G01Y1171953D02*
X672931Y1172020D01*
Y1172153D01*
X673064Y1172220D01*
X673197Y1172153D01*
Y1172020D01*
X673064Y1171953D01*
G01X677664Y1168220D02*
Y1172220D01*
G01X682264Y1168220D02*
Y1172220D01*
G01X691064Y1168220D02*
Y1171620D01*
X691197Y1171953D01*
X691464Y1172153D01*
X691864Y1172220D01*
X692264Y1172087D01*
X692464Y1171753D01*
G01X691664Y1170620D02*
X690331D01*
G01X695064Y1170020D02*
X697197D01*
X696997Y1170487D01*
X696664Y1170753D01*
X696197Y1170887D01*
X695731Y1170820D01*
X695331Y1170620D01*
X695064Y1170153D01*
X694931Y1169753D01*
Y1169353D01*
X695064Y1168953D01*
X695397Y1168553D01*
X695797Y1168287D01*
X696264Y1168220D01*
X696731Y1168353D01*
X697197Y1168753D01*
G01X701864Y1168220D02*
Y1170887D01*
G01Y1170420D02*
X701597Y1170687D01*
X701197Y1170820D01*
X700731Y1170887D01*
X700264Y1170753D01*
X699864Y1170487D01*
X699597Y1170087D01*
X699464Y1169553D01*
X699597Y1169020D01*
X699864Y1168620D01*
X700264Y1168353D01*
X700731Y1168220D01*
X701197Y1168287D01*
X701597Y1168487D01*
X701864Y1168753D01*
G01X705264Y1172220D02*
Y1168220D01*
G01X704331Y1170887D02*
X706197D01*
G01X708731D02*
Y1169020D01*
X708997Y1168553D01*
X709397Y1168287D01*
X709864Y1168220D01*
X710331Y1168287D01*
X710731Y1168553D01*
X710997Y1169020D01*
G01Y1168220D02*
Y1170887D01*
G01X713531Y1168220D02*
Y1170887D01*
G01Y1170353D02*
X713864Y1170620D01*
X714197Y1170820D01*
X714664Y1170887D01*
X714997Y1170820D01*
X715397Y1170620D01*
G01X718064Y1170020D02*
X720197D01*
X719997Y1170487D01*
X719664Y1170753D01*
X719197Y1170887D01*
X718731Y1170820D01*
X718331Y1170620D01*
X718064Y1170153D01*
X717931Y1169753D01*
Y1169353D01*
X718064Y1168953D01*
X718397Y1168553D01*
X718797Y1168287D01*
X719264Y1168220D01*
X719731Y1168353D01*
X720197Y1168753D01*
G01X637244Y1183355D02*
G03X644169Y1170224I37662J11471D01*
G01X637244Y1183355D02*
G03X644169Y1170224I37662J11471D01*
G01X637244Y1183355D02*
G03X617283I-9980J-3040D01*
G01X637244D02*
G03X617283I-9980J-3040D01*
G01X610358Y1170224D02*
G03X617283Y1183355I-30737J24602D01*
G01X610358Y1170224D02*
G03X617283Y1183355I-30737J24601D01*
G01X765439Y228992D02*
Y232992D01*
X767039D01*
X767572Y232792D01*
X767972Y232325D01*
X768105Y231792D01*
X767972Y231259D01*
X767639Y230859D01*
X767039Y230659D01*
X765439D01*
G01X770439Y228992D02*
Y231659D01*
G01Y231125D02*
X770772Y231392D01*
X771105Y231592D01*
X771572Y231659D01*
X771905Y231592D01*
X772305Y231392D01*
G01X774972Y230792D02*
X777105D01*
X776905Y231259D01*
X776572Y231525D01*
X776105Y231659D01*
X775639Y231592D01*
X775239Y231392D01*
X774972Y230925D01*
X774839Y230525D01*
Y230125D01*
X774972Y229725D01*
X775305Y229325D01*
X775705Y229059D01*
X776172Y228992D01*
X776639Y229125D01*
X777105Y229525D01*
G01X779572Y229459D02*
X779905Y229192D01*
X780372Y228992D01*
X780772D01*
X781172Y229125D01*
X781439Y229325D01*
X781572Y229592D01*
X781505Y229992D01*
X781239Y230192D01*
X780039Y230592D01*
X779772Y231059D01*
X779905Y231392D01*
X780172Y231592D01*
X780572Y231659D01*
X780972Y231592D01*
X781372Y231392D01*
G01X784172Y229459D02*
X784505Y229192D01*
X784972Y228992D01*
X785372D01*
X785772Y229125D01*
X786039Y229325D01*
X786172Y229592D01*
X786105Y229992D01*
X785839Y230192D01*
X784639Y230592D01*
X784372Y231059D01*
X784505Y231392D01*
X784772Y231592D01*
X785172Y231659D01*
X785572Y231592D01*
X785972Y231392D01*
G01X788905Y230325D02*
X790639D01*
G01X793972Y228992D02*
Y232392D01*
X794105Y232725D01*
X794372Y232925D01*
X794772Y232992D01*
X795172Y232859D01*
X795372Y232525D01*
G01X794572Y231392D02*
X793239D01*
G01X798972Y231659D02*
Y228992D01*
G01Y232725D02*
X798839Y232792D01*
Y232925D01*
X798972Y232992D01*
X799105Y232925D01*
Y232792D01*
X798972Y232725D01*
G01X803572Y232992D02*
Y228992D01*
G01X802639Y231659D02*
X804505D01*
G01X811439Y228992D02*
Y232992D01*
X813039D01*
X813572Y232792D01*
X813972Y232325D01*
X814105Y231792D01*
X813972Y231259D01*
X813639Y230859D01*
X813039Y230659D01*
X811439D01*
G01X817372Y232992D02*
Y228992D01*
G01X815839Y232992D02*
X818905D01*
G01X820572Y228992D02*
Y232992D01*
G01X823372D02*
Y228992D01*
G01Y230992D02*
X820572D01*
G01X830039Y228992D02*
Y232992D01*
G01X832172Y231659D02*
X830039Y230125D01*
G01X830905Y230725D02*
X832305Y228992D01*
G01X834772Y230792D02*
X836905D01*
X836705Y231259D01*
X836372Y231525D01*
X835905Y231659D01*
X835439Y231592D01*
X835039Y231392D01*
X834772Y230925D01*
X834639Y230525D01*
Y230125D01*
X834772Y229725D01*
X835105Y229325D01*
X835505Y229059D01*
X835972Y228992D01*
X836439Y229125D01*
X836905Y229525D01*
G01X839372Y230792D02*
X841505D01*
X841305Y231259D01*
X840972Y231525D01*
X840505Y231659D01*
X840039Y231592D01*
X839639Y231392D01*
X839372Y230925D01*
X839239Y230525D01*
Y230125D01*
X839372Y229725D01*
X839705Y229325D01*
X840105Y229059D01*
X840572Y228992D01*
X841039Y229125D01*
X841505Y229525D01*
G01X843772Y227659D02*
Y231659D01*
G01Y231059D02*
X844105Y231392D01*
X844439Y231592D01*
X844972Y231659D01*
X845439Y231592D01*
X845905Y231259D01*
X846105Y230792D01*
X846172Y230325D01*
X846105Y229859D01*
X845905Y229392D01*
X845505Y229125D01*
X844972Y228992D01*
X844505Y229059D01*
X844039Y229259D01*
X843772Y229525D01*
G01X853039Y228992D02*
Y232992D01*
G01Y231059D02*
X853372Y231392D01*
X853705Y231592D01*
X854239Y231659D01*
X854639Y231592D01*
X855105Y231325D01*
X855305Y230925D01*
Y228992D01*
G01X858772D02*
X858372Y229059D01*
X857972Y229325D01*
X857705Y229792D01*
X857572Y230325D01*
X857705Y230859D01*
X857972Y231325D01*
X858372Y231592D01*
X858772Y231659D01*
X859172Y231592D01*
X859572Y231325D01*
X859839Y230859D01*
X859905Y230325D01*
X859839Y229792D01*
X859572Y229325D01*
X859172Y229059D01*
X858772Y228992D01*
G01X863372D02*
Y232992D01*
G01X866972Y230792D02*
X869105D01*
X868905Y231259D01*
X868572Y231525D01*
X868105Y231659D01*
X867639Y231592D01*
X867239Y231392D01*
X866972Y230925D01*
X866839Y230525D01*
Y230125D01*
X866972Y229725D01*
X867305Y229325D01*
X867705Y229059D01*
X868172Y228992D01*
X868639Y229125D01*
X869105Y229525D01*
G01X876172Y229459D02*
X876505Y229192D01*
X876972Y228992D01*
X877372D01*
X877772Y229125D01*
X878039Y229325D01*
X878172Y229592D01*
X878105Y229992D01*
X877839Y230192D01*
X876639Y230592D01*
X876372Y231059D01*
X876505Y231392D01*
X876772Y231592D01*
X877172Y231659D01*
X877572Y231592D01*
X877972Y231392D01*
G01X881772Y231659D02*
Y228992D01*
G01Y232725D02*
X881639Y232792D01*
Y232925D01*
X881772Y232992D01*
X881905Y232925D01*
Y232792D01*
X881772Y232725D01*
G01X885372Y231659D02*
X887372D01*
X885372Y228992D01*
X887372D01*
G01X889972Y230792D02*
X892105D01*
X891905Y231259D01*
X891572Y231525D01*
X891105Y231659D01*
X890639Y231592D01*
X890239Y231392D01*
X889972Y230925D01*
X889839Y230525D01*
Y230125D01*
X889972Y229725D01*
X890305Y229325D01*
X890705Y229059D01*
X891172Y228992D01*
X891639Y229125D01*
X892105Y229525D01*
G01X900172Y232992D02*
Y228992D01*
G01X899239Y231659D02*
X901105D01*
G01X904772Y228992D02*
X904372Y229059D01*
X903972Y229325D01*
X903705Y229792D01*
X903572Y230325D01*
X903705Y230859D01*
X903972Y231325D01*
X904372Y231592D01*
X904772Y231659D01*
X905172Y231592D01*
X905572Y231325D01*
X905839Y230859D01*
X905905Y230325D01*
X905839Y229792D01*
X905572Y229325D01*
X905172Y229059D01*
X904772Y228992D01*
G01X909372D02*
Y232992D01*
G01X912972Y230792D02*
X915105D01*
X914905Y231259D01*
X914572Y231525D01*
X914105Y231659D01*
X913639Y231592D01*
X913239Y231392D01*
X912972Y230925D01*
X912839Y230525D01*
Y230125D01*
X912972Y229725D01*
X913305Y229325D01*
X913705Y229059D01*
X914172Y228992D01*
X914639Y229125D01*
X915105Y229525D01*
G01X917639Y228992D02*
Y231659D01*
G01Y231125D02*
X917972Y231392D01*
X918305Y231592D01*
X918772Y231659D01*
X919105Y231592D01*
X919505Y231392D01*
G01X924372Y228992D02*
Y231659D01*
G01Y231192D02*
X924105Y231459D01*
X923705Y231592D01*
X923239Y231659D01*
X922772Y231525D01*
X922372Y231259D01*
X922105Y230859D01*
X921972Y230325D01*
X922105Y229792D01*
X922372Y229392D01*
X922772Y229125D01*
X923239Y228992D01*
X923705Y229059D01*
X924105Y229259D01*
X924372Y229525D01*
G01X926639Y228992D02*
Y231659D01*
G01Y230992D02*
X926905Y231325D01*
X927305Y231592D01*
X927839Y231659D01*
X928305Y231592D01*
X928705Y231325D01*
X928905Y230859D01*
Y228992D01*
G01X933439Y231325D02*
X932972Y231592D01*
X932572Y231659D01*
X932039Y231525D01*
X931639Y231259D01*
X931372Y230792D01*
X931305Y230325D01*
X931372Y229859D01*
X931639Y229459D01*
X932039Y229125D01*
X932572Y228992D01*
X933039Y229125D01*
X933439Y229392D01*
G01X935972Y230792D02*
X938105D01*
X937905Y231259D01*
X937572Y231525D01*
X937105Y231659D01*
X936639Y231592D01*
X936239Y231392D01*
X935972Y230925D01*
X935839Y230525D01*
Y230125D01*
X935972Y229725D01*
X936305Y229325D01*
X936705Y229059D01*
X937172Y228992D01*
X937639Y229125D01*
X938105Y229525D01*
G01X950039Y230325D02*
X951639D01*
G01X950772Y231192D02*
Y229459D01*
G01X954172Y228859D02*
X956572Y232992D01*
G01X959105Y230325D02*
X960839D01*
G01X963305Y232325D02*
X963705Y232725D01*
X964172Y232925D01*
X964705Y232992D01*
X965372Y232859D01*
X965839Y232525D01*
X965972Y232125D01*
X965905Y231725D01*
X965639Y231392D01*
X964305Y230725D01*
X963705Y230259D01*
X963305Y229592D01*
X963172Y228992D01*
X965972D01*
G01X971772D02*
Y231659D01*
G01Y230925D02*
X971972Y231259D01*
X972305Y231525D01*
X972772Y231659D01*
X973239Y231525D01*
X973572Y231259D01*
X973772Y230925D01*
Y228992D01*
G01Y230925D02*
X973972Y231259D01*
X974305Y231525D01*
X974772Y231659D01*
X975239Y231525D01*
X975572Y231259D01*
X975772Y230859D01*
Y228992D01*
G01X978372Y231659D02*
Y228992D01*
G01Y232725D02*
X978239Y232792D01*
Y232925D01*
X978372Y232992D01*
X978505Y232925D01*
Y232792D01*
X978372Y232725D01*
G01X982972Y228992D02*
Y232992D01*
G01X986572Y229459D02*
X986905Y229192D01*
X987372Y228992D01*
X987772D01*
X988172Y229125D01*
X988439Y229325D01*
X988572Y229592D01*
X988505Y229992D01*
X988239Y230192D01*
X987039Y230592D01*
X986772Y231059D01*
X986905Y231392D01*
X987172Y231592D01*
X987572Y231659D01*
X987972Y231592D01*
X988372Y231392D01*
G01X688146Y383043D02*
X688546Y383443D01*
X689013Y383643D01*
X689546Y383710D01*
X690213Y383577D01*
X690680Y383243D01*
X690813Y382843D01*
X690746Y382443D01*
X690480Y382110D01*
X689146Y381443D01*
X688546Y380977D01*
X688146Y380310D01*
X688013Y379710D01*
X690813D01*
G01X692546Y380510D02*
X692946Y380043D01*
X693480Y379777D01*
X694080Y379710D01*
X694613Y379777D01*
X695146Y380110D01*
X695480Y380510D01*
X695546Y380910D01*
X695413Y381377D01*
X694946Y381710D01*
X694480Y381843D01*
X693880D01*
G01X694480D02*
X694880Y382043D01*
X695213Y382377D01*
X695346Y382777D01*
X695213Y383177D01*
X694880Y383510D01*
X694280Y383710D01*
X693680Y383643D01*
X693080Y383377D01*
G01X697346Y381377D02*
X697813Y381843D01*
X698213Y382110D01*
X698746Y382243D01*
X699213Y382110D01*
X699546Y381843D01*
X699813Y381443D01*
X699880Y380977D01*
X699813Y380577D01*
X699546Y380177D01*
X699146Y379843D01*
X698680Y379710D01*
X698146Y379843D01*
X697680Y380243D01*
X697413Y380843D01*
X697346Y381510D01*
X697480Y382377D01*
X697680Y382843D01*
X698013Y383310D01*
X698480Y383643D01*
X698946Y383710D01*
X699413Y383577D01*
X699746Y383243D01*
G01X703213Y379577D02*
X703080Y379643D01*
Y379777D01*
X703213Y379843D01*
X703346Y379777D01*
Y379643D01*
X703213Y379577D01*
G01X706546Y383043D02*
X706946Y383443D01*
X707413Y383643D01*
X707946Y383710D01*
X708613Y383577D01*
X709080Y383243D01*
X709213Y382843D01*
X709146Y382443D01*
X708880Y382110D01*
X707546Y381443D01*
X706946Y380977D01*
X706546Y380310D01*
X706413Y379710D01*
X709213D01*
G01X711146Y383043D02*
X711546Y383443D01*
X712013Y383643D01*
X712546Y383710D01*
X713213Y383577D01*
X713680Y383243D01*
X713813Y382843D01*
X713746Y382443D01*
X713480Y382110D01*
X712146Y381443D01*
X711546Y380977D01*
X711146Y380310D01*
X711013Y379710D01*
X713813D01*
G01X730339Y383610D02*
G03X764149I16905J-13531D01*
G01X730339Y383609D02*
G03X764150I16905J-13530D01*
G01X757225Y396741D02*
G03X764149Y383610I37663J11469D01*
G01X757224Y396741D02*
G03X764150Y383609I37662J11471D01*
G01X757225Y396741D02*
G03X737264I-9981J-3040D01*
G01X730339Y383610D02*
G03X737264Y396741I-30737J24602D01*
G01X757224D02*
G03X737264I-9980J-3041D01*
G01X730339Y383609D02*
G03X737264Y396741I-30738J24601D01*
G01X688146Y816114D02*
X688546Y816514D01*
X689013Y816714D01*
X689546Y816781D01*
X690213Y816648D01*
X690680Y816314D01*
X690813Y815914D01*
X690746Y815514D01*
X690480Y815181D01*
X689146Y814514D01*
X688546Y814048D01*
X688146Y813381D01*
X688013Y812781D01*
X690813D01*
G01X692546Y813581D02*
X692946Y813114D01*
X693480Y812848D01*
X694080Y812781D01*
X694613Y812848D01*
X695146Y813181D01*
X695480Y813581D01*
X695546Y813981D01*
X695413Y814448D01*
X694946Y814781D01*
X694480Y814914D01*
X693880D01*
G01X694480D02*
X694880Y815114D01*
X695213Y815448D01*
X695346Y815848D01*
X695213Y816248D01*
X694880Y816581D01*
X694280Y816781D01*
X693680Y816714D01*
X693080Y816448D01*
G01X697346Y814448D02*
X697813Y814914D01*
X698213Y815181D01*
X698746Y815314D01*
X699213Y815181D01*
X699546Y814914D01*
X699813Y814514D01*
X699880Y814048D01*
X699813Y813648D01*
X699546Y813248D01*
X699146Y812914D01*
X698680Y812781D01*
X698146Y812914D01*
X697680Y813314D01*
X697413Y813914D01*
X697346Y814581D01*
X697480Y815448D01*
X697680Y815914D01*
X698013Y816381D01*
X698480Y816714D01*
X698946Y816781D01*
X699413Y816648D01*
X699746Y816314D01*
G01X703213Y812648D02*
X703080Y812714D01*
Y812848D01*
X703213Y812914D01*
X703346Y812848D01*
Y812714D01*
X703213Y812648D01*
G01X706546Y816114D02*
X706946Y816514D01*
X707413Y816714D01*
X707946Y816781D01*
X708613Y816648D01*
X709080Y816314D01*
X709213Y815914D01*
X709146Y815514D01*
X708880Y815181D01*
X707546Y814514D01*
X706946Y814048D01*
X706546Y813381D01*
X706413Y812781D01*
X709213D01*
G01X711146Y816114D02*
X711546Y816514D01*
X712013Y816714D01*
X712546Y816781D01*
X713213Y816648D01*
X713680Y816314D01*
X713813Y815914D01*
X713746Y815514D01*
X713480Y815181D01*
X712146Y814514D01*
X711546Y814048D01*
X711146Y813381D01*
X711013Y812781D01*
X713813D01*
G01X757225Y829811D02*
G03X764149Y816680I37663J11469D01*
G01X757224Y829811D02*
G03X764150Y816680I37662J11473D01*
G01X757225Y829811D02*
G03X737264I-9981J-3039D01*
G01X757224D02*
G03X737264I-9980J-3040D01*
G01X730339Y816680D02*
G03X737264Y829811I-30737J24602D01*
G01X730339Y816680D02*
G03X737264Y829811I-30737J24602D01*
G01X730339Y816680D02*
G03X764149I16905J-13531D01*
G01X730339D02*
G03X764150I16905J-13531D01*
G01X721850Y1519685D02*
G03X717913Y1515748I0J-3937D01*
G01X775591Y1519685D02*
X721850D01*
G01D02*
G03X717913Y1515748I0J-3937D01*
G01X775591Y1519685D02*
X721850D01*
G01X713976Y1505118D02*
G03X717913Y1509055I0J3937D01*
G01Y1515748D02*
Y1509055D01*
G01X713976Y1505118D02*
G03X717913Y1509055I0J3937D01*
G01Y1515748D02*
Y1509055D01*
G01X684449Y1515748D02*
G03X680512Y1519685I-3937J0D01*
G01X684449Y1515748D02*
G03X680512Y1519685I-3937J0D01*
G01X684449Y1509055D02*
Y1515748D01*
G01Y1509055D02*
G03X688386Y1505118I3937J0D01*
G01X713976D02*
X688386D01*
G01X684449Y1509055D02*
G03X688386Y1505118I3937J0D01*
G01D02*
X713976D01*
G01X684449Y1515748D02*
Y1509055D01*
G01X791339Y3937D02*
G03X795276Y0I3937J0D01*
G01D02*
X892317D01*
G01X791339Y3937D02*
Y23622D01*
G01Y3937D02*
G03X795276Y0I3937J0D01*
G01X791339Y3937D02*
Y23622D01*
G01X795276Y0D02*
X892317D01*
G01X783465Y54331D02*
G03X791339I3937J0D01*
G01X783465D02*
G03X791339I3937J0D01*
G01Y23622D02*
G03X783465I-3937J0D01*
G01X791339D02*
G03X783465I-3937J0D01*
G01X779528Y0D02*
G03X783465Y3937I0J3937D01*
G01X779528Y0D02*
G03X783465Y3937I0J3937D01*
G01X791339Y54331D02*
Y181890D01*
G01Y54331D02*
Y181890D01*
G01X783465Y3937D02*
Y185827D01*
G01Y3937D02*
Y185827D01*
G01X811024Y181890D02*
G03X822835Y193701I0J11811D01*
G01X791339Y181890D02*
X811024D01*
G01D02*
G03X822835Y193701I0J11811D01*
G01X791339Y181890D02*
X811024D01*
G01X787402Y189764D02*
G03X783465Y185827I0J-3937D01*
G01X787402Y189764D02*
G03X783465Y185827I0J-3937D01*
G01X857601Y238493D02*
X858134Y238160D01*
X858734Y237960D01*
X859268D01*
X859801Y238160D01*
X860201Y238493D01*
X860401Y238960D01*
X860268Y239427D01*
X859934Y239827D01*
X859334Y240093D01*
X858534Y240227D01*
X858068Y240493D01*
X857868Y240960D01*
X858001Y241427D01*
X858334Y241760D01*
X858801Y241960D01*
X859268D01*
X859734Y241827D01*
X860134Y241493D01*
G01X863601Y237960D02*
Y241960D01*
G01X868201Y240627D02*
Y237960D01*
G01Y241693D02*
X868068Y241760D01*
Y241893D01*
X868201Y241960D01*
X868334Y241893D01*
Y241760D01*
X868201Y241693D01*
G01X872801Y241960D02*
Y237960D01*
G01X871868Y240627D02*
X873734D01*
G01X824472Y317654D02*
Y251637D01*
X914111D01*
Y317654D01*
X824472D01*
G01X796851Y248031D02*
X946457D01*
G01X811024Y189764D02*
G03X814961Y193701I0J3937D01*
G01X787402Y189764D02*
X811024D01*
G01D02*
G03X814961Y193701I0J3937D01*
G01X787402Y189764D02*
X811024D01*
G01X822835Y193701D02*
Y240157D01*
G01Y193701D02*
Y240157D01*
G01X814961Y193701D02*
Y244094D01*
G01Y193701D02*
Y244094D01*
G01X818898Y248031D02*
G03X814961Y244094I0J-3937D01*
G01X818898Y248031D02*
G03X814961Y244094I0J-3937D01*
G01X928098Y240157D02*
X822835D01*
G01X928098D02*
X822835D01*
G01X818898Y248031D02*
X1055118D01*
G01D02*
X818898D01*
G01X788841Y339449D02*
Y343449D01*
X786374Y340582D01*
X789708D01*
G01X791174Y340249D02*
X791574Y339782D01*
X792108Y339516D01*
X792708Y339449D01*
X793241Y339516D01*
X793774Y339849D01*
X794108Y340249D01*
X794174Y340649D01*
X794041Y341116D01*
X793574Y341449D01*
X793108Y341582D01*
X792508D01*
G01X793108D02*
X793508Y341782D01*
X793841Y342116D01*
X793974Y342516D01*
X793841Y342916D01*
X793508Y343249D01*
X792908Y343449D01*
X792308Y343382D01*
X791708Y343116D01*
G01X795774Y340249D02*
X796174Y339782D01*
X796708Y339516D01*
X797308Y339449D01*
X797841Y339516D01*
X798374Y339849D01*
X798708Y340249D01*
X798774Y340649D01*
X798641Y341116D01*
X798174Y341449D01*
X797708Y341582D01*
X797108D01*
G01X797708D02*
X798108Y341782D01*
X798441Y342116D01*
X798574Y342516D01*
X798441Y342916D01*
X798108Y343249D01*
X797508Y343449D01*
X796908Y343382D01*
X796308Y343116D01*
G01X801841Y339316D02*
X801708Y339382D01*
Y339516D01*
X801841Y339582D01*
X801974Y339516D01*
Y339382D01*
X801841Y339316D01*
G01X806441Y343449D02*
X805908Y343316D01*
X805508Y342982D01*
X805241Y342582D01*
X805041Y342049D01*
X804974Y341449D01*
X805041Y340849D01*
X805241Y340316D01*
X805508Y339916D01*
X805908Y339582D01*
X806441Y339449D01*
X806974Y339582D01*
X807374Y339916D01*
X807641Y340316D01*
X807841Y340849D01*
X807908Y341449D01*
X807841Y342049D01*
X807641Y342582D01*
X807374Y342982D01*
X806974Y343316D01*
X806441Y343449D01*
G01X811041Y339449D02*
X811508Y339516D01*
X812041Y339716D01*
X812374Y340049D01*
X812508Y340516D01*
X812374Y340982D01*
X811974Y341382D01*
X811374Y341582D01*
X810708D01*
X810308Y341716D01*
X809974Y342049D01*
X809841Y342516D01*
X810041Y342982D01*
X810508Y343316D01*
X811041Y343449D01*
X811574Y343316D01*
X812041Y342982D01*
X812241Y342516D01*
X812108Y342049D01*
X811774Y341716D01*
X811374Y341582D01*
X810708D01*
X810108Y341382D01*
X809708Y340982D01*
X809574Y340516D01*
X809708Y340049D01*
X810041Y339716D01*
X810574Y339516D01*
X811041Y339449D01*
G01X788933Y423773D02*
X789333Y424173D01*
X789800Y424373D01*
X790333Y424440D01*
X791000Y424307D01*
X791467Y423973D01*
X791600Y423573D01*
X791533Y423173D01*
X791267Y422840D01*
X789933Y422173D01*
X789333Y421707D01*
X788933Y421040D01*
X788800Y420440D01*
X791600D01*
G01X794800Y424440D02*
X794267Y424307D01*
X793867Y423973D01*
X793600Y423573D01*
X793400Y423040D01*
X793333Y422440D01*
X793400Y421840D01*
X793600Y421307D01*
X793867Y420907D01*
X794267Y420573D01*
X794800Y420440D01*
X795333Y420573D01*
X795733Y420907D01*
X796000Y421307D01*
X796200Y421840D01*
X796267Y422440D01*
X796200Y423040D01*
X796000Y423573D01*
X795733Y423973D01*
X795333Y424307D01*
X794800Y424440D01*
G01X799400Y420440D02*
X799867Y420507D01*
X800400Y420707D01*
X800733Y421040D01*
X800867Y421507D01*
X800733Y421973D01*
X800333Y422373D01*
X799733Y422573D01*
X799067D01*
X798667Y422707D01*
X798333Y423040D01*
X798200Y423507D01*
X798400Y423973D01*
X798867Y424307D01*
X799400Y424440D01*
X799933Y424307D01*
X800400Y423973D01*
X800600Y423507D01*
X800467Y423040D01*
X800133Y422707D01*
X799733Y422573D01*
X799067D01*
X798467Y422373D01*
X798067Y421973D01*
X797933Y421507D01*
X798067Y421040D01*
X798400Y420707D01*
X798933Y420507D01*
X799400Y420440D01*
G01X804000Y420307D02*
X803867Y420373D01*
Y420507D01*
X804000Y420573D01*
X804133Y420507D01*
Y420373D01*
X804000Y420307D01*
G01X807333Y422107D02*
X807800Y422573D01*
X808200Y422840D01*
X808733Y422973D01*
X809200Y422840D01*
X809533Y422573D01*
X809800Y422173D01*
X809867Y421707D01*
X809800Y421307D01*
X809533Y420907D01*
X809133Y420573D01*
X808667Y420440D01*
X808133Y420573D01*
X807667Y420973D01*
X807400Y421573D01*
X807333Y422240D01*
X807467Y423107D01*
X807667Y423573D01*
X808000Y424040D01*
X808467Y424373D01*
X808933Y424440D01*
X809400Y424307D01*
X809733Y423973D01*
G01X811933Y422107D02*
X812400Y422573D01*
X812800Y422840D01*
X813333Y422973D01*
X813800Y422840D01*
X814133Y422573D01*
X814400Y422173D01*
X814467Y421707D01*
X814400Y421307D01*
X814133Y420907D01*
X813733Y420573D01*
X813267Y420440D01*
X812733Y420573D01*
X812267Y420973D01*
X812000Y421573D01*
X811933Y422240D01*
X812067Y423107D01*
X812267Y423573D01*
X812600Y424040D01*
X813067Y424373D01*
X813533Y424440D01*
X814000Y424307D01*
X814333Y423973D01*
G01X782378Y381606D02*
Y385606D01*
X783712D01*
X784245Y385406D01*
X784645Y385139D01*
X784978Y384739D01*
X785245Y384273D01*
X785312Y383606D01*
X785245Y382939D01*
X784978Y382473D01*
X784645Y382073D01*
X784245Y381806D01*
X783712Y381606D01*
X782378D01*
G01X787512D02*
Y384273D01*
G01Y383739D02*
X787845Y384006D01*
X788178Y384206D01*
X788645Y384273D01*
X788978Y384206D01*
X789378Y384006D01*
G01X793045Y384273D02*
Y381606D01*
G01Y385339D02*
X792912Y385406D01*
Y385539D01*
X793045Y385606D01*
X793178Y385539D01*
Y385406D01*
X793045Y385339D01*
G01X797645Y381606D02*
Y385606D01*
G01X802245Y381606D02*
Y385606D01*
G01X811045Y381606D02*
Y385006D01*
X811178Y385339D01*
X811445Y385539D01*
X811845Y385606D01*
X812245Y385473D01*
X812445Y385139D01*
G01X811645Y384006D02*
X810312D01*
G01X815045Y383406D02*
X817178D01*
X816978Y383873D01*
X816645Y384139D01*
X816178Y384273D01*
X815712Y384206D01*
X815312Y384006D01*
X815045Y383539D01*
X814912Y383139D01*
Y382739D01*
X815045Y382339D01*
X815378Y381939D01*
X815778Y381673D01*
X816245Y381606D01*
X816712Y381739D01*
X817178Y382139D01*
G01X821845Y381606D02*
Y384273D01*
G01Y383806D02*
X821578Y384073D01*
X821178Y384206D01*
X820712Y384273D01*
X820245Y384139D01*
X819845Y383873D01*
X819578Y383473D01*
X819445Y382939D01*
X819578Y382406D01*
X819845Y382006D01*
X820245Y381739D01*
X820712Y381606D01*
X821178Y381673D01*
X821578Y381873D01*
X821845Y382139D01*
G01X825245Y385606D02*
Y381606D01*
G01X824312Y384273D02*
X826178D01*
G01X828712D02*
Y382406D01*
X828978Y381939D01*
X829378Y381673D01*
X829845Y381606D01*
X830312Y381673D01*
X830712Y381939D01*
X830978Y382406D01*
G01Y381606D02*
Y384273D01*
G01X833512Y381606D02*
Y384273D01*
G01Y383739D02*
X833845Y384006D01*
X834178Y384206D01*
X834645Y384273D01*
X834978Y384206D01*
X835378Y384006D01*
G01X838045Y383406D02*
X840178D01*
X839978Y383873D01*
X839645Y384139D01*
X839178Y384273D01*
X838712Y384206D01*
X838312Y384006D01*
X838045Y383539D01*
X837912Y383139D01*
Y382739D01*
X838045Y382339D01*
X838378Y381939D01*
X838778Y381673D01*
X839245Y381606D01*
X839712Y381739D01*
X840178Y382139D01*
G01X788841Y772520D02*
Y776520D01*
X786374Y773653D01*
X789708D01*
G01X791174Y773320D02*
X791574Y772853D01*
X792108Y772587D01*
X792708Y772520D01*
X793241Y772587D01*
X793774Y772920D01*
X794108Y773320D01*
X794174Y773720D01*
X794041Y774187D01*
X793574Y774520D01*
X793108Y774653D01*
X792508D01*
G01X793108D02*
X793508Y774853D01*
X793841Y775187D01*
X793974Y775587D01*
X793841Y775987D01*
X793508Y776320D01*
X792908Y776520D01*
X792308Y776453D01*
X791708Y776187D01*
G01X795774Y773320D02*
X796174Y772853D01*
X796708Y772587D01*
X797308Y772520D01*
X797841Y772587D01*
X798374Y772920D01*
X798708Y773320D01*
X798774Y773720D01*
X798641Y774187D01*
X798174Y774520D01*
X797708Y774653D01*
X797108D01*
G01X797708D02*
X798108Y774853D01*
X798441Y775187D01*
X798574Y775587D01*
X798441Y775987D01*
X798108Y776320D01*
X797508Y776520D01*
X796908Y776453D01*
X796308Y776187D01*
G01X801841Y772387D02*
X801708Y772453D01*
Y772587D01*
X801841Y772653D01*
X801974Y772587D01*
Y772453D01*
X801841Y772387D01*
G01X806441Y776520D02*
X805908Y776387D01*
X805508Y776053D01*
X805241Y775653D01*
X805041Y775120D01*
X804974Y774520D01*
X805041Y773920D01*
X805241Y773387D01*
X805508Y772987D01*
X805908Y772653D01*
X806441Y772520D01*
X806974Y772653D01*
X807374Y772987D01*
X807641Y773387D01*
X807841Y773920D01*
X807908Y774520D01*
X807841Y775120D01*
X807641Y775653D01*
X807374Y776053D01*
X806974Y776387D01*
X806441Y776520D01*
G01X811041Y772520D02*
X811508Y772587D01*
X812041Y772787D01*
X812374Y773120D01*
X812508Y773587D01*
X812374Y774053D01*
X811974Y774453D01*
X811374Y774653D01*
X810708D01*
X810308Y774787D01*
X809974Y775120D01*
X809841Y775587D01*
X810041Y776053D01*
X810508Y776387D01*
X811041Y776520D01*
X811574Y776387D01*
X812041Y776053D01*
X812241Y775587D01*
X812108Y775120D01*
X811774Y774787D01*
X811374Y774653D01*
X810708D01*
X810108Y774453D01*
X809708Y774053D01*
X809574Y773587D01*
X809708Y773120D01*
X810041Y772787D01*
X810574Y772587D01*
X811041Y772520D01*
G01X788933Y856844D02*
X789333Y857244D01*
X789800Y857444D01*
X790333Y857511D01*
X791000Y857378D01*
X791467Y857044D01*
X791600Y856644D01*
X791533Y856244D01*
X791267Y855911D01*
X789933Y855244D01*
X789333Y854778D01*
X788933Y854111D01*
X788800Y853511D01*
X791600D01*
G01X794800Y857511D02*
X794267Y857378D01*
X793867Y857044D01*
X793600Y856644D01*
X793400Y856111D01*
X793333Y855511D01*
X793400Y854911D01*
X793600Y854378D01*
X793867Y853978D01*
X794267Y853644D01*
X794800Y853511D01*
X795333Y853644D01*
X795733Y853978D01*
X796000Y854378D01*
X796200Y854911D01*
X796267Y855511D01*
X796200Y856111D01*
X796000Y856644D01*
X795733Y857044D01*
X795333Y857378D01*
X794800Y857511D01*
G01X799400Y853511D02*
X799867Y853578D01*
X800400Y853778D01*
X800733Y854111D01*
X800867Y854578D01*
X800733Y855044D01*
X800333Y855444D01*
X799733Y855644D01*
X799067D01*
X798667Y855778D01*
X798333Y856111D01*
X798200Y856578D01*
X798400Y857044D01*
X798867Y857378D01*
X799400Y857511D01*
X799933Y857378D01*
X800400Y857044D01*
X800600Y856578D01*
X800467Y856111D01*
X800133Y855778D01*
X799733Y855644D01*
X799067D01*
X798467Y855444D01*
X798067Y855044D01*
X797933Y854578D01*
X798067Y854111D01*
X798400Y853778D01*
X798933Y853578D01*
X799400Y853511D01*
G01X804000Y853378D02*
X803867Y853444D01*
Y853578D01*
X804000Y853644D01*
X804133Y853578D01*
Y853444D01*
X804000Y853378D01*
G01X807333Y855178D02*
X807800Y855644D01*
X808200Y855911D01*
X808733Y856044D01*
X809200Y855911D01*
X809533Y855644D01*
X809800Y855244D01*
X809867Y854778D01*
X809800Y854378D01*
X809533Y853978D01*
X809133Y853644D01*
X808667Y853511D01*
X808133Y853644D01*
X807667Y854044D01*
X807400Y854644D01*
X807333Y855311D01*
X807467Y856178D01*
X807667Y856644D01*
X808000Y857111D01*
X808467Y857444D01*
X808933Y857511D01*
X809400Y857378D01*
X809733Y857044D01*
G01X811933Y855178D02*
X812400Y855644D01*
X812800Y855911D01*
X813333Y856044D01*
X813800Y855911D01*
X814133Y855644D01*
X814400Y855244D01*
X814467Y854778D01*
X814400Y854378D01*
X814133Y853978D01*
X813733Y853644D01*
X813267Y853511D01*
X812733Y853644D01*
X812267Y854044D01*
X812000Y854644D01*
X811933Y855311D01*
X812067Y856178D01*
X812267Y856644D01*
X812600Y857111D01*
X813067Y857444D01*
X813533Y857511D01*
X814000Y857378D01*
X814333Y857044D01*
G01X782378Y814677D02*
Y818677D01*
X783712D01*
X784245Y818477D01*
X784645Y818210D01*
X784978Y817810D01*
X785245Y817344D01*
X785312Y816677D01*
X785245Y816010D01*
X784978Y815544D01*
X784645Y815144D01*
X784245Y814877D01*
X783712Y814677D01*
X782378D01*
G01X787512D02*
Y817344D01*
G01Y816810D02*
X787845Y817077D01*
X788178Y817277D01*
X788645Y817344D01*
X788978Y817277D01*
X789378Y817077D01*
G01X793045Y817344D02*
Y814677D01*
G01Y818410D02*
X792912Y818477D01*
Y818610D01*
X793045Y818677D01*
X793178Y818610D01*
Y818477D01*
X793045Y818410D01*
G01X797645Y814677D02*
Y818677D01*
G01X802245Y814677D02*
Y818677D01*
G01X811045Y814677D02*
Y818077D01*
X811178Y818410D01*
X811445Y818610D01*
X811845Y818677D01*
X812245Y818544D01*
X812445Y818210D01*
G01X811645Y817077D02*
X810312D01*
G01X815045Y816477D02*
X817178D01*
X816978Y816944D01*
X816645Y817210D01*
X816178Y817344D01*
X815712Y817277D01*
X815312Y817077D01*
X815045Y816610D01*
X814912Y816210D01*
Y815810D01*
X815045Y815410D01*
X815378Y815010D01*
X815778Y814744D01*
X816245Y814677D01*
X816712Y814810D01*
X817178Y815210D01*
G01X821845Y814677D02*
Y817344D01*
G01Y816877D02*
X821578Y817144D01*
X821178Y817277D01*
X820712Y817344D01*
X820245Y817210D01*
X819845Y816944D01*
X819578Y816544D01*
X819445Y816010D01*
X819578Y815477D01*
X819845Y815077D01*
X820245Y814810D01*
X820712Y814677D01*
X821178Y814744D01*
X821578Y814944D01*
X821845Y815210D01*
G01X825245Y818677D02*
Y814677D01*
G01X824312Y817344D02*
X826178D01*
G01X828712D02*
Y815477D01*
X828978Y815010D01*
X829378Y814744D01*
X829845Y814677D01*
X830312Y814744D01*
X830712Y815010D01*
X830978Y815477D01*
G01Y814677D02*
Y817344D01*
G01X833512Y814677D02*
Y817344D01*
G01Y816810D02*
X833845Y817077D01*
X834178Y817277D01*
X834645Y817344D01*
X834978Y817277D01*
X835378Y817077D01*
G01X838045Y816477D02*
X840178D01*
X839978Y816944D01*
X839645Y817210D01*
X839178Y817344D01*
X838712Y817277D01*
X838312Y817077D01*
X838045Y816610D01*
X837912Y816210D01*
Y815810D01*
X838045Y815410D01*
X838378Y815010D01*
X838778Y814744D01*
X839245Y814677D01*
X839712Y814810D01*
X840178Y815210D01*
G01X954331Y1503937D02*
X817323D01*
G01X954331D02*
X817323D01*
G01X791339Y1519685D02*
G03X787402Y1515748I0J-3937D01*
G01X791339Y1519685D02*
X980315D01*
G01X791339D02*
G03X787402Y1515748I0J-3937D01*
G01X791339Y1519685D02*
X980315D01*
G01X817323Y1503937D02*
G03Y1496063I0J-3937D01*
G01X799213D02*
G03Y1503937I0J3937D01*
G01D02*
X787402D01*
G01Y1515748D02*
Y1503937D01*
G01X799213D02*
X787402D01*
G01X817323D02*
G03Y1496063I0J-3937D01*
G01X799213D02*
G03Y1503937I0J3937D01*
G01X787402Y1515748D02*
Y1503937D01*
G01X779528Y1515748D02*
G03X775591Y1519685I-3937J0D01*
G01X779528Y1515748D02*
G03X775591Y1519685I-3937J0D01*
G01X779528Y1500000D02*
Y1515748D01*
G01Y1500000D02*
G03X783465Y1496063I3937J0D01*
G01X988189D02*
X783465D01*
G01X779528Y1500000D02*
G03X783465Y1496063I3937J0D01*
G01X988189D02*
X783465D01*
G01X779528Y1515748D02*
Y1500000D01*
G01X900191Y0D02*
G03X892317I-3937J0D01*
G01X896254D02*
Y-394D01*
G01Y0D02*
Y394D01*
G01X895762Y0D02*
X896746D01*
G01X900191D02*
G03X892317I-3937J0D01*
G01X900191D02*
X1212598D01*
G01X900191D02*
X1212598D01*
G01X882772Y250992D02*
X878772Y246992D01*
X886772D01*
X882772Y250992D01*
Y234992D01*
G01X865901Y247460D02*
X863901Y245460D01*
X867901D01*
X865901Y247460D01*
Y241460D01*
G01X953294Y248031D02*
G03Y240157I1J-3937D01*
G01X1051181D02*
X953294D01*
G01Y248031D02*
G03Y240157I1J-3937D01*
G01X928098D02*
G03Y248031I0J3937D01*
G01Y240157D02*
G03Y248031I0J3937D01*
G01X1051181Y240157D02*
X953294D01*
G01X1116140Y327906D02*
Y323906D01*
X1114540D01*
X1114007Y324106D01*
X1113607Y324573D01*
X1113474Y325106D01*
X1113607Y325639D01*
X1113940Y326039D01*
X1114540Y326239D01*
X1116140D01*
G01X1111140Y327906D02*
Y325239D01*
G01Y325773D02*
X1110807Y325506D01*
X1110474Y325306D01*
X1110007Y325239D01*
X1109674Y325306D01*
X1109274Y325506D01*
G01X1106607Y326106D02*
X1104474D01*
X1104674Y325639D01*
X1105007Y325373D01*
X1105474Y325239D01*
X1105940Y325306D01*
X1106340Y325506D01*
X1106607Y325973D01*
X1106740Y326373D01*
Y326773D01*
X1106607Y327173D01*
X1106274Y327573D01*
X1105874Y327839D01*
X1105407Y327906D01*
X1104940Y327773D01*
X1104474Y327373D01*
G01X1102007Y327439D02*
X1101674Y327706D01*
X1101207Y327906D01*
X1100807D01*
X1100407Y327773D01*
X1100140Y327573D01*
X1100007Y327306D01*
X1100074Y326906D01*
X1100340Y326706D01*
X1101540Y326306D01*
X1101807Y325839D01*
X1101674Y325506D01*
X1101407Y325306D01*
X1101007Y325239D01*
X1100607Y325306D01*
X1100207Y325506D01*
G01X1097407Y327439D02*
X1097074Y327706D01*
X1096607Y327906D01*
X1096207D01*
X1095807Y327773D01*
X1095540Y327573D01*
X1095407Y327306D01*
X1095474Y326906D01*
X1095740Y326706D01*
X1096940Y326306D01*
X1097207Y325839D01*
X1097074Y325506D01*
X1096807Y325306D01*
X1096407Y325239D01*
X1096007Y325306D01*
X1095607Y325506D01*
G01X1092674Y326573D02*
X1090940D01*
G01X1087607Y327906D02*
Y324506D01*
X1087474Y324173D01*
X1087207Y323973D01*
X1086807Y323906D01*
X1086407Y324039D01*
X1086207Y324373D01*
G01X1087007Y325506D02*
X1088340D01*
G01X1082607Y325239D02*
Y327906D01*
G01Y324173D02*
X1082740Y324106D01*
Y323973D01*
X1082607Y323906D01*
X1082474Y323973D01*
Y324106D01*
X1082607Y324173D01*
G01X1078007Y323906D02*
Y327906D01*
G01X1078940Y325239D02*
X1077074D01*
G01X1070140Y327906D02*
Y323906D01*
X1068540D01*
X1068007Y324106D01*
X1067607Y324573D01*
X1067474Y325106D01*
X1067607Y325639D01*
X1067940Y326039D01*
X1068540Y326239D01*
X1070140D01*
G01X1064207Y323906D02*
Y327906D01*
G01X1065740Y323906D02*
X1062674D01*
G01X1061007Y327906D02*
Y323906D01*
G01X1058207D02*
Y327906D01*
G01Y325906D02*
X1061007D01*
G01X1051540Y327906D02*
Y323906D01*
G01X1049407Y325239D02*
X1051540Y326773D01*
G01X1050674Y326173D02*
X1049274Y327906D01*
G01X1046807Y326106D02*
X1044674D01*
X1044874Y325639D01*
X1045207Y325373D01*
X1045674Y325239D01*
X1046140Y325306D01*
X1046540Y325506D01*
X1046807Y325973D01*
X1046940Y326373D01*
Y326773D01*
X1046807Y327173D01*
X1046474Y327573D01*
X1046074Y327839D01*
X1045607Y327906D01*
X1045140Y327773D01*
X1044674Y327373D01*
G01X1042207Y326106D02*
X1040074D01*
X1040274Y325639D01*
X1040607Y325373D01*
X1041074Y325239D01*
X1041540Y325306D01*
X1041940Y325506D01*
X1042207Y325973D01*
X1042340Y326373D01*
Y326773D01*
X1042207Y327173D01*
X1041874Y327573D01*
X1041474Y327839D01*
X1041007Y327906D01*
X1040540Y327773D01*
X1040074Y327373D01*
G01X1037807Y329239D02*
Y325239D01*
G01Y325839D02*
X1037474Y325506D01*
X1037140Y325306D01*
X1036607Y325239D01*
X1036140Y325306D01*
X1035674Y325639D01*
X1035474Y326106D01*
X1035407Y326573D01*
X1035474Y327039D01*
X1035674Y327506D01*
X1036074Y327773D01*
X1036607Y327906D01*
X1037074Y327839D01*
X1037540Y327639D01*
X1037807Y327373D01*
G01X1028540Y327906D02*
Y323906D01*
G01Y325839D02*
X1028207Y325506D01*
X1027874Y325306D01*
X1027340Y325239D01*
X1026940Y325306D01*
X1026474Y325573D01*
X1026274Y325973D01*
Y327906D01*
G01X1022807D02*
X1023207Y327839D01*
X1023607Y327573D01*
X1023874Y327106D01*
X1024007Y326573D01*
X1023874Y326039D01*
X1023607Y325573D01*
X1023207Y325306D01*
X1022807Y325239D01*
X1022407Y325306D01*
X1022007Y325573D01*
X1021740Y326039D01*
X1021674Y326573D01*
X1021740Y327106D01*
X1022007Y327573D01*
X1022407Y327839D01*
X1022807Y327906D01*
G01X1018207D02*
Y323906D01*
G01X1014607Y326106D02*
X1012474D01*
X1012674Y325639D01*
X1013007Y325373D01*
X1013474Y325239D01*
X1013940Y325306D01*
X1014340Y325506D01*
X1014607Y325973D01*
X1014740Y326373D01*
Y326773D01*
X1014607Y327173D01*
X1014274Y327573D01*
X1013874Y327839D01*
X1013407Y327906D01*
X1012940Y327773D01*
X1012474Y327373D01*
G01X1005407Y327439D02*
X1005074Y327706D01*
X1004607Y327906D01*
X1004207D01*
X1003807Y327773D01*
X1003540Y327573D01*
X1003407Y327306D01*
X1003474Y326906D01*
X1003740Y326706D01*
X1004940Y326306D01*
X1005207Y325839D01*
X1005074Y325506D01*
X1004807Y325306D01*
X1004407Y325239D01*
X1004007Y325306D01*
X1003607Y325506D01*
G01X999807Y325239D02*
Y327906D01*
G01Y324173D02*
X999940Y324106D01*
Y323973D01*
X999807Y323906D01*
X999674Y323973D01*
Y324106D01*
X999807Y324173D01*
G01X996207Y325239D02*
X994207D01*
X996207Y327906D01*
X994207D01*
G01X991607Y326106D02*
X989474D01*
X989674Y325639D01*
X990007Y325373D01*
X990474Y325239D01*
X990940Y325306D01*
X991340Y325506D01*
X991607Y325973D01*
X991740Y326373D01*
Y326773D01*
X991607Y327173D01*
X991274Y327573D01*
X990874Y327839D01*
X990407Y327906D01*
X989940Y327773D01*
X989474Y327373D01*
G01X981407Y323906D02*
Y327906D01*
G01X982340Y325239D02*
X980474D01*
G01X976807Y327906D02*
X977207Y327839D01*
X977607Y327573D01*
X977874Y327106D01*
X978007Y326573D01*
X977874Y326039D01*
X977607Y325573D01*
X977207Y325306D01*
X976807Y325239D01*
X976407Y325306D01*
X976007Y325573D01*
X975740Y326039D01*
X975674Y326573D01*
X975740Y327106D01*
X976007Y327573D01*
X976407Y327839D01*
X976807Y327906D01*
G01X972207D02*
Y323906D01*
G01X968607Y326106D02*
X966474D01*
X966674Y325639D01*
X967007Y325373D01*
X967474Y325239D01*
X967940Y325306D01*
X968340Y325506D01*
X968607Y325973D01*
X968740Y326373D01*
Y326773D01*
X968607Y327173D01*
X968274Y327573D01*
X967874Y327839D01*
X967407Y327906D01*
X966940Y327773D01*
X966474Y327373D01*
G01X963940Y327906D02*
Y325239D01*
G01Y325773D02*
X963607Y325506D01*
X963274Y325306D01*
X962807Y325239D01*
X962474Y325306D01*
X962074Y325506D01*
G01X957207Y327906D02*
Y325239D01*
G01Y325706D02*
X957474Y325439D01*
X957874Y325306D01*
X958340Y325239D01*
X958807Y325373D01*
X959207Y325639D01*
X959474Y326039D01*
X959607Y326573D01*
X959474Y327106D01*
X959207Y327506D01*
X958807Y327773D01*
X958340Y327906D01*
X957874Y327839D01*
X957474Y327639D01*
X957207Y327373D01*
G01X954940Y327906D02*
Y325239D01*
G01Y325906D02*
X954674Y325573D01*
X954274Y325306D01*
X953740Y325239D01*
X953274Y325306D01*
X952874Y325573D01*
X952674Y326039D01*
Y327906D01*
G01X948140Y325573D02*
X948607Y325306D01*
X949007Y325239D01*
X949540Y325373D01*
X949940Y325639D01*
X950207Y326106D01*
X950274Y326573D01*
X950207Y327039D01*
X949940Y327439D01*
X949540Y327773D01*
X949007Y327906D01*
X948540Y327773D01*
X948140Y327506D01*
G01X945607Y326106D02*
X943474D01*
X943674Y325639D01*
X944007Y325373D01*
X944474Y325239D01*
X944940Y325306D01*
X945340Y325506D01*
X945607Y325973D01*
X945740Y326373D01*
Y326773D01*
X945607Y327173D01*
X945274Y327573D01*
X944874Y327839D01*
X944407Y327906D01*
X943940Y327773D01*
X943474Y327373D01*
G01X936140Y326573D02*
X934540D01*
G01X935407Y325706D02*
Y327439D01*
G01X932007Y328039D02*
X929607Y323906D01*
G01X927074Y326573D02*
X925340D01*
G01X922874Y324573D02*
X922474Y324173D01*
X922007Y323973D01*
X921474Y323906D01*
X920807Y324039D01*
X920340Y324373D01*
X920207Y324773D01*
X920274Y325173D01*
X920540Y325506D01*
X921874Y326173D01*
X922474Y326639D01*
X922874Y327306D01*
X923007Y327906D01*
X920207D01*
G01X914407D02*
Y325239D01*
G01Y325973D02*
X914207Y325639D01*
X913874Y325373D01*
X913407Y325239D01*
X912940Y325373D01*
X912607Y325639D01*
X912407Y325973D01*
Y327906D01*
G01Y325973D02*
X912207Y325639D01*
X911874Y325373D01*
X911407Y325239D01*
X910940Y325373D01*
X910607Y325639D01*
X910407Y326039D01*
Y327906D01*
G01X907807Y325239D02*
Y327906D01*
G01Y324173D02*
X907940Y324106D01*
Y323973D01*
X907807Y323906D01*
X907674Y323973D01*
Y324106D01*
X907807Y324173D01*
G01X903207Y327906D02*
Y323906D01*
G01X899607Y327439D02*
X899274Y327706D01*
X898807Y327906D01*
X898407D01*
X898007Y327773D01*
X897740Y327573D01*
X897607Y327306D01*
X897674Y326906D01*
X897940Y326706D01*
X899140Y326306D01*
X899407Y325839D01*
X899274Y325506D01*
X899007Y325306D01*
X898607Y325239D01*
X898207Y325306D01*
X897807Y325506D01*
G01X884980Y694544D02*
X885380Y694211D01*
X885847Y694011D01*
X886447Y693944D01*
X887047Y694077D01*
X887514Y694344D01*
X887847Y694811D01*
X887914Y695344D01*
X887780Y695877D01*
X887447Y696211D01*
X886980Y696477D01*
X886514Y696544D01*
X886047Y696477D01*
X885447Y696211D01*
X885647Y697944D01*
X887447D01*
G01X889580Y694544D02*
X889980Y694211D01*
X890447Y694011D01*
X891047Y693944D01*
X891647Y694077D01*
X892114Y694344D01*
X892447Y694811D01*
X892514Y695344D01*
X892380Y695877D01*
X892047Y696211D01*
X891580Y696477D01*
X891114Y696544D01*
X890647Y696477D01*
X890047Y696211D01*
X890247Y697944D01*
X892047D01*
G01X895514Y693944D02*
X895647Y694811D01*
X895847Y695544D01*
X896114Y696211D01*
X896447Y696944D01*
X896980Y697944D01*
X894314D01*
G01X900247Y693811D02*
X900114Y693877D01*
Y694011D01*
X900247Y694077D01*
X900380Y694011D01*
Y693877D01*
X900247Y693811D01*
G01X904847Y697944D02*
X904314Y697811D01*
X903914Y697477D01*
X903647Y697077D01*
X903447Y696544D01*
X903380Y695944D01*
X903447Y695344D01*
X903647Y694811D01*
X903914Y694411D01*
X904314Y694077D01*
X904847Y693944D01*
X905380Y694077D01*
X905780Y694411D01*
X906047Y694811D01*
X906247Y695344D01*
X906314Y695944D01*
X906247Y696544D01*
X906047Y697077D01*
X905780Y697477D01*
X905380Y697811D01*
X904847Y697944D01*
G01X908314Y694411D02*
X908780Y694077D01*
X909314Y693944D01*
X909847Y694077D01*
X910314Y694477D01*
X910647Y695077D01*
X910780Y695677D01*
Y696411D01*
X910647Y697011D01*
X910314Y697544D01*
X909914Y697811D01*
X909447Y697944D01*
X908914Y697811D01*
X908514Y697544D01*
X908247Y697144D01*
X908114Y696611D01*
X908247Y696144D01*
X908580Y695677D01*
X908980Y695411D01*
X909447Y695344D01*
X909980Y695477D01*
X910380Y695811D01*
X910780Y696411D01*
G01X902319Y705090D02*
X902719Y705490D01*
X903186Y705690D01*
X903719Y705757D01*
X904386Y705624D01*
X904853Y705290D01*
X904986Y704890D01*
X904919Y704490D01*
X904653Y704157D01*
X903319Y703490D01*
X902719Y703024D01*
X902319Y702357D01*
X902186Y701757D01*
X904986D01*
G01X906719Y702557D02*
X907119Y702090D01*
X907653Y701824D01*
X908253Y701757D01*
X908786Y701824D01*
X909319Y702157D01*
X909653Y702557D01*
X909719Y702957D01*
X909586Y703424D01*
X909119Y703757D01*
X908653Y703890D01*
X908053D01*
G01X908653D02*
X909053Y704090D01*
X909386Y704424D01*
X909519Y704824D01*
X909386Y705224D01*
X909053Y705557D01*
X908453Y705757D01*
X907853Y705690D01*
X907253Y705424D01*
G01X911519Y703424D02*
X911986Y703890D01*
X912386Y704157D01*
X912919Y704290D01*
X913386Y704157D01*
X913719Y703890D01*
X913986Y703490D01*
X914053Y703024D01*
X913986Y702624D01*
X913719Y702224D01*
X913319Y701890D01*
X912853Y701757D01*
X912319Y701890D01*
X911853Y702290D01*
X911586Y702890D01*
X911519Y703557D01*
X911653Y704424D01*
X911853Y704890D01*
X912186Y705357D01*
X912653Y705690D01*
X913119Y705757D01*
X913586Y705624D01*
X913919Y705290D01*
G01X917386Y701624D02*
X917253Y701690D01*
Y701824D01*
X917386Y701890D01*
X917519Y701824D01*
Y701690D01*
X917386Y701624D01*
G01X920719Y705090D02*
X921119Y705490D01*
X921586Y705690D01*
X922119Y705757D01*
X922786Y705624D01*
X923253Y705290D01*
X923386Y704890D01*
X923319Y704490D01*
X923053Y704157D01*
X921719Y703490D01*
X921119Y703024D01*
X920719Y702357D01*
X920586Y701757D01*
X923386D01*
G01X925319Y705090D02*
X925719Y705490D01*
X926186Y705690D01*
X926719Y705757D01*
X927386Y705624D01*
X927853Y705290D01*
X927986Y704890D01*
X927919Y704490D01*
X927653Y704157D01*
X926319Y703490D01*
X925719Y703024D01*
X925319Y702357D01*
X925186Y701757D01*
X927986D01*
G01X971398Y718788D02*
G03X951437I-9980J-3040D01*
G01X944512Y705657D02*
G03X951437Y718788I-30737J24602D01*
G01X971398D02*
G03X951437I-9980J-3040D01*
G01X944512Y705657D02*
G03X951437Y718788I-30737J24602D01*
G01X944512Y705657D02*
G03X978323I16905J-13531D01*
G01X944512D02*
G03X978323I16905J-13531D01*
G01X944512Y974161D02*
G03X978323I16905J-13531D01*
G01X944512D02*
G03X978323I16905J-13531D01*
G01X884980Y963048D02*
X885380Y962715D01*
X885847Y962515D01*
X886447Y962448D01*
X887047Y962581D01*
X887514Y962848D01*
X887847Y963315D01*
X887914Y963848D01*
X887780Y964381D01*
X887447Y964715D01*
X886980Y964981D01*
X886514Y965048D01*
X886047Y964981D01*
X885447Y964715D01*
X885647Y966448D01*
X887447D01*
G01X889580Y963048D02*
X889980Y962715D01*
X890447Y962515D01*
X891047Y962448D01*
X891647Y962581D01*
X892114Y962848D01*
X892447Y963315D01*
X892514Y963848D01*
X892380Y964381D01*
X892047Y964715D01*
X891580Y964981D01*
X891114Y965048D01*
X890647Y964981D01*
X890047Y964715D01*
X890247Y966448D01*
X892047D01*
G01X895514Y962448D02*
X895647Y963315D01*
X895847Y964048D01*
X896114Y964715D01*
X896447Y965448D01*
X896980Y966448D01*
X894314D01*
G01X900247Y962315D02*
X900114Y962381D01*
Y962515D01*
X900247Y962581D01*
X900380Y962515D01*
Y962381D01*
X900247Y962315D01*
G01X904847Y966448D02*
X904314Y966315D01*
X903914Y965981D01*
X903647Y965581D01*
X903447Y965048D01*
X903380Y964448D01*
X903447Y963848D01*
X903647Y963315D01*
X903914Y962915D01*
X904314Y962581D01*
X904847Y962448D01*
X905380Y962581D01*
X905780Y962915D01*
X906047Y963315D01*
X906247Y963848D01*
X906314Y964448D01*
X906247Y965048D01*
X906047Y965581D01*
X905780Y965981D01*
X905380Y966315D01*
X904847Y966448D01*
G01X908314Y962915D02*
X908780Y962581D01*
X909314Y962448D01*
X909847Y962581D01*
X910314Y962981D01*
X910647Y963581D01*
X910780Y964181D01*
Y964915D01*
X910647Y965515D01*
X910314Y966048D01*
X909914Y966315D01*
X909447Y966448D01*
X908914Y966315D01*
X908514Y966048D01*
X908247Y965648D01*
X908114Y965115D01*
X908247Y964648D01*
X908580Y964181D01*
X908980Y963915D01*
X909447Y963848D01*
X909980Y963981D01*
X910380Y964315D01*
X910780Y964915D01*
G01X902319Y973594D02*
X902719Y973994D01*
X903186Y974194D01*
X903719Y974261D01*
X904386Y974128D01*
X904853Y973794D01*
X904986Y973394D01*
X904919Y972994D01*
X904653Y972661D01*
X903319Y971994D01*
X902719Y971528D01*
X902319Y970861D01*
X902186Y970261D01*
X904986D01*
G01X906719Y971061D02*
X907119Y970594D01*
X907653Y970328D01*
X908253Y970261D01*
X908786Y970328D01*
X909319Y970661D01*
X909653Y971061D01*
X909719Y971461D01*
X909586Y971928D01*
X909119Y972261D01*
X908653Y972394D01*
X908053D01*
G01X908653D02*
X909053Y972594D01*
X909386Y972928D01*
X909519Y973328D01*
X909386Y973728D01*
X909053Y974061D01*
X908453Y974261D01*
X907853Y974194D01*
X907253Y973928D01*
G01X911519Y971928D02*
X911986Y972394D01*
X912386Y972661D01*
X912919Y972794D01*
X913386Y972661D01*
X913719Y972394D01*
X913986Y971994D01*
X914053Y971528D01*
X913986Y971128D01*
X913719Y970728D01*
X913319Y970394D01*
X912853Y970261D01*
X912319Y970394D01*
X911853Y970794D01*
X911586Y971394D01*
X911519Y972061D01*
X911653Y972928D01*
X911853Y973394D01*
X912186Y973861D01*
X912653Y974194D01*
X913119Y974261D01*
X913586Y974128D01*
X913919Y973794D01*
G01X917386Y970128D02*
X917253Y970194D01*
Y970328D01*
X917386Y970394D01*
X917519Y970328D01*
Y970194D01*
X917386Y970128D01*
G01X920719Y973594D02*
X921119Y973994D01*
X921586Y974194D01*
X922119Y974261D01*
X922786Y974128D01*
X923253Y973794D01*
X923386Y973394D01*
X923319Y972994D01*
X923053Y972661D01*
X921719Y971994D01*
X921119Y971528D01*
X920719Y970861D01*
X920586Y970261D01*
X923386D01*
G01X925319Y973594D02*
X925719Y973994D01*
X926186Y974194D01*
X926719Y974261D01*
X927386Y974128D01*
X927853Y973794D01*
X927986Y973394D01*
X927919Y972994D01*
X927653Y972661D01*
X926319Y971994D01*
X925719Y971528D01*
X925319Y970861D01*
X925186Y970261D01*
X927986D01*
G01X971398Y987292D02*
G03X951437I-9980J-3040D01*
G01X944512Y974161D02*
G03X951437Y987292I-30737J24602D01*
G01X971398D02*
G03X951437I-9980J-3040D01*
G01X944512Y974161D02*
G03X951437Y987292I-30737J24602D01*
G01X954331Y1496063D02*
G03Y1503937I0J3937D01*
G01Y1496063D02*
G03Y1503937I0J3937D01*
G01X1051181Y193701D02*
G03X1062992Y181890I11811J0D01*
G01X1051181Y193701D02*
G03X1062992Y181890I11811J0D01*
G01X1019707Y239873D02*
X1019174Y240206D01*
X1018574Y240406D01*
X1018040D01*
X1017507Y240206D01*
X1017107Y239873D01*
X1016907Y239406D01*
X1017040Y238939D01*
X1017374Y238539D01*
X1017974Y238273D01*
X1018774Y238139D01*
X1019240Y237873D01*
X1019440Y237406D01*
X1019307Y236939D01*
X1018974Y236606D01*
X1018507Y236406D01*
X1018040D01*
X1017574Y236539D01*
X1017174Y236873D01*
G01X1013707Y240406D02*
Y236406D01*
G01X1009107Y237739D02*
Y240406D01*
G01Y236673D02*
X1009240Y236606D01*
Y236473D01*
X1009107Y236406D01*
X1008974Y236473D01*
Y236606D01*
X1009107Y236673D01*
G01X1004507Y236406D02*
Y240406D01*
G01X1005440Y237739D02*
X1003574D01*
G01X1011466Y238133D02*
Y247833D01*
X1006466Y242833D01*
X1016466D01*
X1011466Y247833D01*
G01X1054907Y248032D02*
X961907D01*
G01X1046707Y252506D02*
X970615D01*
Y316393D01*
X1046707D01*
Y252506D01*
G01X1051181Y240157D02*
Y193701D01*
G01Y240157D02*
Y193701D01*
G01X1043307Y326393D02*
Y316693D01*
X1038307Y321693D01*
X1048307D01*
X1043307Y316693D01*
G01X1003014Y661496D02*
Y665496D01*
X1000547Y662629D01*
X1003881D01*
G01X1005347Y662296D02*
X1005747Y661829D01*
X1006281Y661563D01*
X1006881Y661496D01*
X1007414Y661563D01*
X1007947Y661896D01*
X1008281Y662296D01*
X1008347Y662696D01*
X1008214Y663163D01*
X1007747Y663496D01*
X1007281Y663629D01*
X1006681D01*
G01X1007281D02*
X1007681Y663829D01*
X1008014Y664163D01*
X1008147Y664563D01*
X1008014Y664963D01*
X1007681Y665296D01*
X1007081Y665496D01*
X1006481Y665429D01*
X1005881Y665163D01*
G01X1009947Y662296D02*
X1010347Y661829D01*
X1010881Y661563D01*
X1011481Y661496D01*
X1012014Y661563D01*
X1012547Y661896D01*
X1012881Y662296D01*
X1012947Y662696D01*
X1012814Y663163D01*
X1012347Y663496D01*
X1011881Y663629D01*
X1011281D01*
G01X1011881D02*
X1012281Y663829D01*
X1012614Y664163D01*
X1012747Y664563D01*
X1012614Y664963D01*
X1012281Y665296D01*
X1011681Y665496D01*
X1011081Y665429D01*
X1010481Y665163D01*
G01X1016014Y661363D02*
X1015881Y661429D01*
Y661563D01*
X1016014Y661629D01*
X1016147Y661563D01*
Y661429D01*
X1016014Y661363D01*
G01X1020614Y665496D02*
X1020081Y665363D01*
X1019681Y665029D01*
X1019414Y664629D01*
X1019214Y664096D01*
X1019147Y663496D01*
X1019214Y662896D01*
X1019414Y662363D01*
X1019681Y661963D01*
X1020081Y661629D01*
X1020614Y661496D01*
X1021147Y661629D01*
X1021547Y661963D01*
X1021814Y662363D01*
X1022014Y662896D01*
X1022081Y663496D01*
X1022014Y664096D01*
X1021814Y664629D01*
X1021547Y665029D01*
X1021147Y665363D01*
X1020614Y665496D01*
G01X1025214Y661496D02*
X1025681Y661563D01*
X1026214Y661763D01*
X1026547Y662096D01*
X1026681Y662563D01*
X1026547Y663029D01*
X1026147Y663429D01*
X1025547Y663629D01*
X1024881D01*
X1024481Y663763D01*
X1024147Y664096D01*
X1024014Y664563D01*
X1024214Y665029D01*
X1024681Y665363D01*
X1025214Y665496D01*
X1025747Y665363D01*
X1026214Y665029D01*
X1026414Y664563D01*
X1026281Y664096D01*
X1025947Y663763D01*
X1025547Y663629D01*
X1024881D01*
X1024281Y663429D01*
X1023881Y663029D01*
X1023747Y662563D01*
X1023881Y662096D01*
X1024214Y661763D01*
X1024747Y661563D01*
X1025214Y661496D01*
G01X1003106Y745820D02*
X1003506Y746220D01*
X1003973Y746420D01*
X1004506Y746487D01*
X1005173Y746354D01*
X1005640Y746020D01*
X1005773Y745620D01*
X1005706Y745220D01*
X1005440Y744887D01*
X1004106Y744220D01*
X1003506Y743754D01*
X1003106Y743087D01*
X1002973Y742487D01*
X1005773D01*
G01X1008973Y746487D02*
X1008440Y746354D01*
X1008040Y746020D01*
X1007773Y745620D01*
X1007573Y745087D01*
X1007506Y744487D01*
X1007573Y743887D01*
X1007773Y743354D01*
X1008040Y742954D01*
X1008440Y742620D01*
X1008973Y742487D01*
X1009506Y742620D01*
X1009906Y742954D01*
X1010173Y743354D01*
X1010373Y743887D01*
X1010440Y744487D01*
X1010373Y745087D01*
X1010173Y745620D01*
X1009906Y746020D01*
X1009506Y746354D01*
X1008973Y746487D01*
G01X1013573Y742487D02*
X1014040Y742554D01*
X1014573Y742754D01*
X1014906Y743087D01*
X1015040Y743554D01*
X1014906Y744020D01*
X1014506Y744420D01*
X1013906Y744620D01*
X1013240D01*
X1012840Y744754D01*
X1012506Y745087D01*
X1012373Y745554D01*
X1012573Y746020D01*
X1013040Y746354D01*
X1013573Y746487D01*
X1014106Y746354D01*
X1014573Y746020D01*
X1014773Y745554D01*
X1014640Y745087D01*
X1014306Y744754D01*
X1013906Y744620D01*
X1013240D01*
X1012640Y744420D01*
X1012240Y744020D01*
X1012106Y743554D01*
X1012240Y743087D01*
X1012573Y742754D01*
X1013106Y742554D01*
X1013573Y742487D01*
G01X1018173Y742354D02*
X1018040Y742420D01*
Y742554D01*
X1018173Y742620D01*
X1018306Y742554D01*
Y742420D01*
X1018173Y742354D01*
G01X1021506Y744154D02*
X1021973Y744620D01*
X1022373Y744887D01*
X1022906Y745020D01*
X1023373Y744887D01*
X1023706Y744620D01*
X1023973Y744220D01*
X1024040Y743754D01*
X1023973Y743354D01*
X1023706Y742954D01*
X1023306Y742620D01*
X1022840Y742487D01*
X1022306Y742620D01*
X1021840Y743020D01*
X1021573Y743620D01*
X1021506Y744287D01*
X1021640Y745154D01*
X1021840Y745620D01*
X1022173Y746087D01*
X1022640Y746420D01*
X1023106Y746487D01*
X1023573Y746354D01*
X1023906Y746020D01*
G01X1026106Y744154D02*
X1026573Y744620D01*
X1026973Y744887D01*
X1027506Y745020D01*
X1027973Y744887D01*
X1028306Y744620D01*
X1028573Y744220D01*
X1028640Y743754D01*
X1028573Y743354D01*
X1028306Y742954D01*
X1027906Y742620D01*
X1027440Y742487D01*
X1026906Y742620D01*
X1026440Y743020D01*
X1026173Y743620D01*
X1026106Y744287D01*
X1026240Y745154D01*
X1026440Y745620D01*
X1026773Y746087D01*
X1027240Y746420D01*
X1027706Y746487D01*
X1028173Y746354D01*
X1028506Y746020D01*
G01X996551Y703653D02*
Y707653D01*
X997885D01*
X998418Y707453D01*
X998818Y707186D01*
X999151Y706786D01*
X999418Y706320D01*
X999485Y705653D01*
X999418Y704986D01*
X999151Y704520D01*
X998818Y704120D01*
X998418Y703853D01*
X997885Y703653D01*
X996551D01*
G01X1001685D02*
Y706320D01*
G01Y705786D02*
X1002018Y706053D01*
X1002351Y706253D01*
X1002818Y706320D01*
X1003151Y706253D01*
X1003551Y706053D01*
G01X1007218Y706320D02*
Y703653D01*
G01Y707386D02*
X1007085Y707453D01*
Y707586D01*
X1007218Y707653D01*
X1007351Y707586D01*
Y707453D01*
X1007218Y707386D01*
G01X1011818Y703653D02*
Y707653D01*
G01X1016418Y703653D02*
Y707653D01*
G01X1025218Y703653D02*
Y707053D01*
X1025351Y707386D01*
X1025618Y707586D01*
X1026018Y707653D01*
X1026418Y707520D01*
X1026618Y707186D01*
G01X1025818Y706053D02*
X1024485D01*
G01X1029218Y705453D02*
X1031351D01*
X1031151Y705920D01*
X1030818Y706186D01*
X1030351Y706320D01*
X1029885Y706253D01*
X1029485Y706053D01*
X1029218Y705586D01*
X1029085Y705186D01*
Y704786D01*
X1029218Y704386D01*
X1029551Y703986D01*
X1029951Y703720D01*
X1030418Y703653D01*
X1030885Y703786D01*
X1031351Y704186D01*
G01X1036018Y703653D02*
Y706320D01*
G01Y705853D02*
X1035751Y706120D01*
X1035351Y706253D01*
X1034885Y706320D01*
X1034418Y706186D01*
X1034018Y705920D01*
X1033751Y705520D01*
X1033618Y704986D01*
X1033751Y704453D01*
X1034018Y704053D01*
X1034418Y703786D01*
X1034885Y703653D01*
X1035351Y703720D01*
X1035751Y703920D01*
X1036018Y704186D01*
G01X1039418Y707653D02*
Y703653D01*
G01X1038485Y706320D02*
X1040351D01*
G01X1042885D02*
Y704453D01*
X1043151Y703986D01*
X1043551Y703720D01*
X1044018Y703653D01*
X1044485Y703720D01*
X1044885Y703986D01*
X1045151Y704453D01*
G01Y703653D02*
Y706320D01*
G01X1047685Y703653D02*
Y706320D01*
G01Y705786D02*
X1048018Y706053D01*
X1048351Y706253D01*
X1048818Y706320D01*
X1049151Y706253D01*
X1049551Y706053D01*
G01X1052218Y705453D02*
X1054351D01*
X1054151Y705920D01*
X1053818Y706186D01*
X1053351Y706320D01*
X1052885Y706253D01*
X1052485Y706053D01*
X1052218Y705586D01*
X1052085Y705186D01*
Y704786D01*
X1052218Y704386D01*
X1052551Y703986D01*
X1052951Y703720D01*
X1053418Y703653D01*
X1053885Y703786D01*
X1054351Y704186D01*
G01X971398Y718788D02*
G03X978323Y705657I37662J11471D01*
G01X971398Y718788D02*
G03X978323Y705657I37662J11470D01*
G01X1003014Y930000D02*
Y934000D01*
X1000547Y931133D01*
X1003881D01*
G01X1005347Y930800D02*
X1005747Y930333D01*
X1006281Y930067D01*
X1006881Y930000D01*
X1007414Y930067D01*
X1007947Y930400D01*
X1008281Y930800D01*
X1008347Y931200D01*
X1008214Y931667D01*
X1007747Y932000D01*
X1007281Y932133D01*
X1006681D01*
G01X1007281D02*
X1007681Y932333D01*
X1008014Y932667D01*
X1008147Y933067D01*
X1008014Y933467D01*
X1007681Y933800D01*
X1007081Y934000D01*
X1006481Y933933D01*
X1005881Y933667D01*
G01X1009947Y930800D02*
X1010347Y930333D01*
X1010881Y930067D01*
X1011481Y930000D01*
X1012014Y930067D01*
X1012547Y930400D01*
X1012881Y930800D01*
X1012947Y931200D01*
X1012814Y931667D01*
X1012347Y932000D01*
X1011881Y932133D01*
X1011281D01*
G01X1011881D02*
X1012281Y932333D01*
X1012614Y932667D01*
X1012747Y933067D01*
X1012614Y933467D01*
X1012281Y933800D01*
X1011681Y934000D01*
X1011081Y933933D01*
X1010481Y933667D01*
G01X1016014Y929867D02*
X1015881Y929933D01*
Y930067D01*
X1016014Y930133D01*
X1016147Y930067D01*
Y929933D01*
X1016014Y929867D01*
G01X1020614Y934000D02*
X1020081Y933867D01*
X1019681Y933533D01*
X1019414Y933133D01*
X1019214Y932600D01*
X1019147Y932000D01*
X1019214Y931400D01*
X1019414Y930867D01*
X1019681Y930467D01*
X1020081Y930133D01*
X1020614Y930000D01*
X1021147Y930133D01*
X1021547Y930467D01*
X1021814Y930867D01*
X1022014Y931400D01*
X1022081Y932000D01*
X1022014Y932600D01*
X1021814Y933133D01*
X1021547Y933533D01*
X1021147Y933867D01*
X1020614Y934000D01*
G01X1025214Y930000D02*
X1025681Y930067D01*
X1026214Y930267D01*
X1026547Y930600D01*
X1026681Y931067D01*
X1026547Y931533D01*
X1026147Y931933D01*
X1025547Y932133D01*
X1024881D01*
X1024481Y932267D01*
X1024147Y932600D01*
X1024014Y933067D01*
X1024214Y933533D01*
X1024681Y933867D01*
X1025214Y934000D01*
X1025747Y933867D01*
X1026214Y933533D01*
X1026414Y933067D01*
X1026281Y932600D01*
X1025947Y932267D01*
X1025547Y932133D01*
X1024881D01*
X1024281Y931933D01*
X1023881Y931533D01*
X1023747Y931067D01*
X1023881Y930600D01*
X1024214Y930267D01*
X1024747Y930067D01*
X1025214Y930000D01*
G01X1003106Y1014324D02*
X1003506Y1014724D01*
X1003973Y1014924D01*
X1004506Y1014991D01*
X1005173Y1014858D01*
X1005640Y1014524D01*
X1005773Y1014124D01*
X1005706Y1013724D01*
X1005440Y1013391D01*
X1004106Y1012724D01*
X1003506Y1012258D01*
X1003106Y1011591D01*
X1002973Y1010991D01*
X1005773D01*
G01X1008973Y1014991D02*
X1008440Y1014858D01*
X1008040Y1014524D01*
X1007773Y1014124D01*
X1007573Y1013591D01*
X1007506Y1012991D01*
X1007573Y1012391D01*
X1007773Y1011858D01*
X1008040Y1011458D01*
X1008440Y1011124D01*
X1008973Y1010991D01*
X1009506Y1011124D01*
X1009906Y1011458D01*
X1010173Y1011858D01*
X1010373Y1012391D01*
X1010440Y1012991D01*
X1010373Y1013591D01*
X1010173Y1014124D01*
X1009906Y1014524D01*
X1009506Y1014858D01*
X1008973Y1014991D01*
G01X1013573Y1010991D02*
X1014040Y1011058D01*
X1014573Y1011258D01*
X1014906Y1011591D01*
X1015040Y1012058D01*
X1014906Y1012524D01*
X1014506Y1012924D01*
X1013906Y1013124D01*
X1013240D01*
X1012840Y1013258D01*
X1012506Y1013591D01*
X1012373Y1014058D01*
X1012573Y1014524D01*
X1013040Y1014858D01*
X1013573Y1014991D01*
X1014106Y1014858D01*
X1014573Y1014524D01*
X1014773Y1014058D01*
X1014640Y1013591D01*
X1014306Y1013258D01*
X1013906Y1013124D01*
X1013240D01*
X1012640Y1012924D01*
X1012240Y1012524D01*
X1012106Y1012058D01*
X1012240Y1011591D01*
X1012573Y1011258D01*
X1013106Y1011058D01*
X1013573Y1010991D01*
G01X1018173Y1010858D02*
X1018040Y1010924D01*
Y1011058D01*
X1018173Y1011124D01*
X1018306Y1011058D01*
Y1010924D01*
X1018173Y1010858D01*
G01X1021506Y1012658D02*
X1021973Y1013124D01*
X1022373Y1013391D01*
X1022906Y1013524D01*
X1023373Y1013391D01*
X1023706Y1013124D01*
X1023973Y1012724D01*
X1024040Y1012258D01*
X1023973Y1011858D01*
X1023706Y1011458D01*
X1023306Y1011124D01*
X1022840Y1010991D01*
X1022306Y1011124D01*
X1021840Y1011524D01*
X1021573Y1012124D01*
X1021506Y1012791D01*
X1021640Y1013658D01*
X1021840Y1014124D01*
X1022173Y1014591D01*
X1022640Y1014924D01*
X1023106Y1014991D01*
X1023573Y1014858D01*
X1023906Y1014524D01*
G01X1026106Y1012658D02*
X1026573Y1013124D01*
X1026973Y1013391D01*
X1027506Y1013524D01*
X1027973Y1013391D01*
X1028306Y1013124D01*
X1028573Y1012724D01*
X1028640Y1012258D01*
X1028573Y1011858D01*
X1028306Y1011458D01*
X1027906Y1011124D01*
X1027440Y1010991D01*
X1026906Y1011124D01*
X1026440Y1011524D01*
X1026173Y1012124D01*
X1026106Y1012791D01*
X1026240Y1013658D01*
X1026440Y1014124D01*
X1026773Y1014591D01*
X1027240Y1014924D01*
X1027706Y1014991D01*
X1028173Y1014858D01*
X1028506Y1014524D01*
G01X996551Y972157D02*
Y976157D01*
X997885D01*
X998418Y975957D01*
X998818Y975690D01*
X999151Y975290D01*
X999418Y974824D01*
X999485Y974157D01*
X999418Y973490D01*
X999151Y973024D01*
X998818Y972624D01*
X998418Y972357D01*
X997885Y972157D01*
X996551D01*
G01X1001685D02*
Y974824D01*
G01Y974290D02*
X1002018Y974557D01*
X1002351Y974757D01*
X1002818Y974824D01*
X1003151Y974757D01*
X1003551Y974557D01*
G01X1007218Y974824D02*
Y972157D01*
G01Y975890D02*
X1007085Y975957D01*
Y976090D01*
X1007218Y976157D01*
X1007351Y976090D01*
Y975957D01*
X1007218Y975890D01*
G01X1011818Y972157D02*
Y976157D01*
G01X1016418Y972157D02*
Y976157D01*
G01X1025218Y972157D02*
Y975557D01*
X1025351Y975890D01*
X1025618Y976090D01*
X1026018Y976157D01*
X1026418Y976024D01*
X1026618Y975690D01*
G01X1025818Y974557D02*
X1024485D01*
G01X1029218Y973957D02*
X1031351D01*
X1031151Y974424D01*
X1030818Y974690D01*
X1030351Y974824D01*
X1029885Y974757D01*
X1029485Y974557D01*
X1029218Y974090D01*
X1029085Y973690D01*
Y973290D01*
X1029218Y972890D01*
X1029551Y972490D01*
X1029951Y972224D01*
X1030418Y972157D01*
X1030885Y972290D01*
X1031351Y972690D01*
G01X1036018Y972157D02*
Y974824D01*
G01Y974357D02*
X1035751Y974624D01*
X1035351Y974757D01*
X1034885Y974824D01*
X1034418Y974690D01*
X1034018Y974424D01*
X1033751Y974024D01*
X1033618Y973490D01*
X1033751Y972957D01*
X1034018Y972557D01*
X1034418Y972290D01*
X1034885Y972157D01*
X1035351Y972224D01*
X1035751Y972424D01*
X1036018Y972690D01*
G01X1039418Y976157D02*
Y972157D01*
G01X1038485Y974824D02*
X1040351D01*
G01X1042885D02*
Y972957D01*
X1043151Y972490D01*
X1043551Y972224D01*
X1044018Y972157D01*
X1044485Y972224D01*
X1044885Y972490D01*
X1045151Y972957D01*
G01Y972157D02*
Y974824D01*
G01X1047685Y972157D02*
Y974824D01*
G01Y974290D02*
X1048018Y974557D01*
X1048351Y974757D01*
X1048818Y974824D01*
X1049151Y974757D01*
X1049551Y974557D01*
G01X1052218Y973957D02*
X1054351D01*
X1054151Y974424D01*
X1053818Y974690D01*
X1053351Y974824D01*
X1052885Y974757D01*
X1052485Y974557D01*
X1052218Y974090D01*
X1052085Y973690D01*
Y973290D01*
X1052218Y972890D01*
X1052551Y972490D01*
X1052951Y972224D01*
X1053418Y972157D01*
X1053885Y972290D01*
X1054351Y972690D01*
G01X971398Y987292D02*
G03X978323Y974161I37662J11471D01*
G01X971398Y987292D02*
G03X978323Y974161I37662J11470D01*
G01X1059196Y1519685D02*
X996063D01*
G01X1059196D02*
X996063D01*
G01X984252Y1515748D02*
G03X980315Y1519685I-3937J0D01*
G01X984252Y1515748D02*
G03X980315Y1519685I-3937J0D01*
G01X996063D02*
G03X992126Y1515748I0J-3937D01*
G01X996063Y1519685D02*
G03X992126Y1515748I0J-3937D01*
G01X972441Y1503937D02*
G03Y1496063I0J-3937D01*
G01X984252Y1503937D02*
X972441D01*
G01X984252Y1515748D02*
Y1503937D01*
G01X972441D02*
G03Y1496063I0J-3937D01*
G01X988189D02*
G03X992126Y1500000I0J3937D01*
G01Y1515748D02*
Y1500000D01*
G01X984252Y1515748D02*
Y1503937D01*
G01D02*
X972441D01*
G01X988189Y1496063D02*
G03X992126Y1500000I0J3937D01*
G01Y1515748D02*
Y1500000D01*
G01X1133071Y189764D02*
G03Y181890I0J-3937D01*
G01D02*
X1216535D01*
G01X1133071D02*
X1216535D01*
G01X1133071Y189764D02*
G03Y181890I0J-3937D01*
G01X1102362D02*
G03Y189764I0J3937D01*
G01Y181890D02*
G03Y189764I0J3937D01*
G01X1062992Y181890D02*
X1102362D01*
G01X1062992D02*
X1102362D01*
G01X1059055Y244094D02*
G03X1055118Y248031I-3937J0D01*
G01X1059055Y244094D02*
G03X1055118Y248031I-3937J0D01*
G01X1059055Y244094D02*
Y193701D01*
G01Y244094D02*
Y193701D01*
G01X1062992Y189764D02*
X1220472D01*
G01X1059055Y193701D02*
G03X1062992Y189764I3937J0D01*
G01X1059055Y193701D02*
G03X1062992Y189764I3937J0D01*
G01D02*
X1220472D01*
G01X1105452Y372497D02*
X1105852Y372164D01*
X1106319Y371964D01*
X1106919Y371897D01*
X1107519Y372030D01*
X1107986Y372297D01*
X1108319Y372764D01*
X1108386Y373297D01*
X1108252Y373830D01*
X1107919Y374164D01*
X1107452Y374430D01*
X1106986Y374497D01*
X1106519Y374430D01*
X1105919Y374164D01*
X1106119Y375897D01*
X1107919D01*
G01X1110052Y372497D02*
X1110452Y372164D01*
X1110919Y371964D01*
X1111519Y371897D01*
X1112119Y372030D01*
X1112586Y372297D01*
X1112919Y372764D01*
X1112986Y373297D01*
X1112852Y373830D01*
X1112519Y374164D01*
X1112052Y374430D01*
X1111586Y374497D01*
X1111119Y374430D01*
X1110519Y374164D01*
X1110719Y375897D01*
X1112519D01*
G01X1115986Y371897D02*
X1116119Y372764D01*
X1116319Y373497D01*
X1116586Y374164D01*
X1116919Y374897D01*
X1117452Y375897D01*
X1114786D01*
G01X1120719Y371764D02*
X1120586Y371830D01*
Y371964D01*
X1120719Y372030D01*
X1120852Y371964D01*
Y371830D01*
X1120719Y371764D01*
G01X1125319Y375897D02*
X1124786Y375764D01*
X1124386Y375430D01*
X1124119Y375030D01*
X1123919Y374497D01*
X1123852Y373897D01*
X1123919Y373297D01*
X1124119Y372764D01*
X1124386Y372364D01*
X1124786Y372030D01*
X1125319Y371897D01*
X1125852Y372030D01*
X1126252Y372364D01*
X1126519Y372764D01*
X1126719Y373297D01*
X1126786Y373897D01*
X1126719Y374497D01*
X1126519Y375030D01*
X1126252Y375430D01*
X1125852Y375764D01*
X1125319Y375897D01*
G01X1128786Y372364D02*
X1129252Y372030D01*
X1129786Y371897D01*
X1130319Y372030D01*
X1130786Y372430D01*
X1131119Y373030D01*
X1131252Y373630D01*
Y374364D01*
X1131119Y374964D01*
X1130786Y375497D01*
X1130386Y375764D01*
X1129919Y375897D01*
X1129386Y375764D01*
X1128986Y375497D01*
X1128719Y375097D01*
X1128586Y374564D01*
X1128719Y374097D01*
X1129052Y373630D01*
X1129452Y373364D01*
X1129919Y373297D01*
X1130452Y373430D01*
X1130852Y373764D01*
X1131252Y374364D01*
G01X1122791Y383043D02*
X1123191Y383443D01*
X1123658Y383643D01*
X1124191Y383710D01*
X1124858Y383577D01*
X1125325Y383243D01*
X1125458Y382843D01*
X1125391Y382443D01*
X1125125Y382110D01*
X1123791Y381443D01*
X1123191Y380977D01*
X1122791Y380310D01*
X1122658Y379710D01*
X1125458D01*
G01X1127191Y380510D02*
X1127591Y380043D01*
X1128125Y379777D01*
X1128725Y379710D01*
X1129258Y379777D01*
X1129791Y380110D01*
X1130125Y380510D01*
X1130191Y380910D01*
X1130058Y381377D01*
X1129591Y381710D01*
X1129125Y381843D01*
X1128525D01*
G01X1129125D02*
X1129525Y382043D01*
X1129858Y382377D01*
X1129991Y382777D01*
X1129858Y383177D01*
X1129525Y383510D01*
X1128925Y383710D01*
X1128325Y383643D01*
X1127725Y383377D01*
G01X1131991Y381377D02*
X1132458Y381843D01*
X1132858Y382110D01*
X1133391Y382243D01*
X1133858Y382110D01*
X1134191Y381843D01*
X1134458Y381443D01*
X1134525Y380977D01*
X1134458Y380577D01*
X1134191Y380177D01*
X1133791Y379843D01*
X1133325Y379710D01*
X1132791Y379843D01*
X1132325Y380243D01*
X1132058Y380843D01*
X1131991Y381510D01*
X1132125Y382377D01*
X1132325Y382843D01*
X1132658Y383310D01*
X1133125Y383643D01*
X1133591Y383710D01*
X1134058Y383577D01*
X1134391Y383243D01*
G01X1137858Y379577D02*
X1137725Y379643D01*
Y379777D01*
X1137858Y379843D01*
X1137991Y379777D01*
Y379643D01*
X1137858Y379577D01*
G01X1141191Y383043D02*
X1141591Y383443D01*
X1142058Y383643D01*
X1142591Y383710D01*
X1143258Y383577D01*
X1143725Y383243D01*
X1143858Y382843D01*
X1143791Y382443D01*
X1143525Y382110D01*
X1142191Y381443D01*
X1141591Y380977D01*
X1141191Y380310D01*
X1141058Y379710D01*
X1143858D01*
G01X1145791Y383043D02*
X1146191Y383443D01*
X1146658Y383643D01*
X1147191Y383710D01*
X1147858Y383577D01*
X1148325Y383243D01*
X1148458Y382843D01*
X1148391Y382443D01*
X1148125Y382110D01*
X1146791Y381443D01*
X1146191Y380977D01*
X1145791Y380310D01*
X1145658Y379710D01*
X1148458D01*
G01X1075865Y652096D02*
X1079865D01*
Y650496D01*
X1079665Y649963D01*
X1079198Y649563D01*
X1078665Y649430D01*
X1078132Y649563D01*
X1077732Y649896D01*
X1077532Y650496D01*
Y652096D01*
G01X1075865Y647096D02*
X1078532D01*
G01X1077998D02*
X1078265Y646763D01*
X1078465Y646430D01*
X1078532Y645963D01*
X1078465Y645630D01*
X1078265Y645230D01*
G01X1077665Y642563D02*
Y640430D01*
X1078132Y640630D01*
X1078398Y640963D01*
X1078532Y641430D01*
X1078465Y641896D01*
X1078265Y642296D01*
X1077798Y642563D01*
X1077398Y642696D01*
X1076998D01*
X1076598Y642563D01*
X1076198Y642230D01*
X1075932Y641830D01*
X1075865Y641363D01*
X1075998Y640896D01*
X1076398Y640430D01*
G01X1076332Y637963D02*
X1076065Y637630D01*
X1075865Y637163D01*
Y636763D01*
X1075998Y636363D01*
X1076198Y636096D01*
X1076465Y635963D01*
X1076865Y636030D01*
X1077065Y636296D01*
X1077465Y637496D01*
X1077932Y637763D01*
X1078265Y637630D01*
X1078465Y637363D01*
X1078532Y636963D01*
X1078465Y636563D01*
X1078265Y636163D01*
G01X1076332Y633363D02*
X1076065Y633030D01*
X1075865Y632563D01*
Y632163D01*
X1075998Y631763D01*
X1076198Y631496D01*
X1076465Y631363D01*
X1076865Y631430D01*
X1077065Y631696D01*
X1077465Y632896D01*
X1077932Y633163D01*
X1078265Y633030D01*
X1078465Y632763D01*
X1078532Y632363D01*
X1078465Y631963D01*
X1078265Y631563D01*
G01X1077198Y628630D02*
Y626896D01*
G01X1075865Y623563D02*
X1079265D01*
X1079598Y623430D01*
X1079798Y623163D01*
X1079865Y622763D01*
X1079732Y622363D01*
X1079398Y622163D01*
G01X1078265Y622963D02*
Y624296D01*
G01X1078532Y618563D02*
X1075865D01*
G01X1079598D02*
X1079665Y618696D01*
X1079798D01*
X1079865Y618563D01*
X1079798Y618430D01*
X1079665D01*
X1079598Y618563D01*
G01X1079865Y613963D02*
X1075865D01*
G01X1078532Y614896D02*
Y613030D01*
G01X1075865Y606096D02*
X1079865D01*
Y604496D01*
X1079665Y603963D01*
X1079198Y603563D01*
X1078665Y603430D01*
X1078132Y603563D01*
X1077732Y603896D01*
X1077532Y604496D01*
Y606096D01*
G01X1079865Y600163D02*
X1075865D01*
G01X1079865Y601696D02*
Y598630D01*
G01X1075865Y596963D02*
X1079865D01*
G01Y594163D02*
X1075865D01*
G01X1077865D02*
Y596963D01*
G01X1075865Y587496D02*
X1079865D01*
G01X1078532Y585363D02*
X1076998Y587496D01*
G01X1077598Y586630D02*
X1075865Y585230D01*
G01X1077665Y582763D02*
Y580630D01*
X1078132Y580830D01*
X1078398Y581163D01*
X1078532Y581630D01*
X1078465Y582096D01*
X1078265Y582496D01*
X1077798Y582763D01*
X1077398Y582896D01*
X1076998D01*
X1076598Y582763D01*
X1076198Y582430D01*
X1075932Y582030D01*
X1075865Y581563D01*
X1075998Y581096D01*
X1076398Y580630D01*
G01X1077665Y578163D02*
Y576030D01*
X1078132Y576230D01*
X1078398Y576563D01*
X1078532Y577030D01*
X1078465Y577496D01*
X1078265Y577896D01*
X1077798Y578163D01*
X1077398Y578296D01*
X1076998D01*
X1076598Y578163D01*
X1076198Y577830D01*
X1075932Y577430D01*
X1075865Y576963D01*
X1075998Y576496D01*
X1076398Y576030D01*
G01X1074532Y573763D02*
X1078532D01*
G01X1077932D02*
X1078265Y573430D01*
X1078465Y573096D01*
X1078532Y572563D01*
X1078465Y572096D01*
X1078132Y571630D01*
X1077665Y571430D01*
X1077198Y571363D01*
X1076732Y571430D01*
X1076265Y571630D01*
X1075998Y572030D01*
X1075865Y572563D01*
X1075932Y573030D01*
X1076132Y573496D01*
X1076398Y573763D01*
G01X1075865Y564496D02*
X1079865D01*
G01X1077932D02*
X1078265Y564163D01*
X1078465Y563830D01*
X1078532Y563296D01*
X1078465Y562896D01*
X1078198Y562430D01*
X1077798Y562230D01*
X1075865D01*
G01Y558763D02*
X1075932Y559163D01*
X1076198Y559563D01*
X1076665Y559830D01*
X1077198Y559963D01*
X1077732Y559830D01*
X1078198Y559563D01*
X1078465Y559163D01*
X1078532Y558763D01*
X1078465Y558363D01*
X1078198Y557963D01*
X1077732Y557696D01*
X1077198Y557630D01*
X1076665Y557696D01*
X1076198Y557963D01*
X1075932Y558363D01*
X1075865Y558763D01*
G01Y554163D02*
X1079865D01*
G01X1077665Y550563D02*
Y548430D01*
X1078132Y548630D01*
X1078398Y548963D01*
X1078532Y549430D01*
X1078465Y549896D01*
X1078265Y550296D01*
X1077798Y550563D01*
X1077398Y550696D01*
X1076998D01*
X1076598Y550563D01*
X1076198Y550230D01*
X1075932Y549830D01*
X1075865Y549363D01*
X1075998Y548896D01*
X1076398Y548430D01*
G01X1076332Y541363D02*
X1076065Y541030D01*
X1075865Y540563D01*
Y540163D01*
X1075998Y539763D01*
X1076198Y539496D01*
X1076465Y539363D01*
X1076865Y539430D01*
X1077065Y539696D01*
X1077465Y540896D01*
X1077932Y541163D01*
X1078265Y541030D01*
X1078465Y540763D01*
X1078532Y540363D01*
X1078465Y539963D01*
X1078265Y539563D01*
G01X1078532Y535763D02*
X1075865D01*
G01X1079598D02*
X1079665Y535896D01*
X1079798D01*
X1079865Y535763D01*
X1079798Y535630D01*
X1079665D01*
X1079598Y535763D01*
G01X1078532Y532163D02*
Y530163D01*
X1075865Y532163D01*
Y530163D01*
G01X1077665Y527563D02*
Y525430D01*
X1078132Y525630D01*
X1078398Y525963D01*
X1078532Y526430D01*
X1078465Y526896D01*
X1078265Y527296D01*
X1077798Y527563D01*
X1077398Y527696D01*
X1076998D01*
X1076598Y527563D01*
X1076198Y527230D01*
X1075932Y526830D01*
X1075865Y526363D01*
X1075998Y525896D01*
X1076398Y525430D01*
G01X1079865Y517363D02*
X1075865D01*
G01X1078532Y518296D02*
Y516430D01*
G01X1075865Y512763D02*
X1075932Y513163D01*
X1076198Y513563D01*
X1076665Y513830D01*
X1077198Y513963D01*
X1077732Y513830D01*
X1078198Y513563D01*
X1078465Y513163D01*
X1078532Y512763D01*
X1078465Y512363D01*
X1078198Y511963D01*
X1077732Y511696D01*
X1077198Y511630D01*
X1076665Y511696D01*
X1076198Y511963D01*
X1075932Y512363D01*
X1075865Y512763D01*
G01Y508163D02*
X1079865D01*
G01X1077665Y504563D02*
Y502430D01*
X1078132Y502630D01*
X1078398Y502963D01*
X1078532Y503430D01*
X1078465Y503896D01*
X1078265Y504296D01*
X1077798Y504563D01*
X1077398Y504696D01*
X1076998D01*
X1076598Y504563D01*
X1076198Y504230D01*
X1075932Y503830D01*
X1075865Y503363D01*
X1075998Y502896D01*
X1076398Y502430D01*
G01X1075865Y499896D02*
X1078532D01*
G01X1077998D02*
X1078265Y499563D01*
X1078465Y499230D01*
X1078532Y498763D01*
X1078465Y498430D01*
X1078265Y498030D01*
G01X1075865Y493163D02*
X1078532D01*
G01X1078065D02*
X1078332Y493430D01*
X1078465Y493830D01*
X1078532Y494296D01*
X1078398Y494763D01*
X1078132Y495163D01*
X1077732Y495430D01*
X1077198Y495563D01*
X1076665Y495430D01*
X1076265Y495163D01*
X1075998Y494763D01*
X1075865Y494296D01*
X1075932Y493830D01*
X1076132Y493430D01*
X1076398Y493163D01*
G01X1075865Y490896D02*
X1078532D01*
G01X1077865D02*
X1078198Y490630D01*
X1078465Y490230D01*
X1078532Y489696D01*
X1078465Y489230D01*
X1078198Y488830D01*
X1077732Y488630D01*
X1075865D01*
G01X1078198Y484096D02*
X1078465Y484563D01*
X1078532Y484963D01*
X1078398Y485496D01*
X1078132Y485896D01*
X1077665Y486163D01*
X1077198Y486230D01*
X1076732Y486163D01*
X1076332Y485896D01*
X1075998Y485496D01*
X1075865Y484963D01*
X1075998Y484496D01*
X1076265Y484096D01*
G01X1077665Y481563D02*
Y479430D01*
X1078132Y479630D01*
X1078398Y479963D01*
X1078532Y480430D01*
X1078465Y480896D01*
X1078265Y481296D01*
X1077798Y481563D01*
X1077398Y481696D01*
X1076998D01*
X1076598Y481563D01*
X1076198Y481230D01*
X1075932Y480830D01*
X1075865Y480363D01*
X1075998Y479896D01*
X1076398Y479430D01*
G01X1077198Y472096D02*
Y470496D01*
G01X1078065Y471363D02*
X1076332D01*
G01X1075732Y467963D02*
X1079865Y465563D01*
G01X1077198Y463030D02*
Y461296D01*
G01X1079198Y458830D02*
X1079598Y458430D01*
X1079798Y457963D01*
X1079865Y457430D01*
X1079732Y456763D01*
X1079398Y456296D01*
X1078998Y456163D01*
X1078598Y456230D01*
X1078265Y456496D01*
X1077598Y457830D01*
X1077132Y458430D01*
X1076465Y458830D01*
X1075865Y458963D01*
Y456163D01*
G01Y450363D02*
X1078532D01*
G01X1077798D02*
X1078132Y450163D01*
X1078398Y449830D01*
X1078532Y449363D01*
X1078398Y448896D01*
X1078132Y448563D01*
X1077798Y448363D01*
X1075865D01*
G01X1077798D02*
X1078132Y448163D01*
X1078398Y447830D01*
X1078532Y447363D01*
X1078398Y446896D01*
X1078132Y446563D01*
X1077732Y446363D01*
X1075865D01*
G01X1078532Y443763D02*
X1075865D01*
G01X1079598D02*
X1079665Y443896D01*
X1079798D01*
X1079865Y443763D01*
X1079798Y443630D01*
X1079665D01*
X1079598Y443763D01*
G01X1075865Y439163D02*
X1079865D01*
G01X1076332Y435563D02*
X1076065Y435230D01*
X1075865Y434763D01*
Y434363D01*
X1075998Y433963D01*
X1076198Y433696D01*
X1076465Y433563D01*
X1076865Y433630D01*
X1077065Y433896D01*
X1077465Y435096D01*
X1077932Y435363D01*
X1078265Y435230D01*
X1078465Y434963D01*
X1078532Y434563D01*
X1078465Y434163D01*
X1078265Y433763D01*
G01X1078589Y545663D02*
X1088289D01*
X1083289Y540663D01*
Y550663D01*
X1088289Y545663D01*
G01X1136109Y572163D02*
Y517557D01*
X1088589D01*
Y572163D01*
X1136109D01*
G01X1076715Y937575D02*
X1080715D01*
Y935975D01*
X1080515Y935442D01*
X1080048Y935042D01*
X1079515Y934909D01*
X1078982Y935042D01*
X1078582Y935375D01*
X1078382Y935975D01*
Y937575D01*
G01X1076715Y932575D02*
X1079382D01*
G01X1078848D02*
X1079115Y932242D01*
X1079315Y931909D01*
X1079382Y931442D01*
X1079315Y931109D01*
X1079115Y930709D01*
G01X1078515Y928042D02*
Y925909D01*
X1078982Y926109D01*
X1079248Y926442D01*
X1079382Y926909D01*
X1079315Y927375D01*
X1079115Y927775D01*
X1078648Y928042D01*
X1078248Y928175D01*
X1077848D01*
X1077448Y928042D01*
X1077048Y927709D01*
X1076782Y927309D01*
X1076715Y926842D01*
X1076848Y926375D01*
X1077248Y925909D01*
G01X1077182Y923442D02*
X1076915Y923109D01*
X1076715Y922642D01*
Y922242D01*
X1076848Y921842D01*
X1077048Y921575D01*
X1077315Y921442D01*
X1077715Y921509D01*
X1077915Y921775D01*
X1078315Y922975D01*
X1078782Y923242D01*
X1079115Y923109D01*
X1079315Y922842D01*
X1079382Y922442D01*
X1079315Y922042D01*
X1079115Y921642D01*
G01X1077182Y918842D02*
X1076915Y918509D01*
X1076715Y918042D01*
Y917642D01*
X1076848Y917242D01*
X1077048Y916975D01*
X1077315Y916842D01*
X1077715Y916909D01*
X1077915Y917175D01*
X1078315Y918375D01*
X1078782Y918642D01*
X1079115Y918509D01*
X1079315Y918242D01*
X1079382Y917842D01*
X1079315Y917442D01*
X1079115Y917042D01*
G01X1078048Y914109D02*
Y912375D01*
G01X1076715Y909042D02*
X1080115D01*
X1080448Y908909D01*
X1080648Y908642D01*
X1080715Y908242D01*
X1080582Y907842D01*
X1080248Y907642D01*
G01X1079115Y908442D02*
Y909775D01*
G01X1079382Y904042D02*
X1076715D01*
G01X1080448D02*
X1080515Y904175D01*
X1080648D01*
X1080715Y904042D01*
X1080648Y903909D01*
X1080515D01*
X1080448Y904042D01*
G01X1080715Y899442D02*
X1076715D01*
G01X1079382Y900375D02*
Y898509D01*
G01X1076715Y891575D02*
X1080715D01*
Y889975D01*
X1080515Y889442D01*
X1080048Y889042D01*
X1079515Y888909D01*
X1078982Y889042D01*
X1078582Y889375D01*
X1078382Y889975D01*
Y891575D01*
G01X1080715Y885642D02*
X1076715D01*
G01X1080715Y887175D02*
Y884109D01*
G01X1076715Y882442D02*
X1080715D01*
G01Y879642D02*
X1076715D01*
G01X1078715D02*
Y882442D01*
G01X1076715Y872975D02*
X1080715D01*
G01X1079382Y870842D02*
X1077848Y872975D01*
G01X1078448Y872109D02*
X1076715Y870709D01*
G01X1078515Y868242D02*
Y866109D01*
X1078982Y866309D01*
X1079248Y866642D01*
X1079382Y867109D01*
X1079315Y867575D01*
X1079115Y867975D01*
X1078648Y868242D01*
X1078248Y868375D01*
X1077848D01*
X1077448Y868242D01*
X1077048Y867909D01*
X1076782Y867509D01*
X1076715Y867042D01*
X1076848Y866575D01*
X1077248Y866109D01*
G01X1078515Y863642D02*
Y861509D01*
X1078982Y861709D01*
X1079248Y862042D01*
X1079382Y862509D01*
X1079315Y862975D01*
X1079115Y863375D01*
X1078648Y863642D01*
X1078248Y863775D01*
X1077848D01*
X1077448Y863642D01*
X1077048Y863309D01*
X1076782Y862909D01*
X1076715Y862442D01*
X1076848Y861975D01*
X1077248Y861509D01*
G01X1075382Y859242D02*
X1079382D01*
G01X1078782D02*
X1079115Y858909D01*
X1079315Y858575D01*
X1079382Y858042D01*
X1079315Y857575D01*
X1078982Y857109D01*
X1078515Y856909D01*
X1078048Y856842D01*
X1077582Y856909D01*
X1077115Y857109D01*
X1076848Y857509D01*
X1076715Y858042D01*
X1076782Y858509D01*
X1076982Y858975D01*
X1077248Y859242D01*
G01X1076715Y849975D02*
X1080715D01*
G01X1078782D02*
X1079115Y849642D01*
X1079315Y849309D01*
X1079382Y848775D01*
X1079315Y848375D01*
X1079048Y847909D01*
X1078648Y847709D01*
X1076715D01*
G01Y844242D02*
X1076782Y844642D01*
X1077048Y845042D01*
X1077515Y845309D01*
X1078048Y845442D01*
X1078582Y845309D01*
X1079048Y845042D01*
X1079315Y844642D01*
X1079382Y844242D01*
X1079315Y843842D01*
X1079048Y843442D01*
X1078582Y843175D01*
X1078048Y843109D01*
X1077515Y843175D01*
X1077048Y843442D01*
X1076782Y843842D01*
X1076715Y844242D01*
G01Y839642D02*
X1080715D01*
G01X1078515Y836042D02*
Y833909D01*
X1078982Y834109D01*
X1079248Y834442D01*
X1079382Y834909D01*
X1079315Y835375D01*
X1079115Y835775D01*
X1078648Y836042D01*
X1078248Y836175D01*
X1077848D01*
X1077448Y836042D01*
X1077048Y835709D01*
X1076782Y835309D01*
X1076715Y834842D01*
X1076848Y834375D01*
X1077248Y833909D01*
G01X1077182Y826842D02*
X1076915Y826509D01*
X1076715Y826042D01*
Y825642D01*
X1076848Y825242D01*
X1077048Y824975D01*
X1077315Y824842D01*
X1077715Y824909D01*
X1077915Y825175D01*
X1078315Y826375D01*
X1078782Y826642D01*
X1079115Y826509D01*
X1079315Y826242D01*
X1079382Y825842D01*
X1079315Y825442D01*
X1079115Y825042D01*
G01X1079382Y821242D02*
X1076715D01*
G01X1080448D02*
X1080515Y821375D01*
X1080648D01*
X1080715Y821242D01*
X1080648Y821109D01*
X1080515D01*
X1080448Y821242D01*
G01X1079382Y817642D02*
Y815642D01*
X1076715Y817642D01*
Y815642D01*
G01X1078515Y813042D02*
Y810909D01*
X1078982Y811109D01*
X1079248Y811442D01*
X1079382Y811909D01*
X1079315Y812375D01*
X1079115Y812775D01*
X1078648Y813042D01*
X1078248Y813175D01*
X1077848D01*
X1077448Y813042D01*
X1077048Y812709D01*
X1076782Y812309D01*
X1076715Y811842D01*
X1076848Y811375D01*
X1077248Y810909D01*
G01X1080715Y802842D02*
X1076715D01*
G01X1079382Y803775D02*
Y801909D01*
G01X1076715Y798242D02*
X1076782Y798642D01*
X1077048Y799042D01*
X1077515Y799309D01*
X1078048Y799442D01*
X1078582Y799309D01*
X1079048Y799042D01*
X1079315Y798642D01*
X1079382Y798242D01*
X1079315Y797842D01*
X1079048Y797442D01*
X1078582Y797175D01*
X1078048Y797109D01*
X1077515Y797175D01*
X1077048Y797442D01*
X1076782Y797842D01*
X1076715Y798242D01*
G01Y793642D02*
X1080715D01*
G01X1078515Y790042D02*
Y787909D01*
X1078982Y788109D01*
X1079248Y788442D01*
X1079382Y788909D01*
X1079315Y789375D01*
X1079115Y789775D01*
X1078648Y790042D01*
X1078248Y790175D01*
X1077848D01*
X1077448Y790042D01*
X1077048Y789709D01*
X1076782Y789309D01*
X1076715Y788842D01*
X1076848Y788375D01*
X1077248Y787909D01*
G01X1076715Y785375D02*
X1079382D01*
G01X1078848D02*
X1079115Y785042D01*
X1079315Y784709D01*
X1079382Y784242D01*
X1079315Y783909D01*
X1079115Y783509D01*
G01X1076715Y778642D02*
X1079382D01*
G01X1078915D02*
X1079182Y778909D01*
X1079315Y779309D01*
X1079382Y779775D01*
X1079248Y780242D01*
X1078982Y780642D01*
X1078582Y780909D01*
X1078048Y781042D01*
X1077515Y780909D01*
X1077115Y780642D01*
X1076848Y780242D01*
X1076715Y779775D01*
X1076782Y779309D01*
X1076982Y778909D01*
X1077248Y778642D01*
G01X1076715Y776375D02*
X1079382D01*
G01X1078715D02*
X1079048Y776109D01*
X1079315Y775709D01*
X1079382Y775175D01*
X1079315Y774709D01*
X1079048Y774309D01*
X1078582Y774109D01*
X1076715D01*
G01X1079048Y769575D02*
X1079315Y770042D01*
X1079382Y770442D01*
X1079248Y770975D01*
X1078982Y771375D01*
X1078515Y771642D01*
X1078048Y771709D01*
X1077582Y771642D01*
X1077182Y771375D01*
X1076848Y770975D01*
X1076715Y770442D01*
X1076848Y769975D01*
X1077115Y769575D01*
G01X1078515Y767042D02*
Y764909D01*
X1078982Y765109D01*
X1079248Y765442D01*
X1079382Y765909D01*
X1079315Y766375D01*
X1079115Y766775D01*
X1078648Y767042D01*
X1078248Y767175D01*
X1077848D01*
X1077448Y767042D01*
X1077048Y766709D01*
X1076782Y766309D01*
X1076715Y765842D01*
X1076848Y765375D01*
X1077248Y764909D01*
G01X1078048Y757575D02*
Y755975D01*
G01X1078915Y756842D02*
X1077182D01*
G01X1076582Y753442D02*
X1080715Y751042D01*
G01X1078048Y748509D02*
Y746775D01*
G01X1080048Y744309D02*
X1080448Y743909D01*
X1080648Y743442D01*
X1080715Y742909D01*
X1080582Y742242D01*
X1080248Y741775D01*
X1079848Y741642D01*
X1079448Y741709D01*
X1079115Y741975D01*
X1078448Y743309D01*
X1077982Y743909D01*
X1077315Y744309D01*
X1076715Y744442D01*
Y741642D01*
G01Y735842D02*
X1079382D01*
G01X1078648D02*
X1078982Y735642D01*
X1079248Y735309D01*
X1079382Y734842D01*
X1079248Y734375D01*
X1078982Y734042D01*
X1078648Y733842D01*
X1076715D01*
G01X1078648D02*
X1078982Y733642D01*
X1079248Y733309D01*
X1079382Y732842D01*
X1079248Y732375D01*
X1078982Y732042D01*
X1078582Y731842D01*
X1076715D01*
G01X1079382Y729242D02*
X1076715D01*
G01X1080448D02*
X1080515Y729375D01*
X1080648D01*
X1080715Y729242D01*
X1080648Y729109D01*
X1080515D01*
X1080448Y729242D01*
G01X1076715Y724642D02*
X1080715D01*
G01X1077182Y721042D02*
X1076915Y720709D01*
X1076715Y720242D01*
Y719842D01*
X1076848Y719442D01*
X1077048Y719175D01*
X1077315Y719042D01*
X1077715Y719109D01*
X1077915Y719375D01*
X1078315Y720575D01*
X1078782Y720842D01*
X1079115Y720709D01*
X1079315Y720442D01*
X1079382Y720042D01*
X1079315Y719642D01*
X1079115Y719242D01*
G01X1136109Y942242D02*
Y689211D01*
X1088589D01*
Y942242D01*
X1136109D01*
G01X1078748Y807890D02*
X1088448D01*
X1083448Y802890D01*
Y812890D01*
X1088448Y807890D01*
G01X1086326Y1233971D02*
X1090326D01*
Y1232371D01*
X1090126Y1231838D01*
X1089659Y1231438D01*
X1089126Y1231305D01*
X1088593Y1231438D01*
X1088193Y1231771D01*
X1087993Y1232371D01*
Y1233971D01*
G01X1086326Y1228971D02*
X1088993D01*
G01X1088459D02*
X1088726Y1228638D01*
X1088926Y1228305D01*
X1088993Y1227838D01*
X1088926Y1227505D01*
X1088726Y1227105D01*
G01X1088126Y1224438D02*
Y1222305D01*
X1088593Y1222505D01*
X1088859Y1222838D01*
X1088993Y1223305D01*
X1088926Y1223771D01*
X1088726Y1224171D01*
X1088259Y1224438D01*
X1087859Y1224571D01*
X1087459D01*
X1087059Y1224438D01*
X1086659Y1224105D01*
X1086393Y1223705D01*
X1086326Y1223238D01*
X1086459Y1222771D01*
X1086859Y1222305D01*
G01X1086793Y1219838D02*
X1086526Y1219505D01*
X1086326Y1219038D01*
Y1218638D01*
X1086459Y1218238D01*
X1086659Y1217971D01*
X1086926Y1217838D01*
X1087326Y1217905D01*
X1087526Y1218171D01*
X1087926Y1219371D01*
X1088393Y1219638D01*
X1088726Y1219505D01*
X1088926Y1219238D01*
X1088993Y1218838D01*
X1088926Y1218438D01*
X1088726Y1218038D01*
G01X1086793Y1215238D02*
X1086526Y1214905D01*
X1086326Y1214438D01*
Y1214038D01*
X1086459Y1213638D01*
X1086659Y1213371D01*
X1086926Y1213238D01*
X1087326Y1213305D01*
X1087526Y1213571D01*
X1087926Y1214771D01*
X1088393Y1215038D01*
X1088726Y1214905D01*
X1088926Y1214638D01*
X1088993Y1214238D01*
X1088926Y1213838D01*
X1088726Y1213438D01*
G01X1087659Y1210505D02*
Y1208771D01*
G01X1086326Y1205438D02*
X1089726D01*
X1090059Y1205305D01*
X1090259Y1205038D01*
X1090326Y1204638D01*
X1090193Y1204238D01*
X1089859Y1204038D01*
G01X1088726Y1204838D02*
Y1206171D01*
G01X1088993Y1200438D02*
X1086326D01*
G01X1090059D02*
X1090126Y1200571D01*
X1090259D01*
X1090326Y1200438D01*
X1090259Y1200305D01*
X1090126D01*
X1090059Y1200438D01*
G01X1090326Y1195838D02*
X1086326D01*
G01X1088993Y1196771D02*
Y1194905D01*
G01X1086326Y1187971D02*
X1090326D01*
Y1186371D01*
X1090126Y1185838D01*
X1089659Y1185438D01*
X1089126Y1185305D01*
X1088593Y1185438D01*
X1088193Y1185771D01*
X1087993Y1186371D01*
Y1187971D01*
G01X1090326Y1182038D02*
X1086326D01*
G01X1090326Y1183571D02*
Y1180505D01*
G01X1086326Y1178838D02*
X1090326D01*
G01Y1176038D02*
X1086326D01*
G01X1088326D02*
Y1178838D01*
G01X1086326Y1169371D02*
X1090326D01*
G01X1088993Y1167238D02*
X1087459Y1169371D01*
G01X1088059Y1168505D02*
X1086326Y1167105D01*
G01X1088126Y1164638D02*
Y1162505D01*
X1088593Y1162705D01*
X1088859Y1163038D01*
X1088993Y1163505D01*
X1088926Y1163971D01*
X1088726Y1164371D01*
X1088259Y1164638D01*
X1087859Y1164771D01*
X1087459D01*
X1087059Y1164638D01*
X1086659Y1164305D01*
X1086393Y1163905D01*
X1086326Y1163438D01*
X1086459Y1162971D01*
X1086859Y1162505D01*
G01X1088126Y1160038D02*
Y1157905D01*
X1088593Y1158105D01*
X1088859Y1158438D01*
X1088993Y1158905D01*
X1088926Y1159371D01*
X1088726Y1159771D01*
X1088259Y1160038D01*
X1087859Y1160171D01*
X1087459D01*
X1087059Y1160038D01*
X1086659Y1159705D01*
X1086393Y1159305D01*
X1086326Y1158838D01*
X1086459Y1158371D01*
X1086859Y1157905D01*
G01X1084993Y1155638D02*
X1088993D01*
G01X1088393D02*
X1088726Y1155305D01*
X1088926Y1154971D01*
X1088993Y1154438D01*
X1088926Y1153971D01*
X1088593Y1153505D01*
X1088126Y1153305D01*
X1087659Y1153238D01*
X1087193Y1153305D01*
X1086726Y1153505D01*
X1086459Y1153905D01*
X1086326Y1154438D01*
X1086393Y1154905D01*
X1086593Y1155371D01*
X1086859Y1155638D01*
G01X1086326Y1146371D02*
X1090326D01*
G01X1088393D02*
X1088726Y1146038D01*
X1088926Y1145705D01*
X1088993Y1145171D01*
X1088926Y1144771D01*
X1088659Y1144305D01*
X1088259Y1144105D01*
X1086326D01*
G01Y1140638D02*
X1086393Y1141038D01*
X1086659Y1141438D01*
X1087126Y1141705D01*
X1087659Y1141838D01*
X1088193Y1141705D01*
X1088659Y1141438D01*
X1088926Y1141038D01*
X1088993Y1140638D01*
X1088926Y1140238D01*
X1088659Y1139838D01*
X1088193Y1139571D01*
X1087659Y1139505D01*
X1087126Y1139571D01*
X1086659Y1139838D01*
X1086393Y1140238D01*
X1086326Y1140638D01*
G01Y1136038D02*
X1090326D01*
G01X1088126Y1132438D02*
Y1130305D01*
X1088593Y1130505D01*
X1088859Y1130838D01*
X1088993Y1131305D01*
X1088926Y1131771D01*
X1088726Y1132171D01*
X1088259Y1132438D01*
X1087859Y1132571D01*
X1087459D01*
X1087059Y1132438D01*
X1086659Y1132105D01*
X1086393Y1131705D01*
X1086326Y1131238D01*
X1086459Y1130771D01*
X1086859Y1130305D01*
G01X1086793Y1123238D02*
X1086526Y1122905D01*
X1086326Y1122438D01*
Y1122038D01*
X1086459Y1121638D01*
X1086659Y1121371D01*
X1086926Y1121238D01*
X1087326Y1121305D01*
X1087526Y1121571D01*
X1087926Y1122771D01*
X1088393Y1123038D01*
X1088726Y1122905D01*
X1088926Y1122638D01*
X1088993Y1122238D01*
X1088926Y1121838D01*
X1088726Y1121438D01*
G01X1088993Y1117638D02*
X1086326D01*
G01X1090059D02*
X1090126Y1117771D01*
X1090259D01*
X1090326Y1117638D01*
X1090259Y1117505D01*
X1090126D01*
X1090059Y1117638D01*
G01X1088993Y1114038D02*
Y1112038D01*
X1086326Y1114038D01*
Y1112038D01*
G01X1088126Y1109438D02*
Y1107305D01*
X1088593Y1107505D01*
X1088859Y1107838D01*
X1088993Y1108305D01*
X1088926Y1108771D01*
X1088726Y1109171D01*
X1088259Y1109438D01*
X1087859Y1109571D01*
X1087459D01*
X1087059Y1109438D01*
X1086659Y1109105D01*
X1086393Y1108705D01*
X1086326Y1108238D01*
X1086459Y1107771D01*
X1086859Y1107305D01*
G01X1090326Y1099238D02*
X1086326D01*
G01X1088993Y1100171D02*
Y1098305D01*
G01X1086326Y1094638D02*
X1086393Y1095038D01*
X1086659Y1095438D01*
X1087126Y1095705D01*
X1087659Y1095838D01*
X1088193Y1095705D01*
X1088659Y1095438D01*
X1088926Y1095038D01*
X1088993Y1094638D01*
X1088926Y1094238D01*
X1088659Y1093838D01*
X1088193Y1093571D01*
X1087659Y1093505D01*
X1087126Y1093571D01*
X1086659Y1093838D01*
X1086393Y1094238D01*
X1086326Y1094638D01*
G01Y1090038D02*
X1090326D01*
G01X1088126Y1086438D02*
Y1084305D01*
X1088593Y1084505D01*
X1088859Y1084838D01*
X1088993Y1085305D01*
X1088926Y1085771D01*
X1088726Y1086171D01*
X1088259Y1086438D01*
X1087859Y1086571D01*
X1087459D01*
X1087059Y1086438D01*
X1086659Y1086105D01*
X1086393Y1085705D01*
X1086326Y1085238D01*
X1086459Y1084771D01*
X1086859Y1084305D01*
G01X1086326Y1081771D02*
X1088993D01*
G01X1088459D02*
X1088726Y1081438D01*
X1088926Y1081105D01*
X1088993Y1080638D01*
X1088926Y1080305D01*
X1088726Y1079905D01*
G01X1086326Y1075038D02*
X1088993D01*
G01X1088526D02*
X1088793Y1075305D01*
X1088926Y1075705D01*
X1088993Y1076171D01*
X1088859Y1076638D01*
X1088593Y1077038D01*
X1088193Y1077305D01*
X1087659Y1077438D01*
X1087126Y1077305D01*
X1086726Y1077038D01*
X1086459Y1076638D01*
X1086326Y1076171D01*
X1086393Y1075705D01*
X1086593Y1075305D01*
X1086859Y1075038D01*
G01X1086326Y1072771D02*
X1088993D01*
G01X1088326D02*
X1088659Y1072505D01*
X1088926Y1072105D01*
X1088993Y1071571D01*
X1088926Y1071105D01*
X1088659Y1070705D01*
X1088193Y1070505D01*
X1086326D01*
G01X1088659Y1065971D02*
X1088926Y1066438D01*
X1088993Y1066838D01*
X1088859Y1067371D01*
X1088593Y1067771D01*
X1088126Y1068038D01*
X1087659Y1068105D01*
X1087193Y1068038D01*
X1086793Y1067771D01*
X1086459Y1067371D01*
X1086326Y1066838D01*
X1086459Y1066371D01*
X1086726Y1065971D01*
G01X1088126Y1063438D02*
Y1061305D01*
X1088593Y1061505D01*
X1088859Y1061838D01*
X1088993Y1062305D01*
X1088926Y1062771D01*
X1088726Y1063171D01*
X1088259Y1063438D01*
X1087859Y1063571D01*
X1087459D01*
X1087059Y1063438D01*
X1086659Y1063105D01*
X1086393Y1062705D01*
X1086326Y1062238D01*
X1086459Y1061771D01*
X1086859Y1061305D01*
G01X1087659Y1053971D02*
Y1052371D01*
G01X1088526Y1053238D02*
X1086793D01*
G01X1086193Y1049838D02*
X1090326Y1047438D01*
G01X1087659Y1044905D02*
Y1043171D01*
G01X1089659Y1040705D02*
X1090059Y1040305D01*
X1090259Y1039838D01*
X1090326Y1039305D01*
X1090193Y1038638D01*
X1089859Y1038171D01*
X1089459Y1038038D01*
X1089059Y1038105D01*
X1088726Y1038371D01*
X1088059Y1039705D01*
X1087593Y1040305D01*
X1086926Y1040705D01*
X1086326Y1040838D01*
Y1038038D01*
G01Y1032238D02*
X1088993D01*
G01X1088259D02*
X1088593Y1032038D01*
X1088859Y1031705D01*
X1088993Y1031238D01*
X1088859Y1030771D01*
X1088593Y1030438D01*
X1088259Y1030238D01*
X1086326D01*
G01X1088259D02*
X1088593Y1030038D01*
X1088859Y1029705D01*
X1088993Y1029238D01*
X1088859Y1028771D01*
X1088593Y1028438D01*
X1088193Y1028238D01*
X1086326D01*
G01X1088993Y1025638D02*
X1086326D01*
G01X1090059D02*
X1090126Y1025771D01*
X1090259D01*
X1090326Y1025638D01*
X1090259Y1025505D01*
X1090126D01*
X1090059Y1025638D01*
G01X1086326Y1021038D02*
X1090326D01*
G01X1086793Y1017438D02*
X1086526Y1017105D01*
X1086326Y1016638D01*
Y1016238D01*
X1086459Y1015838D01*
X1086659Y1015571D01*
X1086926Y1015438D01*
X1087326Y1015505D01*
X1087526Y1015771D01*
X1087926Y1016971D01*
X1088393Y1017238D01*
X1088726Y1017105D01*
X1088926Y1016838D01*
X1088993Y1016438D01*
X1088926Y1016038D01*
X1088726Y1015638D01*
G01X1105452Y963048D02*
X1105852Y962715D01*
X1106319Y962515D01*
X1106919Y962448D01*
X1107519Y962581D01*
X1107986Y962848D01*
X1108319Y963315D01*
X1108386Y963848D01*
X1108252Y964381D01*
X1107919Y964715D01*
X1107452Y964981D01*
X1106986Y965048D01*
X1106519Y964981D01*
X1105919Y964715D01*
X1106119Y966448D01*
X1107919D01*
G01X1110052Y963048D02*
X1110452Y962715D01*
X1110919Y962515D01*
X1111519Y962448D01*
X1112119Y962581D01*
X1112586Y962848D01*
X1112919Y963315D01*
X1112986Y963848D01*
X1112852Y964381D01*
X1112519Y964715D01*
X1112052Y964981D01*
X1111586Y965048D01*
X1111119Y964981D01*
X1110519Y964715D01*
X1110719Y966448D01*
X1112519D01*
G01X1115986Y962448D02*
X1116119Y963315D01*
X1116319Y964048D01*
X1116586Y964715D01*
X1116919Y965448D01*
X1117452Y966448D01*
X1114786D01*
G01X1120719Y962315D02*
X1120586Y962381D01*
Y962515D01*
X1120719Y962581D01*
X1120852Y962515D01*
Y962381D01*
X1120719Y962315D01*
G01X1125319Y966448D02*
X1124786Y966315D01*
X1124386Y965981D01*
X1124119Y965581D01*
X1123919Y965048D01*
X1123852Y964448D01*
X1123919Y963848D01*
X1124119Y963315D01*
X1124386Y962915D01*
X1124786Y962581D01*
X1125319Y962448D01*
X1125852Y962581D01*
X1126252Y962915D01*
X1126519Y963315D01*
X1126719Y963848D01*
X1126786Y964448D01*
X1126719Y965048D01*
X1126519Y965581D01*
X1126252Y965981D01*
X1125852Y966315D01*
X1125319Y966448D01*
G01X1128786Y962915D02*
X1129252Y962581D01*
X1129786Y962448D01*
X1130319Y962581D01*
X1130786Y962981D01*
X1131119Y963581D01*
X1131252Y964181D01*
Y964915D01*
X1131119Y965515D01*
X1130786Y966048D01*
X1130386Y966315D01*
X1129919Y966448D01*
X1129386Y966315D01*
X1128986Y966048D01*
X1128719Y965648D01*
X1128586Y965115D01*
X1128719Y964648D01*
X1129052Y964181D01*
X1129452Y963915D01*
X1129919Y963848D01*
X1130452Y963981D01*
X1130852Y964315D01*
X1131252Y964915D01*
G01X1122791Y973594D02*
X1123191Y973994D01*
X1123658Y974194D01*
X1124191Y974261D01*
X1124858Y974128D01*
X1125325Y973794D01*
X1125458Y973394D01*
X1125391Y972994D01*
X1125125Y972661D01*
X1123791Y971994D01*
X1123191Y971528D01*
X1122791Y970861D01*
X1122658Y970261D01*
X1125458D01*
G01X1127191Y971061D02*
X1127591Y970594D01*
X1128125Y970328D01*
X1128725Y970261D01*
X1129258Y970328D01*
X1129791Y970661D01*
X1130125Y971061D01*
X1130191Y971461D01*
X1130058Y971928D01*
X1129591Y972261D01*
X1129125Y972394D01*
X1128525D01*
G01X1129125D02*
X1129525Y972594D01*
X1129858Y972928D01*
X1129991Y973328D01*
X1129858Y973728D01*
X1129525Y974061D01*
X1128925Y974261D01*
X1128325Y974194D01*
X1127725Y973928D01*
G01X1131991Y971928D02*
X1132458Y972394D01*
X1132858Y972661D01*
X1133391Y972794D01*
X1133858Y972661D01*
X1134191Y972394D01*
X1134458Y971994D01*
X1134525Y971528D01*
X1134458Y971128D01*
X1134191Y970728D01*
X1133791Y970394D01*
X1133325Y970261D01*
X1132791Y970394D01*
X1132325Y970794D01*
X1132058Y971394D01*
X1131991Y972061D01*
X1132125Y972928D01*
X1132325Y973394D01*
X1132658Y973861D01*
X1133125Y974194D01*
X1133591Y974261D01*
X1134058Y974128D01*
X1134391Y973794D01*
G01X1137858Y970128D02*
X1137725Y970194D01*
Y970328D01*
X1137858Y970394D01*
X1137991Y970328D01*
Y970194D01*
X1137858Y970128D01*
G01X1141191Y973594D02*
X1141591Y973994D01*
X1142058Y974194D01*
X1142591Y974261D01*
X1143258Y974128D01*
X1143725Y973794D01*
X1143858Y973394D01*
X1143791Y972994D01*
X1143525Y972661D01*
X1142191Y971994D01*
X1141591Y971528D01*
X1141191Y970861D01*
X1141058Y970261D01*
X1143858D01*
G01X1145791Y973594D02*
X1146191Y973994D01*
X1146658Y974194D01*
X1147191Y974261D01*
X1147858Y974128D01*
X1148325Y973794D01*
X1148458Y973394D01*
X1148391Y972994D01*
X1148125Y972661D01*
X1146791Y971994D01*
X1146191Y971528D01*
X1145791Y970861D01*
X1145658Y970261D01*
X1148458D01*
G01X1088002Y1126638D02*
X1097702D01*
X1092702Y1121638D01*
Y1131638D01*
X1097702Y1126638D01*
G01X1129730Y1136038D02*
Y1116640D01*
X1098002D01*
Y1136038D01*
X1129730D01*
G01X1085630Y1417323D02*
G03X1089567Y1421260I0J3937D01*
G01X1085630Y1417323D02*
G03X1089567Y1421260I0J3937D01*
G01X1072638D02*
G03X1076575Y1417322I3937J-1D01*
G01X1085630Y1417323D02*
X1076575D01*
G01X1072638Y1421260D02*
G03X1076575Y1417323I3937J0D01*
G01D02*
X1085630D01*
G01X1089567Y1506243D02*
Y1421260D01*
G01Y1506243D02*
Y1421260D01*
G01X1072638D02*
Y1506243D01*
G01D02*
Y1421260D01*
G01X1103009Y1519685D02*
G03X1100225Y1518532I0J-3937D01*
G01X1207283Y1519685D02*
X1103009D01*
G01D02*
G03X1100225Y1518532I0J-3937D01*
G01X1207283Y1519685D02*
X1103009D01*
G01X1090720Y1509027D02*
G03X1089567Y1506243I2784J-2784D01*
G01X1100225Y1518532D02*
X1090720Y1509027D01*
G01D02*
G03X1089567Y1506243I2784J-2784D01*
G01X1100225Y1518532D02*
X1090720Y1509027D01*
G01X1061980Y1518532D02*
G03X1059196Y1519685I-2784J-2784D01*
G01X1061980Y1518532D02*
G03X1059196Y1519685I-2784J-2784D01*
G01X1071485Y1509027D02*
X1061980Y1518532D01*
G01X1072638Y1506243D02*
G03X1071485Y1509027I-3937J0D01*
G01X1072638Y1506243D02*
G03X1071485Y1509027I-3937J0D01*
G01X1061980Y1518532D02*
X1071485Y1509027D01*
G01X1216535Y54331D02*
G03X1224409I3937J0D01*
G01X1216535D02*
Y181890D01*
G01Y54331D02*
Y181890D01*
G01Y54331D02*
G03X1224409I3937J0D01*
G01Y23622D02*
G03X1216535I-3937J0D01*
G01X1224409D02*
G03X1216535I-3937J0D01*
G01X1212598Y0D02*
G03X1216535Y3937I0J3937D01*
G01D02*
Y23622D01*
G01X1212598Y0D02*
G03X1216535Y3937I0J3937D01*
G01X1224409D02*
G03X1228346Y0I3937J0D01*
G01X1224409Y185827D02*
Y3937D01*
G01X1216535D02*
Y23622D01*
G01X1224409Y3937D02*
G03X1228346Y0I3937J0D01*
G01X1224409Y3937D02*
Y185827D01*
G01X1228346Y0D02*
X1930906D01*
G01X1228346D02*
X1930906D01*
G01X1224409Y185827D02*
G03X1220472Y189764I-3937J0D01*
G01X1224409Y185827D02*
G03X1220472Y189764I-3937J0D01*
G01X1225433Y253599D02*
X1225833Y253266D01*
X1226300Y253066D01*
X1226900Y252999D01*
X1227500Y253132D01*
X1227967Y253399D01*
X1228300Y253866D01*
X1228367Y254399D01*
X1228233Y254932D01*
X1227900Y255266D01*
X1227433Y255532D01*
X1226967Y255599D01*
X1226500Y255532D01*
X1225900Y255266D01*
X1226100Y256999D01*
X1227900D01*
G01X1230033Y253599D02*
X1230433Y253266D01*
X1230900Y253066D01*
X1231500Y252999D01*
X1232100Y253132D01*
X1232567Y253399D01*
X1232900Y253866D01*
X1232967Y254399D01*
X1232833Y254932D01*
X1232500Y255266D01*
X1232033Y255532D01*
X1231567Y255599D01*
X1231100Y255532D01*
X1230500Y255266D01*
X1230700Y256999D01*
X1232500D01*
G01X1235967Y252999D02*
X1236100Y253866D01*
X1236300Y254599D01*
X1236567Y255266D01*
X1236900Y255999D01*
X1237433Y256999D01*
X1234767D01*
G01X1240700Y252866D02*
X1240567Y252932D01*
Y253066D01*
X1240700Y253132D01*
X1240833Y253066D01*
Y252932D01*
X1240700Y252866D01*
G01X1245300Y256999D02*
X1244767Y256866D01*
X1244367Y256532D01*
X1244100Y256132D01*
X1243900Y255599D01*
X1243833Y254999D01*
X1243900Y254399D01*
X1244100Y253866D01*
X1244367Y253466D01*
X1244767Y253132D01*
X1245300Y252999D01*
X1245833Y253132D01*
X1246233Y253466D01*
X1246500Y253866D01*
X1246700Y254399D01*
X1246767Y254999D01*
X1246700Y255599D01*
X1246500Y256132D01*
X1246233Y256532D01*
X1245833Y256866D01*
X1245300Y256999D01*
G01X1248767Y253466D02*
X1249233Y253132D01*
X1249767Y252999D01*
X1250300Y253132D01*
X1250767Y253532D01*
X1251100Y254132D01*
X1251233Y254732D01*
Y255466D01*
X1251100Y256066D01*
X1250767Y256599D01*
X1250367Y256866D01*
X1249900Y256999D01*
X1249367Y256866D01*
X1248967Y256599D01*
X1248700Y256199D01*
X1248567Y255666D01*
X1248700Y255199D01*
X1249033Y254732D01*
X1249433Y254466D01*
X1249900Y254399D01*
X1250433Y254532D01*
X1250833Y254866D01*
X1251233Y255466D01*
G01X1242772Y264145D02*
X1243172Y264545D01*
X1243639Y264745D01*
X1244172Y264812D01*
X1244839Y264679D01*
X1245306Y264345D01*
X1245439Y263945D01*
X1245372Y263545D01*
X1245106Y263212D01*
X1243772Y262545D01*
X1243172Y262079D01*
X1242772Y261412D01*
X1242639Y260812D01*
X1245439D01*
G01X1247172Y261612D02*
X1247572Y261145D01*
X1248106Y260879D01*
X1248706Y260812D01*
X1249239Y260879D01*
X1249772Y261212D01*
X1250106Y261612D01*
X1250172Y262012D01*
X1250039Y262479D01*
X1249572Y262812D01*
X1249106Y262945D01*
X1248506D01*
G01X1249106D02*
X1249506Y263145D01*
X1249839Y263479D01*
X1249972Y263879D01*
X1249839Y264279D01*
X1249506Y264612D01*
X1248906Y264812D01*
X1248306Y264745D01*
X1247706Y264479D01*
G01X1251972Y262479D02*
X1252439Y262945D01*
X1252839Y263212D01*
X1253372Y263345D01*
X1253839Y263212D01*
X1254172Y262945D01*
X1254439Y262545D01*
X1254506Y262079D01*
X1254439Y261679D01*
X1254172Y261279D01*
X1253772Y260945D01*
X1253306Y260812D01*
X1252772Y260945D01*
X1252306Y261345D01*
X1252039Y261945D01*
X1251972Y262612D01*
X1252106Y263479D01*
X1252306Y263945D01*
X1252639Y264412D01*
X1253106Y264745D01*
X1253572Y264812D01*
X1254039Y264679D01*
X1254372Y264345D01*
G01X1257839Y260679D02*
X1257706Y260745D01*
Y260879D01*
X1257839Y260945D01*
X1257972Y260879D01*
Y260745D01*
X1257839Y260679D01*
G01X1261172Y264145D02*
X1261572Y264545D01*
X1262039Y264745D01*
X1262572Y264812D01*
X1263239Y264679D01*
X1263706Y264345D01*
X1263839Y263945D01*
X1263772Y263545D01*
X1263506Y263212D01*
X1262172Y262545D01*
X1261572Y262079D01*
X1261172Y261412D01*
X1261039Y260812D01*
X1263839D01*
G01X1265772Y264145D02*
X1266172Y264545D01*
X1266639Y264745D01*
X1267172Y264812D01*
X1267839Y264679D01*
X1268306Y264345D01*
X1268439Y263945D01*
X1268372Y263545D01*
X1268106Y263212D01*
X1266772Y262545D01*
X1266172Y262079D01*
X1265772Y261412D01*
X1265639Y260812D01*
X1268439D01*
G01X1223486Y339449D02*
Y343449D01*
X1221019Y340582D01*
X1224353D01*
G01X1225819Y340249D02*
X1226219Y339782D01*
X1226753Y339516D01*
X1227353Y339449D01*
X1227886Y339516D01*
X1228419Y339849D01*
X1228753Y340249D01*
X1228819Y340649D01*
X1228686Y341116D01*
X1228219Y341449D01*
X1227753Y341582D01*
X1227153D01*
G01X1227753D02*
X1228153Y341782D01*
X1228486Y342116D01*
X1228619Y342516D01*
X1228486Y342916D01*
X1228153Y343249D01*
X1227553Y343449D01*
X1226953Y343382D01*
X1226353Y343116D01*
G01X1230419Y340249D02*
X1230819Y339782D01*
X1231353Y339516D01*
X1231953Y339449D01*
X1232486Y339516D01*
X1233019Y339849D01*
X1233353Y340249D01*
X1233419Y340649D01*
X1233286Y341116D01*
X1232819Y341449D01*
X1232353Y341582D01*
X1231753D01*
G01X1232353D02*
X1232753Y341782D01*
X1233086Y342116D01*
X1233219Y342516D01*
X1233086Y342916D01*
X1232753Y343249D01*
X1232153Y343449D01*
X1231553Y343382D01*
X1230953Y343116D01*
G01X1236486Y339316D02*
X1236353Y339382D01*
Y339516D01*
X1236486Y339582D01*
X1236619Y339516D01*
Y339382D01*
X1236486Y339316D01*
G01X1241086Y343449D02*
X1240553Y343316D01*
X1240153Y342982D01*
X1239886Y342582D01*
X1239686Y342049D01*
X1239619Y341449D01*
X1239686Y340849D01*
X1239886Y340316D01*
X1240153Y339916D01*
X1240553Y339582D01*
X1241086Y339449D01*
X1241619Y339582D01*
X1242019Y339916D01*
X1242286Y340316D01*
X1242486Y340849D01*
X1242553Y341449D01*
X1242486Y342049D01*
X1242286Y342582D01*
X1242019Y342982D01*
X1241619Y343316D01*
X1241086Y343449D01*
G01X1245686Y339449D02*
X1246153Y339516D01*
X1246686Y339716D01*
X1247019Y340049D01*
X1247153Y340516D01*
X1247019Y340982D01*
X1246619Y341382D01*
X1246019Y341582D01*
X1245353D01*
X1244953Y341716D01*
X1244619Y342049D01*
X1244486Y342516D01*
X1244686Y342982D01*
X1245153Y343316D01*
X1245686Y343449D01*
X1246219Y343316D01*
X1246686Y342982D01*
X1246886Y342516D01*
X1246753Y342049D01*
X1246419Y341716D01*
X1246019Y341582D01*
X1245353D01*
X1244753Y341382D01*
X1244353Y340982D01*
X1244219Y340516D01*
X1244353Y340049D01*
X1244686Y339716D01*
X1245219Y339516D01*
X1245686Y339449D01*
G01X1164984Y383609D02*
G03X1198795I16906J-13530D01*
G01X1164984D02*
G03X1198795I16906J-13530D01*
G01X1223578Y423773D02*
X1223978Y424173D01*
X1224445Y424373D01*
X1224978Y424440D01*
X1225645Y424307D01*
X1226112Y423973D01*
X1226245Y423573D01*
X1226178Y423173D01*
X1225912Y422840D01*
X1224578Y422173D01*
X1223978Y421707D01*
X1223578Y421040D01*
X1223445Y420440D01*
X1226245D01*
G01X1229445Y424440D02*
X1228912Y424307D01*
X1228512Y423973D01*
X1228245Y423573D01*
X1228045Y423040D01*
X1227978Y422440D01*
X1228045Y421840D01*
X1228245Y421307D01*
X1228512Y420907D01*
X1228912Y420573D01*
X1229445Y420440D01*
X1229978Y420573D01*
X1230378Y420907D01*
X1230645Y421307D01*
X1230845Y421840D01*
X1230912Y422440D01*
X1230845Y423040D01*
X1230645Y423573D01*
X1230378Y423973D01*
X1229978Y424307D01*
X1229445Y424440D01*
G01X1234045Y420440D02*
X1234512Y420507D01*
X1235045Y420707D01*
X1235378Y421040D01*
X1235512Y421507D01*
X1235378Y421973D01*
X1234978Y422373D01*
X1234378Y422573D01*
X1233712D01*
X1233312Y422707D01*
X1232978Y423040D01*
X1232845Y423507D01*
X1233045Y423973D01*
X1233512Y424307D01*
X1234045Y424440D01*
X1234578Y424307D01*
X1235045Y423973D01*
X1235245Y423507D01*
X1235112Y423040D01*
X1234778Y422707D01*
X1234378Y422573D01*
X1233712D01*
X1233112Y422373D01*
X1232712Y421973D01*
X1232578Y421507D01*
X1232712Y421040D01*
X1233045Y420707D01*
X1233578Y420507D01*
X1234045Y420440D01*
G01X1238645Y420307D02*
X1238512Y420373D01*
Y420507D01*
X1238645Y420573D01*
X1238778Y420507D01*
Y420373D01*
X1238645Y420307D01*
G01X1241978Y422107D02*
X1242445Y422573D01*
X1242845Y422840D01*
X1243378Y422973D01*
X1243845Y422840D01*
X1244178Y422573D01*
X1244445Y422173D01*
X1244512Y421707D01*
X1244445Y421307D01*
X1244178Y420907D01*
X1243778Y420573D01*
X1243312Y420440D01*
X1242778Y420573D01*
X1242312Y420973D01*
X1242045Y421573D01*
X1241978Y422240D01*
X1242112Y423107D01*
X1242312Y423573D01*
X1242645Y424040D01*
X1243112Y424373D01*
X1243578Y424440D01*
X1244045Y424307D01*
X1244378Y423973D01*
G01X1246578Y422107D02*
X1247045Y422573D01*
X1247445Y422840D01*
X1247978Y422973D01*
X1248445Y422840D01*
X1248778Y422573D01*
X1249045Y422173D01*
X1249112Y421707D01*
X1249045Y421307D01*
X1248778Y420907D01*
X1248378Y420573D01*
X1247912Y420440D01*
X1247378Y420573D01*
X1246912Y420973D01*
X1246645Y421573D01*
X1246578Y422240D01*
X1246712Y423107D01*
X1246912Y423573D01*
X1247245Y424040D01*
X1247712Y424373D01*
X1248178Y424440D01*
X1248645Y424307D01*
X1248978Y423973D01*
G01X1217023Y381606D02*
Y385606D01*
X1218357D01*
X1218890Y385406D01*
X1219290Y385139D01*
X1219623Y384739D01*
X1219890Y384273D01*
X1219957Y383606D01*
X1219890Y382939D01*
X1219623Y382473D01*
X1219290Y382073D01*
X1218890Y381806D01*
X1218357Y381606D01*
X1217023D01*
G01X1222157D02*
Y384273D01*
G01Y383739D02*
X1222490Y384006D01*
X1222823Y384206D01*
X1223290Y384273D01*
X1223623Y384206D01*
X1224023Y384006D01*
G01X1227690Y384273D02*
Y381606D01*
G01Y385339D02*
X1227557Y385406D01*
Y385539D01*
X1227690Y385606D01*
X1227823Y385539D01*
Y385406D01*
X1227690Y385339D01*
G01X1232290Y381606D02*
Y385606D01*
G01X1236890Y381606D02*
Y385606D01*
G01X1245690Y381606D02*
Y385006D01*
X1245823Y385339D01*
X1246090Y385539D01*
X1246490Y385606D01*
X1246890Y385473D01*
X1247090Y385139D01*
G01X1246290Y384006D02*
X1244957D01*
G01X1249690Y383406D02*
X1251823D01*
X1251623Y383873D01*
X1251290Y384139D01*
X1250823Y384273D01*
X1250357Y384206D01*
X1249957Y384006D01*
X1249690Y383539D01*
X1249557Y383139D01*
Y382739D01*
X1249690Y382339D01*
X1250023Y381939D01*
X1250423Y381673D01*
X1250890Y381606D01*
X1251357Y381739D01*
X1251823Y382139D01*
G01X1256490Y381606D02*
Y384273D01*
G01Y383806D02*
X1256223Y384073D01*
X1255823Y384206D01*
X1255357Y384273D01*
X1254890Y384139D01*
X1254490Y383873D01*
X1254223Y383473D01*
X1254090Y382939D01*
X1254223Y382406D01*
X1254490Y382006D01*
X1254890Y381739D01*
X1255357Y381606D01*
X1255823Y381673D01*
X1256223Y381873D01*
X1256490Y382139D01*
G01X1259890Y385606D02*
Y381606D01*
G01X1258957Y384273D02*
X1260823D01*
G01X1263357D02*
Y382406D01*
X1263623Y381939D01*
X1264023Y381673D01*
X1264490Y381606D01*
X1264957Y381673D01*
X1265357Y381939D01*
X1265623Y382406D01*
G01Y381606D02*
Y384273D01*
G01X1268157Y381606D02*
Y384273D01*
G01Y383739D02*
X1268490Y384006D01*
X1268823Y384206D01*
X1269290Y384273D01*
X1269623Y384206D01*
X1270023Y384006D01*
G01X1272690Y383406D02*
X1274823D01*
X1274623Y383873D01*
X1274290Y384139D01*
X1273823Y384273D01*
X1273357Y384206D01*
X1272957Y384006D01*
X1272690Y383539D01*
X1272557Y383139D01*
Y382739D01*
X1272690Y382339D01*
X1273023Y381939D01*
X1273423Y381673D01*
X1273890Y381606D01*
X1274357Y381739D01*
X1274823Y382139D01*
G01X1191870Y396741D02*
G03X1198795Y383610I37662J11471D01*
G01X1191870Y396741D02*
G03X1198795Y383609I37663J11469D01*
G01X1191870Y396741D02*
G03X1171909I-9980J-3040D01*
G01X1164984Y383610D02*
G03X1171909Y396741I-30737J24602D01*
G01X1191870D02*
G03X1171909I-9980J-3040D01*
G01X1164984Y383609D02*
G03X1171909Y396741I-30737J24601D01*
G01X1225433Y706356D02*
X1225833Y706023D01*
X1226300Y705823D01*
X1226900Y705756D01*
X1227500Y705889D01*
X1227967Y706156D01*
X1228300Y706623D01*
X1228367Y707156D01*
X1228233Y707689D01*
X1227900Y708023D01*
X1227433Y708289D01*
X1226967Y708356D01*
X1226500Y708289D01*
X1225900Y708023D01*
X1226100Y709756D01*
X1227900D01*
G01X1230033Y706356D02*
X1230433Y706023D01*
X1230900Y705823D01*
X1231500Y705756D01*
X1232100Y705889D01*
X1232567Y706156D01*
X1232900Y706623D01*
X1232967Y707156D01*
X1232833Y707689D01*
X1232500Y708023D01*
X1232033Y708289D01*
X1231567Y708356D01*
X1231100Y708289D01*
X1230500Y708023D01*
X1230700Y709756D01*
X1232500D01*
G01X1235967Y705756D02*
X1236100Y706623D01*
X1236300Y707356D01*
X1236567Y708023D01*
X1236900Y708756D01*
X1237433Y709756D01*
X1234767D01*
G01X1240700Y705623D02*
X1240567Y705689D01*
Y705823D01*
X1240700Y705889D01*
X1240833Y705823D01*
Y705689D01*
X1240700Y705623D01*
G01X1245300Y709756D02*
X1244767Y709623D01*
X1244367Y709289D01*
X1244100Y708889D01*
X1243900Y708356D01*
X1243833Y707756D01*
X1243900Y707156D01*
X1244100Y706623D01*
X1244367Y706223D01*
X1244767Y705889D01*
X1245300Y705756D01*
X1245833Y705889D01*
X1246233Y706223D01*
X1246500Y706623D01*
X1246700Y707156D01*
X1246767Y707756D01*
X1246700Y708356D01*
X1246500Y708889D01*
X1246233Y709289D01*
X1245833Y709623D01*
X1245300Y709756D01*
G01X1248767Y706223D02*
X1249233Y705889D01*
X1249767Y705756D01*
X1250300Y705889D01*
X1250767Y706289D01*
X1251100Y706889D01*
X1251233Y707489D01*
Y708223D01*
X1251100Y708823D01*
X1250767Y709356D01*
X1250367Y709623D01*
X1249900Y709756D01*
X1249367Y709623D01*
X1248967Y709356D01*
X1248700Y708956D01*
X1248567Y708423D01*
X1248700Y707956D01*
X1249033Y707489D01*
X1249433Y707223D01*
X1249900Y707156D01*
X1250433Y707289D01*
X1250833Y707623D01*
X1251233Y708223D01*
G01X1242772Y716902D02*
X1243172Y717302D01*
X1243639Y717502D01*
X1244172Y717569D01*
X1244839Y717436D01*
X1245306Y717102D01*
X1245439Y716702D01*
X1245372Y716302D01*
X1245106Y715969D01*
X1243772Y715302D01*
X1243172Y714836D01*
X1242772Y714169D01*
X1242639Y713569D01*
X1245439D01*
G01X1247172Y714369D02*
X1247572Y713902D01*
X1248106Y713636D01*
X1248706Y713569D01*
X1249239Y713636D01*
X1249772Y713969D01*
X1250106Y714369D01*
X1250172Y714769D01*
X1250039Y715236D01*
X1249572Y715569D01*
X1249106Y715702D01*
X1248506D01*
G01X1249106D02*
X1249506Y715902D01*
X1249839Y716236D01*
X1249972Y716636D01*
X1249839Y717036D01*
X1249506Y717369D01*
X1248906Y717569D01*
X1248306Y717502D01*
X1247706Y717236D01*
G01X1251972Y715236D02*
X1252439Y715702D01*
X1252839Y715969D01*
X1253372Y716102D01*
X1253839Y715969D01*
X1254172Y715702D01*
X1254439Y715302D01*
X1254506Y714836D01*
X1254439Y714436D01*
X1254172Y714036D01*
X1253772Y713702D01*
X1253306Y713569D01*
X1252772Y713702D01*
X1252306Y714102D01*
X1252039Y714702D01*
X1251972Y715369D01*
X1252106Y716236D01*
X1252306Y716702D01*
X1252639Y717169D01*
X1253106Y717502D01*
X1253572Y717569D01*
X1254039Y717436D01*
X1254372Y717102D01*
G01X1257839Y713436D02*
X1257706Y713502D01*
Y713636D01*
X1257839Y713702D01*
X1257972Y713636D01*
Y713502D01*
X1257839Y713436D01*
G01X1261172Y716902D02*
X1261572Y717302D01*
X1262039Y717502D01*
X1262572Y717569D01*
X1263239Y717436D01*
X1263706Y717102D01*
X1263839Y716702D01*
X1263772Y716302D01*
X1263506Y715969D01*
X1262172Y715302D01*
X1261572Y714836D01*
X1261172Y714169D01*
X1261039Y713569D01*
X1263839D01*
G01X1265772Y716902D02*
X1266172Y717302D01*
X1266639Y717502D01*
X1267172Y717569D01*
X1267839Y717436D01*
X1268306Y717102D01*
X1268439Y716702D01*
X1268372Y716302D01*
X1268106Y715969D01*
X1266772Y715302D01*
X1266172Y714836D01*
X1265772Y714169D01*
X1265639Y713569D01*
X1268439D01*
G01X1223486Y930000D02*
Y934000D01*
X1221019Y931133D01*
X1224353D01*
G01X1225819Y930800D02*
X1226219Y930333D01*
X1226753Y930067D01*
X1227353Y930000D01*
X1227886Y930067D01*
X1228419Y930400D01*
X1228753Y930800D01*
X1228819Y931200D01*
X1228686Y931667D01*
X1228219Y932000D01*
X1227753Y932133D01*
X1227153D01*
G01X1227753D02*
X1228153Y932333D01*
X1228486Y932667D01*
X1228619Y933067D01*
X1228486Y933467D01*
X1228153Y933800D01*
X1227553Y934000D01*
X1226953Y933933D01*
X1226353Y933667D01*
G01X1230419Y930800D02*
X1230819Y930333D01*
X1231353Y930067D01*
X1231953Y930000D01*
X1232486Y930067D01*
X1233019Y930400D01*
X1233353Y930800D01*
X1233419Y931200D01*
X1233286Y931667D01*
X1232819Y932000D01*
X1232353Y932133D01*
X1231753D01*
G01X1232353D02*
X1232753Y932333D01*
X1233086Y932667D01*
X1233219Y933067D01*
X1233086Y933467D01*
X1232753Y933800D01*
X1232153Y934000D01*
X1231553Y933933D01*
X1230953Y933667D01*
G01X1236486Y929867D02*
X1236353Y929933D01*
Y930067D01*
X1236486Y930133D01*
X1236619Y930067D01*
Y929933D01*
X1236486Y929867D01*
G01X1241086Y934000D02*
X1240553Y933867D01*
X1240153Y933533D01*
X1239886Y933133D01*
X1239686Y932600D01*
X1239619Y932000D01*
X1239686Y931400D01*
X1239886Y930867D01*
X1240153Y930467D01*
X1240553Y930133D01*
X1241086Y930000D01*
X1241619Y930133D01*
X1242019Y930467D01*
X1242286Y930867D01*
X1242486Y931400D01*
X1242553Y932000D01*
X1242486Y932600D01*
X1242286Y933133D01*
X1242019Y933533D01*
X1241619Y933867D01*
X1241086Y934000D01*
G01X1245686Y930000D02*
X1246153Y930067D01*
X1246686Y930267D01*
X1247019Y930600D01*
X1247153Y931067D01*
X1247019Y931533D01*
X1246619Y931933D01*
X1246019Y932133D01*
X1245353D01*
X1244953Y932267D01*
X1244619Y932600D01*
X1244486Y933067D01*
X1244686Y933533D01*
X1245153Y933867D01*
X1245686Y934000D01*
X1246219Y933867D01*
X1246686Y933533D01*
X1246886Y933067D01*
X1246753Y932600D01*
X1246419Y932267D01*
X1246019Y932133D01*
X1245353D01*
X1244753Y931933D01*
X1244353Y931533D01*
X1244219Y931067D01*
X1244353Y930600D01*
X1244686Y930267D01*
X1245219Y930067D01*
X1245686Y930000D01*
G01X1164984Y974161D02*
G03X1198795I16906J-13531D01*
G01X1164984D02*
G03X1198795I16906J-13531D01*
G01X1223578Y1014324D02*
X1223978Y1014724D01*
X1224445Y1014924D01*
X1224978Y1014991D01*
X1225645Y1014858D01*
X1226112Y1014524D01*
X1226245Y1014124D01*
X1226178Y1013724D01*
X1225912Y1013391D01*
X1224578Y1012724D01*
X1223978Y1012258D01*
X1223578Y1011591D01*
X1223445Y1010991D01*
X1226245D01*
G01X1229445Y1014991D02*
X1228912Y1014858D01*
X1228512Y1014524D01*
X1228245Y1014124D01*
X1228045Y1013591D01*
X1227978Y1012991D01*
X1228045Y1012391D01*
X1228245Y1011858D01*
X1228512Y1011458D01*
X1228912Y1011124D01*
X1229445Y1010991D01*
X1229978Y1011124D01*
X1230378Y1011458D01*
X1230645Y1011858D01*
X1230845Y1012391D01*
X1230912Y1012991D01*
X1230845Y1013591D01*
X1230645Y1014124D01*
X1230378Y1014524D01*
X1229978Y1014858D01*
X1229445Y1014991D01*
G01X1234045Y1010991D02*
X1234512Y1011058D01*
X1235045Y1011258D01*
X1235378Y1011591D01*
X1235512Y1012058D01*
X1235378Y1012524D01*
X1234978Y1012924D01*
X1234378Y1013124D01*
X1233712D01*
X1233312Y1013258D01*
X1232978Y1013591D01*
X1232845Y1014058D01*
X1233045Y1014524D01*
X1233512Y1014858D01*
X1234045Y1014991D01*
X1234578Y1014858D01*
X1235045Y1014524D01*
X1235245Y1014058D01*
X1235112Y1013591D01*
X1234778Y1013258D01*
X1234378Y1013124D01*
X1233712D01*
X1233112Y1012924D01*
X1232712Y1012524D01*
X1232578Y1012058D01*
X1232712Y1011591D01*
X1233045Y1011258D01*
X1233578Y1011058D01*
X1234045Y1010991D01*
G01X1238645Y1010858D02*
X1238512Y1010924D01*
Y1011058D01*
X1238645Y1011124D01*
X1238778Y1011058D01*
Y1010924D01*
X1238645Y1010858D01*
G01X1241978Y1012658D02*
X1242445Y1013124D01*
X1242845Y1013391D01*
X1243378Y1013524D01*
X1243845Y1013391D01*
X1244178Y1013124D01*
X1244445Y1012724D01*
X1244512Y1012258D01*
X1244445Y1011858D01*
X1244178Y1011458D01*
X1243778Y1011124D01*
X1243312Y1010991D01*
X1242778Y1011124D01*
X1242312Y1011524D01*
X1242045Y1012124D01*
X1241978Y1012791D01*
X1242112Y1013658D01*
X1242312Y1014124D01*
X1242645Y1014591D01*
X1243112Y1014924D01*
X1243578Y1014991D01*
X1244045Y1014858D01*
X1244378Y1014524D01*
G01X1246578Y1012658D02*
X1247045Y1013124D01*
X1247445Y1013391D01*
X1247978Y1013524D01*
X1248445Y1013391D01*
X1248778Y1013124D01*
X1249045Y1012724D01*
X1249112Y1012258D01*
X1249045Y1011858D01*
X1248778Y1011458D01*
X1248378Y1011124D01*
X1247912Y1010991D01*
X1247378Y1011124D01*
X1246912Y1011524D01*
X1246645Y1012124D01*
X1246578Y1012791D01*
X1246712Y1013658D01*
X1246912Y1014124D01*
X1247245Y1014591D01*
X1247712Y1014924D01*
X1248178Y1014991D01*
X1248645Y1014858D01*
X1248978Y1014524D01*
G01X1217023Y972157D02*
Y976157D01*
X1218357D01*
X1218890Y975957D01*
X1219290Y975690D01*
X1219623Y975290D01*
X1219890Y974824D01*
X1219957Y974157D01*
X1219890Y973490D01*
X1219623Y973024D01*
X1219290Y972624D01*
X1218890Y972357D01*
X1218357Y972157D01*
X1217023D01*
G01X1222157D02*
Y974824D01*
G01Y974290D02*
X1222490Y974557D01*
X1222823Y974757D01*
X1223290Y974824D01*
X1223623Y974757D01*
X1224023Y974557D01*
G01X1227690Y974824D02*
Y972157D01*
G01Y975890D02*
X1227557Y975957D01*
Y976090D01*
X1227690Y976157D01*
X1227823Y976090D01*
Y975957D01*
X1227690Y975890D01*
G01X1232290Y972157D02*
Y976157D01*
G01X1236890Y972157D02*
Y976157D01*
G01X1245690Y972157D02*
Y975557D01*
X1245823Y975890D01*
X1246090Y976090D01*
X1246490Y976157D01*
X1246890Y976024D01*
X1247090Y975690D01*
G01X1246290Y974557D02*
X1244957D01*
G01X1249690Y973957D02*
X1251823D01*
X1251623Y974424D01*
X1251290Y974690D01*
X1250823Y974824D01*
X1250357Y974757D01*
X1249957Y974557D01*
X1249690Y974090D01*
X1249557Y973690D01*
Y973290D01*
X1249690Y972890D01*
X1250023Y972490D01*
X1250423Y972224D01*
X1250890Y972157D01*
X1251357Y972290D01*
X1251823Y972690D01*
G01X1256490Y972157D02*
Y974824D01*
G01Y974357D02*
X1256223Y974624D01*
X1255823Y974757D01*
X1255357Y974824D01*
X1254890Y974690D01*
X1254490Y974424D01*
X1254223Y974024D01*
X1254090Y973490D01*
X1254223Y972957D01*
X1254490Y972557D01*
X1254890Y972290D01*
X1255357Y972157D01*
X1255823Y972224D01*
X1256223Y972424D01*
X1256490Y972690D01*
G01X1259890Y976157D02*
Y972157D01*
G01X1258957Y974824D02*
X1260823D01*
G01X1263357D02*
Y972957D01*
X1263623Y972490D01*
X1264023Y972224D01*
X1264490Y972157D01*
X1264957Y972224D01*
X1265357Y972490D01*
X1265623Y972957D01*
G01Y972157D02*
Y974824D01*
G01X1268157Y972157D02*
Y974824D01*
G01Y974290D02*
X1268490Y974557D01*
X1268823Y974757D01*
X1269290Y974824D01*
X1269623Y974757D01*
X1270023Y974557D01*
G01X1272690Y973957D02*
X1274823D01*
X1274623Y974424D01*
X1274290Y974690D01*
X1273823Y974824D01*
X1273357Y974757D01*
X1272957Y974557D01*
X1272690Y974090D01*
X1272557Y973690D01*
Y973290D01*
X1272690Y972890D01*
X1273023Y972490D01*
X1273423Y972224D01*
X1273890Y972157D01*
X1274357Y972290D01*
X1274823Y972690D01*
G01X1191870Y987292D02*
G03X1198795Y974161I37662J11471D01*
G01X1191870Y987292D02*
G03X1198795Y974161I37662J11471D01*
G01X1191870Y987292D02*
G03X1171909I-9980J-3040D01*
G01X1164984Y974161D02*
G03X1171909Y987292I-30737J24602D01*
G01X1191870D02*
G03X1171909I-9980J-3040D01*
G01X1164984Y974161D02*
G03X1171909Y987292I-30737J24601D01*
G01X1225433Y1159111D02*
X1225833Y1158778D01*
X1226300Y1158578D01*
X1226900Y1158511D01*
X1227500Y1158644D01*
X1227967Y1158911D01*
X1228300Y1159378D01*
X1228367Y1159911D01*
X1228233Y1160444D01*
X1227900Y1160778D01*
X1227433Y1161044D01*
X1226967Y1161111D01*
X1226500Y1161044D01*
X1225900Y1160778D01*
X1226100Y1162511D01*
X1227900D01*
G01X1230033Y1159111D02*
X1230433Y1158778D01*
X1230900Y1158578D01*
X1231500Y1158511D01*
X1232100Y1158644D01*
X1232567Y1158911D01*
X1232900Y1159378D01*
X1232967Y1159911D01*
X1232833Y1160444D01*
X1232500Y1160778D01*
X1232033Y1161044D01*
X1231567Y1161111D01*
X1231100Y1161044D01*
X1230500Y1160778D01*
X1230700Y1162511D01*
X1232500D01*
G01X1235967Y1158511D02*
X1236100Y1159378D01*
X1236300Y1160111D01*
X1236567Y1160778D01*
X1236900Y1161511D01*
X1237433Y1162511D01*
X1234767D01*
G01X1240700Y1158378D02*
X1240567Y1158444D01*
Y1158578D01*
X1240700Y1158644D01*
X1240833Y1158578D01*
Y1158444D01*
X1240700Y1158378D01*
G01X1245300Y1162511D02*
X1244767Y1162378D01*
X1244367Y1162044D01*
X1244100Y1161644D01*
X1243900Y1161111D01*
X1243833Y1160511D01*
X1243900Y1159911D01*
X1244100Y1159378D01*
X1244367Y1158978D01*
X1244767Y1158644D01*
X1245300Y1158511D01*
X1245833Y1158644D01*
X1246233Y1158978D01*
X1246500Y1159378D01*
X1246700Y1159911D01*
X1246767Y1160511D01*
X1246700Y1161111D01*
X1246500Y1161644D01*
X1246233Y1162044D01*
X1245833Y1162378D01*
X1245300Y1162511D01*
G01X1248767Y1158978D02*
X1249233Y1158644D01*
X1249767Y1158511D01*
X1250300Y1158644D01*
X1250767Y1159044D01*
X1251100Y1159644D01*
X1251233Y1160244D01*
Y1160978D01*
X1251100Y1161578D01*
X1250767Y1162111D01*
X1250367Y1162378D01*
X1249900Y1162511D01*
X1249367Y1162378D01*
X1248967Y1162111D01*
X1248700Y1161711D01*
X1248567Y1161178D01*
X1248700Y1160711D01*
X1249033Y1160244D01*
X1249433Y1159978D01*
X1249900Y1159911D01*
X1250433Y1160044D01*
X1250833Y1160378D01*
X1251233Y1160978D01*
G01X1242772Y1169657D02*
X1243172Y1170057D01*
X1243639Y1170257D01*
X1244172Y1170324D01*
X1244839Y1170191D01*
X1245306Y1169857D01*
X1245439Y1169457D01*
X1245372Y1169057D01*
X1245106Y1168724D01*
X1243772Y1168057D01*
X1243172Y1167591D01*
X1242772Y1166924D01*
X1242639Y1166324D01*
X1245439D01*
G01X1247172Y1167124D02*
X1247572Y1166657D01*
X1248106Y1166391D01*
X1248706Y1166324D01*
X1249239Y1166391D01*
X1249772Y1166724D01*
X1250106Y1167124D01*
X1250172Y1167524D01*
X1250039Y1167991D01*
X1249572Y1168324D01*
X1249106Y1168457D01*
X1248506D01*
G01X1249106D02*
X1249506Y1168657D01*
X1249839Y1168991D01*
X1249972Y1169391D01*
X1249839Y1169791D01*
X1249506Y1170124D01*
X1248906Y1170324D01*
X1248306Y1170257D01*
X1247706Y1169991D01*
G01X1251972Y1167991D02*
X1252439Y1168457D01*
X1252839Y1168724D01*
X1253372Y1168857D01*
X1253839Y1168724D01*
X1254172Y1168457D01*
X1254439Y1168057D01*
X1254506Y1167591D01*
X1254439Y1167191D01*
X1254172Y1166791D01*
X1253772Y1166457D01*
X1253306Y1166324D01*
X1252772Y1166457D01*
X1252306Y1166857D01*
X1252039Y1167457D01*
X1251972Y1168124D01*
X1252106Y1168991D01*
X1252306Y1169457D01*
X1252639Y1169924D01*
X1253106Y1170257D01*
X1253572Y1170324D01*
X1254039Y1170191D01*
X1254372Y1169857D01*
G01X1257839Y1166191D02*
X1257706Y1166257D01*
Y1166391D01*
X1257839Y1166457D01*
X1257972Y1166391D01*
Y1166257D01*
X1257839Y1166191D01*
G01X1261172Y1169657D02*
X1261572Y1170057D01*
X1262039Y1170257D01*
X1262572Y1170324D01*
X1263239Y1170191D01*
X1263706Y1169857D01*
X1263839Y1169457D01*
X1263772Y1169057D01*
X1263506Y1168724D01*
X1262172Y1168057D01*
X1261572Y1167591D01*
X1261172Y1166924D01*
X1261039Y1166324D01*
X1263839D01*
G01X1265772Y1169657D02*
X1266172Y1170057D01*
X1266639Y1170257D01*
X1267172Y1170324D01*
X1267839Y1170191D01*
X1268306Y1169857D01*
X1268439Y1169457D01*
X1268372Y1169057D01*
X1268106Y1168724D01*
X1266772Y1168057D01*
X1266172Y1167591D01*
X1265772Y1166924D01*
X1265639Y1166324D01*
X1268439D01*
G01X1240748Y1505118D02*
G03X1244685Y1509055I0J3937D01*
G01X1240748Y1505118D02*
G03X1244685Y1509055I0J3937D01*
G01X1211220Y1515748D02*
G03X1207283Y1519685I-3937J0D01*
G01X1211220Y1515748D02*
G03X1207283Y1519685I-3937J0D01*
G01X1211220Y1509055D02*
Y1515748D01*
G01Y1509055D02*
G03X1215157Y1505118I3937J0D01*
G01X1240748D02*
X1215157D01*
G01X1211220Y1509055D02*
G03X1215157Y1505118I3937J0D01*
G01D02*
X1240748D01*
G01X1211220Y1515748D02*
Y1509055D01*
G01X1337004Y262708D02*
Y266708D01*
X1338338D01*
X1338871Y266508D01*
X1339271Y266241D01*
X1339604Y265841D01*
X1339871Y265375D01*
X1339938Y264708D01*
X1339871Y264041D01*
X1339604Y263575D01*
X1339271Y263175D01*
X1338871Y262908D01*
X1338338Y262708D01*
X1337004D01*
G01X1342138D02*
Y265375D01*
G01Y264841D02*
X1342471Y265108D01*
X1342804Y265308D01*
X1343271Y265375D01*
X1343604Y265308D01*
X1344004Y265108D01*
G01X1347671Y265375D02*
Y262708D01*
G01Y266441D02*
X1347538Y266508D01*
Y266641D01*
X1347671Y266708D01*
X1347804Y266641D01*
Y266508D01*
X1347671Y266441D01*
G01X1352271Y262708D02*
Y266708D01*
G01X1356871Y262708D02*
Y266708D01*
G01X1365671Y262708D02*
Y266108D01*
X1365804Y266441D01*
X1366071Y266641D01*
X1366471Y266708D01*
X1366871Y266575D01*
X1367071Y266241D01*
G01X1366271Y265108D02*
X1364938D01*
G01X1369671Y264508D02*
X1371804D01*
X1371604Y264975D01*
X1371271Y265241D01*
X1370804Y265375D01*
X1370338Y265308D01*
X1369938Y265108D01*
X1369671Y264641D01*
X1369538Y264241D01*
Y263841D01*
X1369671Y263441D01*
X1370004Y263041D01*
X1370404Y262775D01*
X1370871Y262708D01*
X1371338Y262841D01*
X1371804Y263241D01*
G01X1376471Y262708D02*
Y265375D01*
G01Y264908D02*
X1376204Y265175D01*
X1375804Y265308D01*
X1375338Y265375D01*
X1374871Y265241D01*
X1374471Y264975D01*
X1374204Y264575D01*
X1374071Y264041D01*
X1374204Y263508D01*
X1374471Y263108D01*
X1374871Y262841D01*
X1375338Y262708D01*
X1375804Y262775D01*
X1376204Y262975D01*
X1376471Y263241D01*
G01X1379871Y266708D02*
Y262708D01*
G01X1378938Y265375D02*
X1380804D01*
G01X1383338D02*
Y263508D01*
X1383604Y263041D01*
X1384004Y262775D01*
X1384471Y262708D01*
X1384938Y262775D01*
X1385338Y263041D01*
X1385604Y263508D01*
G01Y262708D02*
Y265375D01*
G01X1388138Y262708D02*
Y265375D01*
G01Y264841D02*
X1388471Y265108D01*
X1388804Y265308D01*
X1389271Y265375D01*
X1389604Y265308D01*
X1390004Y265108D01*
G01X1392671Y264508D02*
X1394804D01*
X1394604Y264975D01*
X1394271Y265241D01*
X1393804Y265375D01*
X1393338Y265308D01*
X1392938Y265108D01*
X1392671Y264641D01*
X1392538Y264241D01*
Y263841D01*
X1392671Y263441D01*
X1393004Y263041D01*
X1393404Y262775D01*
X1393871Y262708D01*
X1394338Y262841D01*
X1394804Y263241D01*
G01X1311851Y277843D02*
G03X1318775Y264712I37663J11469D01*
G01X1311850Y277843D02*
G03X1318776Y264712I37661J11473D01*
G01X1311851Y277843D02*
G03X1291890I-9980J-3040D01*
G01X1284965Y264712D02*
G03X1291890Y277843I-30737J24602D01*
G01X1311850D02*
G03X1291890I-9980J-3040D01*
G01X1284965Y264712D02*
G03X1291890Y277843I-30737J24602D01*
G01X1284965Y264712D02*
G03X1318775I16905J-13531D01*
G01X1284965D02*
G03X1318776I16906J-13531D01*
G01X1337004Y715465D02*
Y719465D01*
X1338338D01*
X1338871Y719265D01*
X1339271Y718998D01*
X1339604Y718598D01*
X1339871Y718132D01*
X1339938Y717465D01*
X1339871Y716798D01*
X1339604Y716332D01*
X1339271Y715932D01*
X1338871Y715665D01*
X1338338Y715465D01*
X1337004D01*
G01X1342138D02*
Y718132D01*
G01Y717598D02*
X1342471Y717865D01*
X1342804Y718065D01*
X1343271Y718132D01*
X1343604Y718065D01*
X1344004Y717865D01*
G01X1347671Y718132D02*
Y715465D01*
G01Y719198D02*
X1347538Y719265D01*
Y719398D01*
X1347671Y719465D01*
X1347804Y719398D01*
Y719265D01*
X1347671Y719198D01*
G01X1352271Y715465D02*
Y719465D01*
G01X1356871Y715465D02*
Y719465D01*
G01X1365671Y715465D02*
Y718865D01*
X1365804Y719198D01*
X1366071Y719398D01*
X1366471Y719465D01*
X1366871Y719332D01*
X1367071Y718998D01*
G01X1366271Y717865D02*
X1364938D01*
G01X1369671Y717265D02*
X1371804D01*
X1371604Y717732D01*
X1371271Y717998D01*
X1370804Y718132D01*
X1370338Y718065D01*
X1369938Y717865D01*
X1369671Y717398D01*
X1369538Y716998D01*
Y716598D01*
X1369671Y716198D01*
X1370004Y715798D01*
X1370404Y715532D01*
X1370871Y715465D01*
X1371338Y715598D01*
X1371804Y715998D01*
G01X1376471Y715465D02*
Y718132D01*
G01Y717665D02*
X1376204Y717932D01*
X1375804Y718065D01*
X1375338Y718132D01*
X1374871Y717998D01*
X1374471Y717732D01*
X1374204Y717332D01*
X1374071Y716798D01*
X1374204Y716265D01*
X1374471Y715865D01*
X1374871Y715598D01*
X1375338Y715465D01*
X1375804Y715532D01*
X1376204Y715732D01*
X1376471Y715998D01*
G01X1379871Y719465D02*
Y715465D01*
G01X1378938Y718132D02*
X1380804D01*
G01X1383338D02*
Y716265D01*
X1383604Y715798D01*
X1384004Y715532D01*
X1384471Y715465D01*
X1384938Y715532D01*
X1385338Y715798D01*
X1385604Y716265D01*
G01Y715465D02*
Y718132D01*
G01X1388138Y715465D02*
Y718132D01*
G01Y717598D02*
X1388471Y717865D01*
X1388804Y718065D01*
X1389271Y718132D01*
X1389604Y718065D01*
X1390004Y717865D01*
G01X1392671Y717265D02*
X1394804D01*
X1394604Y717732D01*
X1394271Y717998D01*
X1393804Y718132D01*
X1393338Y718065D01*
X1392938Y717865D01*
X1392671Y717398D01*
X1392538Y716998D01*
Y716598D01*
X1392671Y716198D01*
X1393004Y715798D01*
X1393404Y715532D01*
X1393871Y715465D01*
X1394338Y715598D01*
X1394804Y715998D01*
G01X1311851Y730599D02*
G03X1318775Y717468I37663J11469D01*
G01X1311850Y730599D02*
G03X1318776Y717468I37661J11473D01*
G01X1311851Y730599D02*
G03X1291890I-9980J-3040D01*
G01X1284965Y717468D02*
G03X1291891Y730599I-30736J24604D01*
G01X1311850D02*
G03X1291890I-9980J-3040D01*
G01X1284965Y717468D02*
G03X1291890Y730599I-30737J24602D01*
G01X1284965Y717468D02*
G03X1318775I16905J-13531D01*
G01X1284965D02*
G03X1318776I16906J-13531D01*
G01X1284965Y1170224D02*
G03X1318775I16905J-13531D01*
G01X1284965D02*
G03X1318776I16906J-13531D01*
G01X1337004Y1168220D02*
Y1172220D01*
X1338338D01*
X1338871Y1172020D01*
X1339271Y1171753D01*
X1339604Y1171353D01*
X1339871Y1170887D01*
X1339938Y1170220D01*
X1339871Y1169553D01*
X1339604Y1169087D01*
X1339271Y1168687D01*
X1338871Y1168420D01*
X1338338Y1168220D01*
X1337004D01*
G01X1342138D02*
Y1170887D01*
G01Y1170353D02*
X1342471Y1170620D01*
X1342804Y1170820D01*
X1343271Y1170887D01*
X1343604Y1170820D01*
X1344004Y1170620D01*
G01X1347671Y1170887D02*
Y1168220D01*
G01Y1171953D02*
X1347538Y1172020D01*
Y1172153D01*
X1347671Y1172220D01*
X1347804Y1172153D01*
Y1172020D01*
X1347671Y1171953D01*
G01X1352271Y1168220D02*
Y1172220D01*
G01X1356871Y1168220D02*
Y1172220D01*
G01X1365671Y1168220D02*
Y1171620D01*
X1365804Y1171953D01*
X1366071Y1172153D01*
X1366471Y1172220D01*
X1366871Y1172087D01*
X1367071Y1171753D01*
G01X1366271Y1170620D02*
X1364938D01*
G01X1369671Y1170020D02*
X1371804D01*
X1371604Y1170487D01*
X1371271Y1170753D01*
X1370804Y1170887D01*
X1370338Y1170820D01*
X1369938Y1170620D01*
X1369671Y1170153D01*
X1369538Y1169753D01*
Y1169353D01*
X1369671Y1168953D01*
X1370004Y1168553D01*
X1370404Y1168287D01*
X1370871Y1168220D01*
X1371338Y1168353D01*
X1371804Y1168753D01*
G01X1376471Y1168220D02*
Y1170887D01*
G01Y1170420D02*
X1376204Y1170687D01*
X1375804Y1170820D01*
X1375338Y1170887D01*
X1374871Y1170753D01*
X1374471Y1170487D01*
X1374204Y1170087D01*
X1374071Y1169553D01*
X1374204Y1169020D01*
X1374471Y1168620D01*
X1374871Y1168353D01*
X1375338Y1168220D01*
X1375804Y1168287D01*
X1376204Y1168487D01*
X1376471Y1168753D01*
G01X1379871Y1172220D02*
Y1168220D01*
G01X1378938Y1170887D02*
X1380804D01*
G01X1383338D02*
Y1169020D01*
X1383604Y1168553D01*
X1384004Y1168287D01*
X1384471Y1168220D01*
X1384938Y1168287D01*
X1385338Y1168553D01*
X1385604Y1169020D01*
G01Y1168220D02*
Y1170887D01*
G01X1388138Y1168220D02*
Y1170887D01*
G01Y1170353D02*
X1388471Y1170620D01*
X1388804Y1170820D01*
X1389271Y1170887D01*
X1389604Y1170820D01*
X1390004Y1170620D01*
G01X1392671Y1170020D02*
X1394804D01*
X1394604Y1170487D01*
X1394271Y1170753D01*
X1393804Y1170887D01*
X1393338Y1170820D01*
X1392938Y1170620D01*
X1392671Y1170153D01*
X1392538Y1169753D01*
Y1169353D01*
X1392671Y1168953D01*
X1393004Y1168553D01*
X1393404Y1168287D01*
X1393871Y1168220D01*
X1394338Y1168353D01*
X1394804Y1168753D01*
G01X1311851Y1183355D02*
G03X1318775Y1170224I37663J11469D01*
G01X1311850Y1183355D02*
G03X1318776Y1170224I37661J11473D01*
G01X1311851Y1183355D02*
G03X1291890I-9980J-3040D01*
G01X1311850D02*
G03X1291890I-9980J-3040D01*
G01X1284965Y1170224D02*
G03X1291890Y1183355I-30737J24602D01*
G01X1284965Y1170224D02*
G03X1291890Y1183355I-30737J24602D01*
G01X1248622Y1519685D02*
G03X1244685Y1515748I0J-3937D01*
G01X1427953Y1519685D02*
X1248622D01*
G01D02*
G03X1244685Y1515748I0J-3937D01*
G01X1427953Y1519685D02*
X1248622D01*
G01X1244685Y1515748D02*
Y1509055D01*
G01Y1515748D02*
Y1509055D01*
G01X1343467Y220551D02*
Y224551D01*
X1341000Y221684D01*
X1344334D01*
G01X1345800Y221351D02*
X1346200Y220884D01*
X1346734Y220618D01*
X1347334Y220551D01*
X1347867Y220618D01*
X1348400Y220951D01*
X1348734Y221351D01*
X1348800Y221751D01*
X1348667Y222218D01*
X1348200Y222551D01*
X1347734Y222684D01*
X1347134D01*
G01X1347734D02*
X1348134Y222884D01*
X1348467Y223218D01*
X1348600Y223618D01*
X1348467Y224018D01*
X1348134Y224351D01*
X1347534Y224551D01*
X1346934Y224484D01*
X1346334Y224218D01*
G01X1350400Y221351D02*
X1350800Y220884D01*
X1351334Y220618D01*
X1351934Y220551D01*
X1352467Y220618D01*
X1353000Y220951D01*
X1353334Y221351D01*
X1353400Y221751D01*
X1353267Y222218D01*
X1352800Y222551D01*
X1352334Y222684D01*
X1351734D01*
G01X1352334D02*
X1352734Y222884D01*
X1353067Y223218D01*
X1353200Y223618D01*
X1353067Y224018D01*
X1352734Y224351D01*
X1352134Y224551D01*
X1351534Y224484D01*
X1350934Y224218D01*
G01X1356467Y220418D02*
X1356334Y220484D01*
Y220618D01*
X1356467Y220684D01*
X1356600Y220618D01*
Y220484D01*
X1356467Y220418D01*
G01X1361067Y224551D02*
X1360534Y224418D01*
X1360134Y224084D01*
X1359867Y223684D01*
X1359667Y223151D01*
X1359600Y222551D01*
X1359667Y221951D01*
X1359867Y221418D01*
X1360134Y221018D01*
X1360534Y220684D01*
X1361067Y220551D01*
X1361600Y220684D01*
X1362000Y221018D01*
X1362267Y221418D01*
X1362467Y221951D01*
X1362534Y222551D01*
X1362467Y223151D01*
X1362267Y223684D01*
X1362000Y224084D01*
X1361600Y224418D01*
X1361067Y224551D01*
G01X1365667Y220551D02*
X1366134Y220618D01*
X1366667Y220818D01*
X1367000Y221151D01*
X1367134Y221618D01*
X1367000Y222084D01*
X1366600Y222484D01*
X1366000Y222684D01*
X1365334D01*
X1364934Y222818D01*
X1364600Y223151D01*
X1364467Y223618D01*
X1364667Y224084D01*
X1365134Y224418D01*
X1365667Y224551D01*
X1366200Y224418D01*
X1366667Y224084D01*
X1366867Y223618D01*
X1366734Y223151D01*
X1366400Y222818D01*
X1366000Y222684D01*
X1365334D01*
X1364734Y222484D01*
X1364334Y222084D01*
X1364200Y221618D01*
X1364334Y221151D01*
X1364667Y220818D01*
X1365200Y220618D01*
X1365667Y220551D01*
G01X1343559Y304875D02*
X1343959Y305275D01*
X1344426Y305475D01*
X1344959Y305542D01*
X1345626Y305409D01*
X1346093Y305075D01*
X1346226Y304675D01*
X1346159Y304275D01*
X1345893Y303942D01*
X1344559Y303275D01*
X1343959Y302809D01*
X1343559Y302142D01*
X1343426Y301542D01*
X1346226D01*
G01X1349426Y305542D02*
X1348893Y305409D01*
X1348493Y305075D01*
X1348226Y304675D01*
X1348026Y304142D01*
X1347959Y303542D01*
X1348026Y302942D01*
X1348226Y302409D01*
X1348493Y302009D01*
X1348893Y301675D01*
X1349426Y301542D01*
X1349959Y301675D01*
X1350359Y302009D01*
X1350626Y302409D01*
X1350826Y302942D01*
X1350893Y303542D01*
X1350826Y304142D01*
X1350626Y304675D01*
X1350359Y305075D01*
X1349959Y305409D01*
X1349426Y305542D01*
G01X1354026Y301542D02*
X1354493Y301609D01*
X1355026Y301809D01*
X1355359Y302142D01*
X1355493Y302609D01*
X1355359Y303075D01*
X1354959Y303475D01*
X1354359Y303675D01*
X1353693D01*
X1353293Y303809D01*
X1352959Y304142D01*
X1352826Y304609D01*
X1353026Y305075D01*
X1353493Y305409D01*
X1354026Y305542D01*
X1354559Y305409D01*
X1355026Y305075D01*
X1355226Y304609D01*
X1355093Y304142D01*
X1354759Y303809D01*
X1354359Y303675D01*
X1353693D01*
X1353093Y303475D01*
X1352693Y303075D01*
X1352559Y302609D01*
X1352693Y302142D01*
X1353026Y301809D01*
X1353559Y301609D01*
X1354026Y301542D01*
G01X1358626Y301409D02*
X1358493Y301475D01*
Y301609D01*
X1358626Y301675D01*
X1358759Y301609D01*
Y301475D01*
X1358626Y301409D01*
G01X1361959Y303209D02*
X1362426Y303675D01*
X1362826Y303942D01*
X1363359Y304075D01*
X1363826Y303942D01*
X1364159Y303675D01*
X1364426Y303275D01*
X1364493Y302809D01*
X1364426Y302409D01*
X1364159Y302009D01*
X1363759Y301675D01*
X1363293Y301542D01*
X1362759Y301675D01*
X1362293Y302075D01*
X1362026Y302675D01*
X1361959Y303342D01*
X1362093Y304209D01*
X1362293Y304675D01*
X1362626Y305142D01*
X1363093Y305475D01*
X1363559Y305542D01*
X1364026Y305409D01*
X1364359Y305075D01*
G01X1366559Y303209D02*
X1367026Y303675D01*
X1367426Y303942D01*
X1367959Y304075D01*
X1368426Y303942D01*
X1368759Y303675D01*
X1369026Y303275D01*
X1369093Y302809D01*
X1369026Y302409D01*
X1368759Y302009D01*
X1368359Y301675D01*
X1367893Y301542D01*
X1367359Y301675D01*
X1366893Y302075D01*
X1366626Y302675D01*
X1366559Y303342D01*
X1366693Y304209D01*
X1366893Y304675D01*
X1367226Y305142D01*
X1367693Y305475D01*
X1368159Y305542D01*
X1368626Y305409D01*
X1368959Y305075D01*
G01X1343467Y673308D02*
Y677308D01*
X1341000Y674441D01*
X1344334D01*
G01X1345800Y674108D02*
X1346200Y673641D01*
X1346734Y673375D01*
X1347334Y673308D01*
X1347867Y673375D01*
X1348400Y673708D01*
X1348734Y674108D01*
X1348800Y674508D01*
X1348667Y674975D01*
X1348200Y675308D01*
X1347734Y675441D01*
X1347134D01*
G01X1347734D02*
X1348134Y675641D01*
X1348467Y675975D01*
X1348600Y676375D01*
X1348467Y676775D01*
X1348134Y677108D01*
X1347534Y677308D01*
X1346934Y677241D01*
X1346334Y676975D01*
G01X1350400Y674108D02*
X1350800Y673641D01*
X1351334Y673375D01*
X1351934Y673308D01*
X1352467Y673375D01*
X1353000Y673708D01*
X1353334Y674108D01*
X1353400Y674508D01*
X1353267Y674975D01*
X1352800Y675308D01*
X1352334Y675441D01*
X1351734D01*
G01X1352334D02*
X1352734Y675641D01*
X1353067Y675975D01*
X1353200Y676375D01*
X1353067Y676775D01*
X1352734Y677108D01*
X1352134Y677308D01*
X1351534Y677241D01*
X1350934Y676975D01*
G01X1356467Y673175D02*
X1356334Y673241D01*
Y673375D01*
X1356467Y673441D01*
X1356600Y673375D01*
Y673241D01*
X1356467Y673175D01*
G01X1361067Y677308D02*
X1360534Y677175D01*
X1360134Y676841D01*
X1359867Y676441D01*
X1359667Y675908D01*
X1359600Y675308D01*
X1359667Y674708D01*
X1359867Y674175D01*
X1360134Y673775D01*
X1360534Y673441D01*
X1361067Y673308D01*
X1361600Y673441D01*
X1362000Y673775D01*
X1362267Y674175D01*
X1362467Y674708D01*
X1362534Y675308D01*
X1362467Y675908D01*
X1362267Y676441D01*
X1362000Y676841D01*
X1361600Y677175D01*
X1361067Y677308D01*
G01X1365667Y673308D02*
X1366134Y673375D01*
X1366667Y673575D01*
X1367000Y673908D01*
X1367134Y674375D01*
X1367000Y674841D01*
X1366600Y675241D01*
X1366000Y675441D01*
X1365334D01*
X1364934Y675575D01*
X1364600Y675908D01*
X1364467Y676375D01*
X1364667Y676841D01*
X1365134Y677175D01*
X1365667Y677308D01*
X1366200Y677175D01*
X1366667Y676841D01*
X1366867Y676375D01*
X1366734Y675908D01*
X1366400Y675575D01*
X1366000Y675441D01*
X1365334D01*
X1364734Y675241D01*
X1364334Y674841D01*
X1364200Y674375D01*
X1364334Y673908D01*
X1364667Y673575D01*
X1365200Y673375D01*
X1365667Y673308D01*
G01X1343559Y757632D02*
X1343959Y758032D01*
X1344426Y758232D01*
X1344959Y758299D01*
X1345626Y758166D01*
X1346093Y757832D01*
X1346226Y757432D01*
X1346159Y757032D01*
X1345893Y756699D01*
X1344559Y756032D01*
X1343959Y755566D01*
X1343559Y754899D01*
X1343426Y754299D01*
X1346226D01*
G01X1349426Y758299D02*
X1348893Y758166D01*
X1348493Y757832D01*
X1348226Y757432D01*
X1348026Y756899D01*
X1347959Y756299D01*
X1348026Y755699D01*
X1348226Y755166D01*
X1348493Y754766D01*
X1348893Y754432D01*
X1349426Y754299D01*
X1349959Y754432D01*
X1350359Y754766D01*
X1350626Y755166D01*
X1350826Y755699D01*
X1350893Y756299D01*
X1350826Y756899D01*
X1350626Y757432D01*
X1350359Y757832D01*
X1349959Y758166D01*
X1349426Y758299D01*
G01X1354026Y754299D02*
X1354493Y754366D01*
X1355026Y754566D01*
X1355359Y754899D01*
X1355493Y755366D01*
X1355359Y755832D01*
X1354959Y756232D01*
X1354359Y756432D01*
X1353693D01*
X1353293Y756566D01*
X1352959Y756899D01*
X1352826Y757366D01*
X1353026Y757832D01*
X1353493Y758166D01*
X1354026Y758299D01*
X1354559Y758166D01*
X1355026Y757832D01*
X1355226Y757366D01*
X1355093Y756899D01*
X1354759Y756566D01*
X1354359Y756432D01*
X1353693D01*
X1353093Y756232D01*
X1352693Y755832D01*
X1352559Y755366D01*
X1352693Y754899D01*
X1353026Y754566D01*
X1353559Y754366D01*
X1354026Y754299D01*
G01X1358626Y754166D02*
X1358493Y754232D01*
Y754366D01*
X1358626Y754432D01*
X1358759Y754366D01*
Y754232D01*
X1358626Y754166D01*
G01X1361959Y755966D02*
X1362426Y756432D01*
X1362826Y756699D01*
X1363359Y756832D01*
X1363826Y756699D01*
X1364159Y756432D01*
X1364426Y756032D01*
X1364493Y755566D01*
X1364426Y755166D01*
X1364159Y754766D01*
X1363759Y754432D01*
X1363293Y754299D01*
X1362759Y754432D01*
X1362293Y754832D01*
X1362026Y755432D01*
X1361959Y756099D01*
X1362093Y756966D01*
X1362293Y757432D01*
X1362626Y757899D01*
X1363093Y758232D01*
X1363559Y758299D01*
X1364026Y758166D01*
X1364359Y757832D01*
G01X1366559Y755966D02*
X1367026Y756432D01*
X1367426Y756699D01*
X1367959Y756832D01*
X1368426Y756699D01*
X1368759Y756432D01*
X1369026Y756032D01*
X1369093Y755566D01*
X1369026Y755166D01*
X1368759Y754766D01*
X1368359Y754432D01*
X1367893Y754299D01*
X1367359Y754432D01*
X1366893Y754832D01*
X1366626Y755432D01*
X1366559Y756099D01*
X1366693Y756966D01*
X1366893Y757432D01*
X1367226Y757899D01*
X1367693Y758232D01*
X1368159Y758299D01*
X1368626Y758166D01*
X1368959Y757832D01*
G01X1343467Y1126063D02*
Y1130063D01*
X1341000Y1127196D01*
X1344334D01*
G01X1345800Y1126863D02*
X1346200Y1126396D01*
X1346734Y1126130D01*
X1347334Y1126063D01*
X1347867Y1126130D01*
X1348400Y1126463D01*
X1348734Y1126863D01*
X1348800Y1127263D01*
X1348667Y1127730D01*
X1348200Y1128063D01*
X1347734Y1128196D01*
X1347134D01*
G01X1347734D02*
X1348134Y1128396D01*
X1348467Y1128730D01*
X1348600Y1129130D01*
X1348467Y1129530D01*
X1348134Y1129863D01*
X1347534Y1130063D01*
X1346934Y1129996D01*
X1346334Y1129730D01*
G01X1350400Y1126863D02*
X1350800Y1126396D01*
X1351334Y1126130D01*
X1351934Y1126063D01*
X1352467Y1126130D01*
X1353000Y1126463D01*
X1353334Y1126863D01*
X1353400Y1127263D01*
X1353267Y1127730D01*
X1352800Y1128063D01*
X1352334Y1128196D01*
X1351734D01*
G01X1352334D02*
X1352734Y1128396D01*
X1353067Y1128730D01*
X1353200Y1129130D01*
X1353067Y1129530D01*
X1352734Y1129863D01*
X1352134Y1130063D01*
X1351534Y1129996D01*
X1350934Y1129730D01*
G01X1356467Y1125930D02*
X1356334Y1125996D01*
Y1126130D01*
X1356467Y1126196D01*
X1356600Y1126130D01*
Y1125996D01*
X1356467Y1125930D01*
G01X1361067Y1130063D02*
X1360534Y1129930D01*
X1360134Y1129596D01*
X1359867Y1129196D01*
X1359667Y1128663D01*
X1359600Y1128063D01*
X1359667Y1127463D01*
X1359867Y1126930D01*
X1360134Y1126530D01*
X1360534Y1126196D01*
X1361067Y1126063D01*
X1361600Y1126196D01*
X1362000Y1126530D01*
X1362267Y1126930D01*
X1362467Y1127463D01*
X1362534Y1128063D01*
X1362467Y1128663D01*
X1362267Y1129196D01*
X1362000Y1129596D01*
X1361600Y1129930D01*
X1361067Y1130063D01*
G01X1365667Y1126063D02*
X1366134Y1126130D01*
X1366667Y1126330D01*
X1367000Y1126663D01*
X1367134Y1127130D01*
X1367000Y1127596D01*
X1366600Y1127996D01*
X1366000Y1128196D01*
X1365334D01*
X1364934Y1128330D01*
X1364600Y1128663D01*
X1364467Y1129130D01*
X1364667Y1129596D01*
X1365134Y1129930D01*
X1365667Y1130063D01*
X1366200Y1129930D01*
X1366667Y1129596D01*
X1366867Y1129130D01*
X1366734Y1128663D01*
X1366400Y1128330D01*
X1366000Y1128196D01*
X1365334D01*
X1364734Y1127996D01*
X1364334Y1127596D01*
X1364200Y1127130D01*
X1364334Y1126663D01*
X1364667Y1126330D01*
X1365200Y1126130D01*
X1365667Y1126063D01*
G01X1343559Y1210387D02*
X1343959Y1210787D01*
X1344426Y1210987D01*
X1344959Y1211054D01*
X1345626Y1210921D01*
X1346093Y1210587D01*
X1346226Y1210187D01*
X1346159Y1209787D01*
X1345893Y1209454D01*
X1344559Y1208787D01*
X1343959Y1208321D01*
X1343559Y1207654D01*
X1343426Y1207054D01*
X1346226D01*
G01X1349426Y1211054D02*
X1348893Y1210921D01*
X1348493Y1210587D01*
X1348226Y1210187D01*
X1348026Y1209654D01*
X1347959Y1209054D01*
X1348026Y1208454D01*
X1348226Y1207921D01*
X1348493Y1207521D01*
X1348893Y1207187D01*
X1349426Y1207054D01*
X1349959Y1207187D01*
X1350359Y1207521D01*
X1350626Y1207921D01*
X1350826Y1208454D01*
X1350893Y1209054D01*
X1350826Y1209654D01*
X1350626Y1210187D01*
X1350359Y1210587D01*
X1349959Y1210921D01*
X1349426Y1211054D01*
G01X1354026Y1207054D02*
X1354493Y1207121D01*
X1355026Y1207321D01*
X1355359Y1207654D01*
X1355493Y1208121D01*
X1355359Y1208587D01*
X1354959Y1208987D01*
X1354359Y1209187D01*
X1353693D01*
X1353293Y1209321D01*
X1352959Y1209654D01*
X1352826Y1210121D01*
X1353026Y1210587D01*
X1353493Y1210921D01*
X1354026Y1211054D01*
X1354559Y1210921D01*
X1355026Y1210587D01*
X1355226Y1210121D01*
X1355093Y1209654D01*
X1354759Y1209321D01*
X1354359Y1209187D01*
X1353693D01*
X1353093Y1208987D01*
X1352693Y1208587D01*
X1352559Y1208121D01*
X1352693Y1207654D01*
X1353026Y1207321D01*
X1353559Y1207121D01*
X1354026Y1207054D01*
G01X1358626Y1206921D02*
X1358493Y1206987D01*
Y1207121D01*
X1358626Y1207187D01*
X1358759Y1207121D01*
Y1206987D01*
X1358626Y1206921D01*
G01X1361959Y1208721D02*
X1362426Y1209187D01*
X1362826Y1209454D01*
X1363359Y1209587D01*
X1363826Y1209454D01*
X1364159Y1209187D01*
X1364426Y1208787D01*
X1364493Y1208321D01*
X1364426Y1207921D01*
X1364159Y1207521D01*
X1363759Y1207187D01*
X1363293Y1207054D01*
X1362759Y1207187D01*
X1362293Y1207587D01*
X1362026Y1208187D01*
X1361959Y1208854D01*
X1362093Y1209721D01*
X1362293Y1210187D01*
X1362626Y1210654D01*
X1363093Y1210987D01*
X1363559Y1211054D01*
X1364026Y1210921D01*
X1364359Y1210587D01*
G01X1366559Y1208721D02*
X1367026Y1209187D01*
X1367426Y1209454D01*
X1367959Y1209587D01*
X1368426Y1209454D01*
X1368759Y1209187D01*
X1369026Y1208787D01*
X1369093Y1208321D01*
X1369026Y1207921D01*
X1368759Y1207521D01*
X1368359Y1207187D01*
X1367893Y1207054D01*
X1367359Y1207187D01*
X1366893Y1207587D01*
X1366626Y1208187D01*
X1366559Y1208854D01*
X1366693Y1209721D01*
X1366893Y1210187D01*
X1367226Y1210654D01*
X1367693Y1210987D01*
X1368159Y1211054D01*
X1368626Y1210921D01*
X1368959Y1210587D01*
G01X1431890Y1515748D02*
G03X1427953Y1519685I-3937J0D01*
G01X1431890Y1515748D02*
G03X1427953Y1519685I-3937J0D01*
G01X1431890Y1500000D02*
Y1515748D01*
G01Y1500000D02*
G03X1435827Y1496063I3937J0D01*
G01X1431890Y1500000D02*
G03X1435827Y1496063I3937J0D01*
G01X1431890Y1515748D02*
Y1500000D01*
G01X1473464Y253600D02*
X1473864Y253267D01*
X1474331Y253067D01*
X1474931Y253000D01*
X1475531Y253133D01*
X1475998Y253400D01*
X1476331Y253867D01*
X1476398Y254400D01*
X1476264Y254933D01*
X1475931Y255267D01*
X1475464Y255533D01*
X1474998Y255600D01*
X1474531Y255533D01*
X1473931Y255267D01*
X1474131Y257000D01*
X1475931D01*
G01X1478064Y253600D02*
X1478464Y253267D01*
X1478931Y253067D01*
X1479531Y253000D01*
X1480131Y253133D01*
X1480598Y253400D01*
X1480931Y253867D01*
X1480998Y254400D01*
X1480864Y254933D01*
X1480531Y255267D01*
X1480064Y255533D01*
X1479598Y255600D01*
X1479131Y255533D01*
X1478531Y255267D01*
X1478731Y257000D01*
X1480531D01*
G01X1483998Y253000D02*
X1484131Y253867D01*
X1484331Y254600D01*
X1484598Y255267D01*
X1484931Y256000D01*
X1485464Y257000D01*
X1482798D01*
G01X1488731Y252867D02*
X1488598Y252933D01*
Y253067D01*
X1488731Y253133D01*
X1488864Y253067D01*
Y252933D01*
X1488731Y252867D01*
G01X1493331Y257000D02*
X1492798Y256867D01*
X1492398Y256533D01*
X1492131Y256133D01*
X1491931Y255600D01*
X1491864Y255000D01*
X1491931Y254400D01*
X1492131Y253867D01*
X1492398Y253467D01*
X1492798Y253133D01*
X1493331Y253000D01*
X1493864Y253133D01*
X1494264Y253467D01*
X1494531Y253867D01*
X1494731Y254400D01*
X1494798Y255000D01*
X1494731Y255600D01*
X1494531Y256133D01*
X1494264Y256533D01*
X1493864Y256867D01*
X1493331Y257000D01*
G01X1496798Y253467D02*
X1497264Y253133D01*
X1497798Y253000D01*
X1498331Y253133D01*
X1498798Y253533D01*
X1499131Y254133D01*
X1499264Y254733D01*
Y255467D01*
X1499131Y256067D01*
X1498798Y256600D01*
X1498398Y256867D01*
X1497931Y257000D01*
X1497398Y256867D01*
X1496998Y256600D01*
X1496731Y256200D01*
X1496598Y255667D01*
X1496731Y255200D01*
X1497064Y254733D01*
X1497464Y254467D01*
X1497931Y254400D01*
X1498464Y254533D01*
X1498864Y254867D01*
X1499264Y255467D01*
G01X1490803Y264146D02*
X1491203Y264546D01*
X1491670Y264746D01*
X1492203Y264813D01*
X1492870Y264680D01*
X1493337Y264346D01*
X1493470Y263946D01*
X1493403Y263546D01*
X1493137Y263213D01*
X1491803Y262546D01*
X1491203Y262080D01*
X1490803Y261413D01*
X1490670Y260813D01*
X1493470D01*
G01X1495203Y261613D02*
X1495603Y261146D01*
X1496137Y260880D01*
X1496737Y260813D01*
X1497270Y260880D01*
X1497803Y261213D01*
X1498137Y261613D01*
X1498203Y262013D01*
X1498070Y262480D01*
X1497603Y262813D01*
X1497137Y262946D01*
X1496537D01*
G01X1497137D02*
X1497537Y263146D01*
X1497870Y263480D01*
X1498003Y263880D01*
X1497870Y264280D01*
X1497537Y264613D01*
X1496937Y264813D01*
X1496337Y264746D01*
X1495737Y264480D01*
G01X1500003Y262480D02*
X1500470Y262946D01*
X1500870Y263213D01*
X1501403Y263346D01*
X1501870Y263213D01*
X1502203Y262946D01*
X1502470Y262546D01*
X1502537Y262080D01*
X1502470Y261680D01*
X1502203Y261280D01*
X1501803Y260946D01*
X1501337Y260813D01*
X1500803Y260946D01*
X1500337Y261346D01*
X1500070Y261946D01*
X1500003Y262613D01*
X1500137Y263480D01*
X1500337Y263946D01*
X1500670Y264413D01*
X1501137Y264746D01*
X1501603Y264813D01*
X1502070Y264680D01*
X1502403Y264346D01*
G01X1505870Y260680D02*
X1505737Y260746D01*
Y260880D01*
X1505870Y260946D01*
X1506003Y260880D01*
Y260746D01*
X1505870Y260680D01*
G01X1509203Y264146D02*
X1509603Y264546D01*
X1510070Y264746D01*
X1510603Y264813D01*
X1511270Y264680D01*
X1511737Y264346D01*
X1511870Y263946D01*
X1511803Y263546D01*
X1511537Y263213D01*
X1510203Y262546D01*
X1509603Y262080D01*
X1509203Y261413D01*
X1509070Y260813D01*
X1511870D01*
G01X1513803Y264146D02*
X1514203Y264546D01*
X1514670Y264746D01*
X1515203Y264813D01*
X1515870Y264680D01*
X1516337Y264346D01*
X1516470Y263946D01*
X1516403Y263546D01*
X1516137Y263213D01*
X1514803Y262546D01*
X1514203Y262080D01*
X1513803Y261413D01*
X1513670Y260813D01*
X1516470D01*
G01X1532996Y264712D02*
G03X1566807I16906J-13531D01*
G01X1532996D02*
G03X1566807I16906J-13531D01*
G01X1473464Y706356D02*
X1473864Y706023D01*
X1474331Y705823D01*
X1474931Y705756D01*
X1475531Y705889D01*
X1475998Y706156D01*
X1476331Y706623D01*
X1476398Y707156D01*
X1476264Y707689D01*
X1475931Y708023D01*
X1475464Y708289D01*
X1474998Y708356D01*
X1474531Y708289D01*
X1473931Y708023D01*
X1474131Y709756D01*
X1475931D01*
G01X1478064Y706356D02*
X1478464Y706023D01*
X1478931Y705823D01*
X1479531Y705756D01*
X1480131Y705889D01*
X1480598Y706156D01*
X1480931Y706623D01*
X1480998Y707156D01*
X1480864Y707689D01*
X1480531Y708023D01*
X1480064Y708289D01*
X1479598Y708356D01*
X1479131Y708289D01*
X1478531Y708023D01*
X1478731Y709756D01*
X1480531D01*
G01X1483998Y705756D02*
X1484131Y706623D01*
X1484331Y707356D01*
X1484598Y708023D01*
X1484931Y708756D01*
X1485464Y709756D01*
X1482798D01*
G01X1488731Y705623D02*
X1488598Y705689D01*
Y705823D01*
X1488731Y705889D01*
X1488864Y705823D01*
Y705689D01*
X1488731Y705623D01*
G01X1493331Y709756D02*
X1492798Y709623D01*
X1492398Y709289D01*
X1492131Y708889D01*
X1491931Y708356D01*
X1491864Y707756D01*
X1491931Y707156D01*
X1492131Y706623D01*
X1492398Y706223D01*
X1492798Y705889D01*
X1493331Y705756D01*
X1493864Y705889D01*
X1494264Y706223D01*
X1494531Y706623D01*
X1494731Y707156D01*
X1494798Y707756D01*
X1494731Y708356D01*
X1494531Y708889D01*
X1494264Y709289D01*
X1493864Y709623D01*
X1493331Y709756D01*
G01X1496798Y706223D02*
X1497264Y705889D01*
X1497798Y705756D01*
X1498331Y705889D01*
X1498798Y706289D01*
X1499131Y706889D01*
X1499264Y707489D01*
Y708223D01*
X1499131Y708823D01*
X1498798Y709356D01*
X1498398Y709623D01*
X1497931Y709756D01*
X1497398Y709623D01*
X1496998Y709356D01*
X1496731Y708956D01*
X1496598Y708423D01*
X1496731Y707956D01*
X1497064Y707489D01*
X1497464Y707223D01*
X1497931Y707156D01*
X1498464Y707289D01*
X1498864Y707623D01*
X1499264Y708223D01*
G01X1490803Y716902D02*
X1491203Y717302D01*
X1491670Y717502D01*
X1492203Y717569D01*
X1492870Y717436D01*
X1493337Y717102D01*
X1493470Y716702D01*
X1493403Y716302D01*
X1493137Y715969D01*
X1491803Y715302D01*
X1491203Y714836D01*
X1490803Y714169D01*
X1490670Y713569D01*
X1493470D01*
G01X1495203Y714369D02*
X1495603Y713902D01*
X1496137Y713636D01*
X1496737Y713569D01*
X1497270Y713636D01*
X1497803Y713969D01*
X1498137Y714369D01*
X1498203Y714769D01*
X1498070Y715236D01*
X1497603Y715569D01*
X1497137Y715702D01*
X1496537D01*
G01X1497137D02*
X1497537Y715902D01*
X1497870Y716236D01*
X1498003Y716636D01*
X1497870Y717036D01*
X1497537Y717369D01*
X1496937Y717569D01*
X1496337Y717502D01*
X1495737Y717236D01*
G01X1500003Y715236D02*
X1500470Y715702D01*
X1500870Y715969D01*
X1501403Y716102D01*
X1501870Y715969D01*
X1502203Y715702D01*
X1502470Y715302D01*
X1502537Y714836D01*
X1502470Y714436D01*
X1502203Y714036D01*
X1501803Y713702D01*
X1501337Y713569D01*
X1500803Y713702D01*
X1500337Y714102D01*
X1500070Y714702D01*
X1500003Y715369D01*
X1500137Y716236D01*
X1500337Y716702D01*
X1500670Y717169D01*
X1501137Y717502D01*
X1501603Y717569D01*
X1502070Y717436D01*
X1502403Y717102D01*
G01X1505870Y713436D02*
X1505737Y713502D01*
Y713636D01*
X1505870Y713702D01*
X1506003Y713636D01*
Y713502D01*
X1505870Y713436D01*
G01X1509203Y716902D02*
X1509603Y717302D01*
X1510070Y717502D01*
X1510603Y717569D01*
X1511270Y717436D01*
X1511737Y717102D01*
X1511870Y716702D01*
X1511803Y716302D01*
X1511537Y715969D01*
X1510203Y715302D01*
X1509603Y714836D01*
X1509203Y714169D01*
X1509070Y713569D01*
X1511870D01*
G01X1513803Y716902D02*
X1514203Y717302D01*
X1514670Y717502D01*
X1515203Y717569D01*
X1515870Y717436D01*
X1516337Y717102D01*
X1516470Y716702D01*
X1516403Y716302D01*
X1516137Y715969D01*
X1514803Y715302D01*
X1514203Y714836D01*
X1513803Y714169D01*
X1513670Y713569D01*
X1516470D01*
G01X1532996Y717468D02*
G03X1566807I16906J-13531D01*
G01X1532996D02*
G03X1566807I16906J-13531D01*
G01X1473464Y1159111D02*
X1473864Y1158778D01*
X1474331Y1158578D01*
X1474931Y1158511D01*
X1475531Y1158644D01*
X1475998Y1158911D01*
X1476331Y1159378D01*
X1476398Y1159911D01*
X1476264Y1160444D01*
X1475931Y1160778D01*
X1475464Y1161044D01*
X1474998Y1161111D01*
X1474531Y1161044D01*
X1473931Y1160778D01*
X1474131Y1162511D01*
X1475931D01*
G01X1478064Y1159111D02*
X1478464Y1158778D01*
X1478931Y1158578D01*
X1479531Y1158511D01*
X1480131Y1158644D01*
X1480598Y1158911D01*
X1480931Y1159378D01*
X1480998Y1159911D01*
X1480864Y1160444D01*
X1480531Y1160778D01*
X1480064Y1161044D01*
X1479598Y1161111D01*
X1479131Y1161044D01*
X1478531Y1160778D01*
X1478731Y1162511D01*
X1480531D01*
G01X1483998Y1158511D02*
X1484131Y1159378D01*
X1484331Y1160111D01*
X1484598Y1160778D01*
X1484931Y1161511D01*
X1485464Y1162511D01*
X1482798D01*
G01X1488731Y1158378D02*
X1488598Y1158444D01*
Y1158578D01*
X1488731Y1158644D01*
X1488864Y1158578D01*
Y1158444D01*
X1488731Y1158378D01*
G01X1493331Y1162511D02*
X1492798Y1162378D01*
X1492398Y1162044D01*
X1492131Y1161644D01*
X1491931Y1161111D01*
X1491864Y1160511D01*
X1491931Y1159911D01*
X1492131Y1159378D01*
X1492398Y1158978D01*
X1492798Y1158644D01*
X1493331Y1158511D01*
X1493864Y1158644D01*
X1494264Y1158978D01*
X1494531Y1159378D01*
X1494731Y1159911D01*
X1494798Y1160511D01*
X1494731Y1161111D01*
X1494531Y1161644D01*
X1494264Y1162044D01*
X1493864Y1162378D01*
X1493331Y1162511D01*
G01X1496798Y1158978D02*
X1497264Y1158644D01*
X1497798Y1158511D01*
X1498331Y1158644D01*
X1498798Y1159044D01*
X1499131Y1159644D01*
X1499264Y1160244D01*
Y1160978D01*
X1499131Y1161578D01*
X1498798Y1162111D01*
X1498398Y1162378D01*
X1497931Y1162511D01*
X1497398Y1162378D01*
X1496998Y1162111D01*
X1496731Y1161711D01*
X1496598Y1161178D01*
X1496731Y1160711D01*
X1497064Y1160244D01*
X1497464Y1159978D01*
X1497931Y1159911D01*
X1498464Y1160044D01*
X1498864Y1160378D01*
X1499264Y1160978D01*
G01X1490803Y1169657D02*
X1491203Y1170057D01*
X1491670Y1170257D01*
X1492203Y1170324D01*
X1492870Y1170191D01*
X1493337Y1169857D01*
X1493470Y1169457D01*
X1493403Y1169057D01*
X1493137Y1168724D01*
X1491803Y1168057D01*
X1491203Y1167591D01*
X1490803Y1166924D01*
X1490670Y1166324D01*
X1493470D01*
G01X1495203Y1167124D02*
X1495603Y1166657D01*
X1496137Y1166391D01*
X1496737Y1166324D01*
X1497270Y1166391D01*
X1497803Y1166724D01*
X1498137Y1167124D01*
X1498203Y1167524D01*
X1498070Y1167991D01*
X1497603Y1168324D01*
X1497137Y1168457D01*
X1496537D01*
G01X1497137D02*
X1497537Y1168657D01*
X1497870Y1168991D01*
X1498003Y1169391D01*
X1497870Y1169791D01*
X1497537Y1170124D01*
X1496937Y1170324D01*
X1496337Y1170257D01*
X1495737Y1169991D01*
G01X1500003Y1167991D02*
X1500470Y1168457D01*
X1500870Y1168724D01*
X1501403Y1168857D01*
X1501870Y1168724D01*
X1502203Y1168457D01*
X1502470Y1168057D01*
X1502537Y1167591D01*
X1502470Y1167191D01*
X1502203Y1166791D01*
X1501803Y1166457D01*
X1501337Y1166324D01*
X1500803Y1166457D01*
X1500337Y1166857D01*
X1500070Y1167457D01*
X1500003Y1168124D01*
X1500137Y1168991D01*
X1500337Y1169457D01*
X1500670Y1169924D01*
X1501137Y1170257D01*
X1501603Y1170324D01*
X1502070Y1170191D01*
X1502403Y1169857D01*
G01X1505870Y1166191D02*
X1505737Y1166257D01*
Y1166391D01*
X1505870Y1166457D01*
X1506003Y1166391D01*
Y1166257D01*
X1505870Y1166191D01*
G01X1509203Y1169657D02*
X1509603Y1170057D01*
X1510070Y1170257D01*
X1510603Y1170324D01*
X1511270Y1170191D01*
X1511737Y1169857D01*
X1511870Y1169457D01*
X1511803Y1169057D01*
X1511537Y1168724D01*
X1510203Y1168057D01*
X1509603Y1167591D01*
X1509203Y1166924D01*
X1509070Y1166324D01*
X1511870D01*
G01X1513803Y1169657D02*
X1514203Y1170057D01*
X1514670Y1170257D01*
X1515203Y1170324D01*
X1515870Y1170191D01*
X1516337Y1169857D01*
X1516470Y1169457D01*
X1516403Y1169057D01*
X1516137Y1168724D01*
X1514803Y1168057D01*
X1514203Y1167591D01*
X1513803Y1166924D01*
X1513670Y1166324D01*
X1516470D01*
G01X1532996Y1170224D02*
G03X1566807I16906J-13531D01*
G01X1532996D02*
G03X1566807I16906J-13531D01*
G01X1469685Y1503937D02*
G03Y1496063I0J-3937D01*
G01X1451575D02*
G03Y1503937I0J3937D01*
G01X1606693D02*
X1469685D01*
G01X1606693D02*
X1469685D01*
G01D02*
G03Y1496063I0J-3937D01*
G01X1451575D02*
G03Y1503937I0J3937D01*
G01X1443701Y1519685D02*
G03X1439764Y1515748I0J-3937D01*
G01X1443701Y1519685D02*
X1632677D01*
G01X1443701D02*
G03X1439764Y1515748I0J-3937D01*
G01X1443701Y1519685D02*
X1632677D01*
G01X1451575Y1503937D02*
X1439764D01*
G01Y1515748D02*
Y1503937D01*
G01X1451575D02*
X1439764D01*
G01X1640551Y1496063D02*
X1435827D01*
G01X1439764Y1515748D02*
Y1503937D01*
G01X1640551Y1496063D02*
X1435827D01*
G01X1591498Y220552D02*
Y224552D01*
X1589031Y221685D01*
X1592365D01*
G01X1593831Y221352D02*
X1594231Y220885D01*
X1594765Y220619D01*
X1595365Y220552D01*
X1595898Y220619D01*
X1596431Y220952D01*
X1596765Y221352D01*
X1596831Y221752D01*
X1596698Y222219D01*
X1596231Y222552D01*
X1595765Y222685D01*
X1595165D01*
G01X1595765D02*
X1596165Y222885D01*
X1596498Y223219D01*
X1596631Y223619D01*
X1596498Y224019D01*
X1596165Y224352D01*
X1595565Y224552D01*
X1594965Y224485D01*
X1594365Y224219D01*
G01X1598431Y221352D02*
X1598831Y220885D01*
X1599365Y220619D01*
X1599965Y220552D01*
X1600498Y220619D01*
X1601031Y220952D01*
X1601365Y221352D01*
X1601431Y221752D01*
X1601298Y222219D01*
X1600831Y222552D01*
X1600365Y222685D01*
X1599765D01*
G01X1600365D02*
X1600765Y222885D01*
X1601098Y223219D01*
X1601231Y223619D01*
X1601098Y224019D01*
X1600765Y224352D01*
X1600165Y224552D01*
X1599565Y224485D01*
X1598965Y224219D01*
G01X1604498Y220419D02*
X1604365Y220485D01*
Y220619D01*
X1604498Y220685D01*
X1604631Y220619D01*
Y220485D01*
X1604498Y220419D01*
G01X1609098Y224552D02*
X1608565Y224419D01*
X1608165Y224085D01*
X1607898Y223685D01*
X1607698Y223152D01*
X1607631Y222552D01*
X1607698Y221952D01*
X1607898Y221419D01*
X1608165Y221019D01*
X1608565Y220685D01*
X1609098Y220552D01*
X1609631Y220685D01*
X1610031Y221019D01*
X1610298Y221419D01*
X1610498Y221952D01*
X1610565Y222552D01*
X1610498Y223152D01*
X1610298Y223685D01*
X1610031Y224085D01*
X1609631Y224419D01*
X1609098Y224552D01*
G01X1613698Y220552D02*
X1614165Y220619D01*
X1614698Y220819D01*
X1615031Y221152D01*
X1615165Y221619D01*
X1615031Y222085D01*
X1614631Y222485D01*
X1614031Y222685D01*
X1613365D01*
X1612965Y222819D01*
X1612631Y223152D01*
X1612498Y223619D01*
X1612698Y224085D01*
X1613165Y224419D01*
X1613698Y224552D01*
X1614231Y224419D01*
X1614698Y224085D01*
X1614898Y223619D01*
X1614765Y223152D01*
X1614431Y222819D01*
X1614031Y222685D01*
X1613365D01*
X1612765Y222485D01*
X1612365Y222085D01*
X1612231Y221619D01*
X1612365Y221152D01*
X1612698Y220819D01*
X1613231Y220619D01*
X1613698Y220552D01*
G01X1585035Y262709D02*
Y266709D01*
X1586369D01*
X1586902Y266509D01*
X1587302Y266242D01*
X1587635Y265842D01*
X1587902Y265376D01*
X1587969Y264709D01*
X1587902Y264042D01*
X1587635Y263576D01*
X1587302Y263176D01*
X1586902Y262909D01*
X1586369Y262709D01*
X1585035D01*
G01X1590169D02*
Y265376D01*
G01Y264842D02*
X1590502Y265109D01*
X1590835Y265309D01*
X1591302Y265376D01*
X1591635Y265309D01*
X1592035Y265109D01*
G01X1595702Y265376D02*
Y262709D01*
G01Y266442D02*
X1595569Y266509D01*
Y266642D01*
X1595702Y266709D01*
X1595835Y266642D01*
Y266509D01*
X1595702Y266442D01*
G01X1600302Y262709D02*
Y266709D01*
G01X1604902Y262709D02*
Y266709D01*
G01X1613702Y262709D02*
Y266109D01*
X1613835Y266442D01*
X1614102Y266642D01*
X1614502Y266709D01*
X1614902Y266576D01*
X1615102Y266242D01*
G01X1614302Y265109D02*
X1612969D01*
G01X1617702Y264509D02*
X1619835D01*
X1619635Y264976D01*
X1619302Y265242D01*
X1618835Y265376D01*
X1618369Y265309D01*
X1617969Y265109D01*
X1617702Y264642D01*
X1617569Y264242D01*
Y263842D01*
X1617702Y263442D01*
X1618035Y263042D01*
X1618435Y262776D01*
X1618902Y262709D01*
X1619369Y262842D01*
X1619835Y263242D01*
G01X1624502Y262709D02*
Y265376D01*
G01Y264909D02*
X1624235Y265176D01*
X1623835Y265309D01*
X1623369Y265376D01*
X1622902Y265242D01*
X1622502Y264976D01*
X1622235Y264576D01*
X1622102Y264042D01*
X1622235Y263509D01*
X1622502Y263109D01*
X1622902Y262842D01*
X1623369Y262709D01*
X1623835Y262776D01*
X1624235Y262976D01*
X1624502Y263242D01*
G01X1627902Y266709D02*
Y262709D01*
G01X1626969Y265376D02*
X1628835D01*
G01X1631369D02*
Y263509D01*
X1631635Y263042D01*
X1632035Y262776D01*
X1632502Y262709D01*
X1632969Y262776D01*
X1633369Y263042D01*
X1633635Y263509D01*
G01Y262709D02*
Y265376D01*
G01X1636169Y262709D02*
Y265376D01*
G01Y264842D02*
X1636502Y265109D01*
X1636835Y265309D01*
X1637302Y265376D01*
X1637635Y265309D01*
X1638035Y265109D01*
G01X1640702Y264509D02*
X1642835D01*
X1642635Y264976D01*
X1642302Y265242D01*
X1641835Y265376D01*
X1641369Y265309D01*
X1640969Y265109D01*
X1640702Y264642D01*
X1640569Y264242D01*
Y263842D01*
X1640702Y263442D01*
X1641035Y263042D01*
X1641435Y262776D01*
X1641902Y262709D01*
X1642369Y262842D01*
X1642835Y263242D01*
G01X1559882Y277843D02*
G03X1566807Y264712I37662J11471D01*
G01X1559882Y277843D02*
G03X1539921I-9980J-3040D01*
G01X1559882D02*
G03X1566807Y264712I37662J11471D01*
G01X1559882Y277843D02*
G03X1539921I-9980J-3040D01*
G01X1532996Y264712D02*
G03X1539921Y277843I-30737J24602D01*
G01X1532996Y264712D02*
G03X1539921Y277843I-30737J24602D01*
G01X1591590Y304876D02*
X1591990Y305276D01*
X1592457Y305476D01*
X1592990Y305543D01*
X1593657Y305410D01*
X1594124Y305076D01*
X1594257Y304676D01*
X1594190Y304276D01*
X1593924Y303943D01*
X1592590Y303276D01*
X1591990Y302810D01*
X1591590Y302143D01*
X1591457Y301543D01*
X1594257D01*
G01X1597457Y305543D02*
X1596924Y305410D01*
X1596524Y305076D01*
X1596257Y304676D01*
X1596057Y304143D01*
X1595990Y303543D01*
X1596057Y302943D01*
X1596257Y302410D01*
X1596524Y302010D01*
X1596924Y301676D01*
X1597457Y301543D01*
X1597990Y301676D01*
X1598390Y302010D01*
X1598657Y302410D01*
X1598857Y302943D01*
X1598924Y303543D01*
X1598857Y304143D01*
X1598657Y304676D01*
X1598390Y305076D01*
X1597990Y305410D01*
X1597457Y305543D01*
G01X1602057Y301543D02*
X1602524Y301610D01*
X1603057Y301810D01*
X1603390Y302143D01*
X1603524Y302610D01*
X1603390Y303076D01*
X1602990Y303476D01*
X1602390Y303676D01*
X1601724D01*
X1601324Y303810D01*
X1600990Y304143D01*
X1600857Y304610D01*
X1601057Y305076D01*
X1601524Y305410D01*
X1602057Y305543D01*
X1602590Y305410D01*
X1603057Y305076D01*
X1603257Y304610D01*
X1603124Y304143D01*
X1602790Y303810D01*
X1602390Y303676D01*
X1601724D01*
X1601124Y303476D01*
X1600724Y303076D01*
X1600590Y302610D01*
X1600724Y302143D01*
X1601057Y301810D01*
X1601590Y301610D01*
X1602057Y301543D01*
G01X1606657Y301410D02*
X1606524Y301476D01*
Y301610D01*
X1606657Y301676D01*
X1606790Y301610D01*
Y301476D01*
X1606657Y301410D01*
G01X1609990Y303210D02*
X1610457Y303676D01*
X1610857Y303943D01*
X1611390Y304076D01*
X1611857Y303943D01*
X1612190Y303676D01*
X1612457Y303276D01*
X1612524Y302810D01*
X1612457Y302410D01*
X1612190Y302010D01*
X1611790Y301676D01*
X1611324Y301543D01*
X1610790Y301676D01*
X1610324Y302076D01*
X1610057Y302676D01*
X1609990Y303343D01*
X1610124Y304210D01*
X1610324Y304676D01*
X1610657Y305143D01*
X1611124Y305476D01*
X1611590Y305543D01*
X1612057Y305410D01*
X1612390Y305076D01*
G01X1614590Y303210D02*
X1615057Y303676D01*
X1615457Y303943D01*
X1615990Y304076D01*
X1616457Y303943D01*
X1616790Y303676D01*
X1617057Y303276D01*
X1617124Y302810D01*
X1617057Y302410D01*
X1616790Y302010D01*
X1616390Y301676D01*
X1615924Y301543D01*
X1615390Y301676D01*
X1614924Y302076D01*
X1614657Y302676D01*
X1614590Y303343D01*
X1614724Y304210D01*
X1614924Y304676D01*
X1615257Y305143D01*
X1615724Y305476D01*
X1616190Y305543D01*
X1616657Y305410D01*
X1616990Y305076D01*
G01X1591498Y673308D02*
Y677308D01*
X1589031Y674441D01*
X1592365D01*
G01X1593831Y674108D02*
X1594231Y673641D01*
X1594765Y673375D01*
X1595365Y673308D01*
X1595898Y673375D01*
X1596431Y673708D01*
X1596765Y674108D01*
X1596831Y674508D01*
X1596698Y674975D01*
X1596231Y675308D01*
X1595765Y675441D01*
X1595165D01*
G01X1595765D02*
X1596165Y675641D01*
X1596498Y675975D01*
X1596631Y676375D01*
X1596498Y676775D01*
X1596165Y677108D01*
X1595565Y677308D01*
X1594965Y677241D01*
X1594365Y676975D01*
G01X1598431Y674108D02*
X1598831Y673641D01*
X1599365Y673375D01*
X1599965Y673308D01*
X1600498Y673375D01*
X1601031Y673708D01*
X1601365Y674108D01*
X1601431Y674508D01*
X1601298Y674975D01*
X1600831Y675308D01*
X1600365Y675441D01*
X1599765D01*
G01X1600365D02*
X1600765Y675641D01*
X1601098Y675975D01*
X1601231Y676375D01*
X1601098Y676775D01*
X1600765Y677108D01*
X1600165Y677308D01*
X1599565Y677241D01*
X1598965Y676975D01*
G01X1604498Y673175D02*
X1604365Y673241D01*
Y673375D01*
X1604498Y673441D01*
X1604631Y673375D01*
Y673241D01*
X1604498Y673175D01*
G01X1609098Y677308D02*
X1608565Y677175D01*
X1608165Y676841D01*
X1607898Y676441D01*
X1607698Y675908D01*
X1607631Y675308D01*
X1607698Y674708D01*
X1607898Y674175D01*
X1608165Y673775D01*
X1608565Y673441D01*
X1609098Y673308D01*
X1609631Y673441D01*
X1610031Y673775D01*
X1610298Y674175D01*
X1610498Y674708D01*
X1610565Y675308D01*
X1610498Y675908D01*
X1610298Y676441D01*
X1610031Y676841D01*
X1609631Y677175D01*
X1609098Y677308D01*
G01X1613698Y673308D02*
X1614165Y673375D01*
X1614698Y673575D01*
X1615031Y673908D01*
X1615165Y674375D01*
X1615031Y674841D01*
X1614631Y675241D01*
X1614031Y675441D01*
X1613365D01*
X1612965Y675575D01*
X1612631Y675908D01*
X1612498Y676375D01*
X1612698Y676841D01*
X1613165Y677175D01*
X1613698Y677308D01*
X1614231Y677175D01*
X1614698Y676841D01*
X1614898Y676375D01*
X1614765Y675908D01*
X1614431Y675575D01*
X1614031Y675441D01*
X1613365D01*
X1612765Y675241D01*
X1612365Y674841D01*
X1612231Y674375D01*
X1612365Y673908D01*
X1612698Y673575D01*
X1613231Y673375D01*
X1613698Y673308D01*
G01X1591590Y757632D02*
X1591990Y758032D01*
X1592457Y758232D01*
X1592990Y758299D01*
X1593657Y758166D01*
X1594124Y757832D01*
X1594257Y757432D01*
X1594190Y757032D01*
X1593924Y756699D01*
X1592590Y756032D01*
X1591990Y755566D01*
X1591590Y754899D01*
X1591457Y754299D01*
X1594257D01*
G01X1597457Y758299D02*
X1596924Y758166D01*
X1596524Y757832D01*
X1596257Y757432D01*
X1596057Y756899D01*
X1595990Y756299D01*
X1596057Y755699D01*
X1596257Y755166D01*
X1596524Y754766D01*
X1596924Y754432D01*
X1597457Y754299D01*
X1597990Y754432D01*
X1598390Y754766D01*
X1598657Y755166D01*
X1598857Y755699D01*
X1598924Y756299D01*
X1598857Y756899D01*
X1598657Y757432D01*
X1598390Y757832D01*
X1597990Y758166D01*
X1597457Y758299D01*
G01X1602057Y754299D02*
X1602524Y754366D01*
X1603057Y754566D01*
X1603390Y754899D01*
X1603524Y755366D01*
X1603390Y755832D01*
X1602990Y756232D01*
X1602390Y756432D01*
X1601724D01*
X1601324Y756566D01*
X1600990Y756899D01*
X1600857Y757366D01*
X1601057Y757832D01*
X1601524Y758166D01*
X1602057Y758299D01*
X1602590Y758166D01*
X1603057Y757832D01*
X1603257Y757366D01*
X1603124Y756899D01*
X1602790Y756566D01*
X1602390Y756432D01*
X1601724D01*
X1601124Y756232D01*
X1600724Y755832D01*
X1600590Y755366D01*
X1600724Y754899D01*
X1601057Y754566D01*
X1601590Y754366D01*
X1602057Y754299D01*
G01X1606657Y754166D02*
X1606524Y754232D01*
Y754366D01*
X1606657Y754432D01*
X1606790Y754366D01*
Y754232D01*
X1606657Y754166D01*
G01X1609990Y755966D02*
X1610457Y756432D01*
X1610857Y756699D01*
X1611390Y756832D01*
X1611857Y756699D01*
X1612190Y756432D01*
X1612457Y756032D01*
X1612524Y755566D01*
X1612457Y755166D01*
X1612190Y754766D01*
X1611790Y754432D01*
X1611324Y754299D01*
X1610790Y754432D01*
X1610324Y754832D01*
X1610057Y755432D01*
X1609990Y756099D01*
X1610124Y756966D01*
X1610324Y757432D01*
X1610657Y757899D01*
X1611124Y758232D01*
X1611590Y758299D01*
X1612057Y758166D01*
X1612390Y757832D01*
G01X1614590Y755966D02*
X1615057Y756432D01*
X1615457Y756699D01*
X1615990Y756832D01*
X1616457Y756699D01*
X1616790Y756432D01*
X1617057Y756032D01*
X1617124Y755566D01*
X1617057Y755166D01*
X1616790Y754766D01*
X1616390Y754432D01*
X1615924Y754299D01*
X1615390Y754432D01*
X1614924Y754832D01*
X1614657Y755432D01*
X1614590Y756099D01*
X1614724Y756966D01*
X1614924Y757432D01*
X1615257Y757899D01*
X1615724Y758232D01*
X1616190Y758299D01*
X1616657Y758166D01*
X1616990Y757832D01*
G01X1585035Y715465D02*
Y719465D01*
X1586369D01*
X1586902Y719265D01*
X1587302Y718998D01*
X1587635Y718598D01*
X1587902Y718132D01*
X1587969Y717465D01*
X1587902Y716798D01*
X1587635Y716332D01*
X1587302Y715932D01*
X1586902Y715665D01*
X1586369Y715465D01*
X1585035D01*
G01X1590169D02*
Y718132D01*
G01Y717598D02*
X1590502Y717865D01*
X1590835Y718065D01*
X1591302Y718132D01*
X1591635Y718065D01*
X1592035Y717865D01*
G01X1595702Y718132D02*
Y715465D01*
G01Y719198D02*
X1595569Y719265D01*
Y719398D01*
X1595702Y719465D01*
X1595835Y719398D01*
Y719265D01*
X1595702Y719198D01*
G01X1600302Y715465D02*
Y719465D01*
G01X1604902Y715465D02*
Y719465D01*
G01X1613702Y715465D02*
Y718865D01*
X1613835Y719198D01*
X1614102Y719398D01*
X1614502Y719465D01*
X1614902Y719332D01*
X1615102Y718998D01*
G01X1614302Y717865D02*
X1612969D01*
G01X1617702Y717265D02*
X1619835D01*
X1619635Y717732D01*
X1619302Y717998D01*
X1618835Y718132D01*
X1618369Y718065D01*
X1617969Y717865D01*
X1617702Y717398D01*
X1617569Y716998D01*
Y716598D01*
X1617702Y716198D01*
X1618035Y715798D01*
X1618435Y715532D01*
X1618902Y715465D01*
X1619369Y715598D01*
X1619835Y715998D01*
G01X1624502Y715465D02*
Y718132D01*
G01Y717665D02*
X1624235Y717932D01*
X1623835Y718065D01*
X1623369Y718132D01*
X1622902Y717998D01*
X1622502Y717732D01*
X1622235Y717332D01*
X1622102Y716798D01*
X1622235Y716265D01*
X1622502Y715865D01*
X1622902Y715598D01*
X1623369Y715465D01*
X1623835Y715532D01*
X1624235Y715732D01*
X1624502Y715998D01*
G01X1627902Y719465D02*
Y715465D01*
G01X1626969Y718132D02*
X1628835D01*
G01X1631369D02*
Y716265D01*
X1631635Y715798D01*
X1632035Y715532D01*
X1632502Y715465D01*
X1632969Y715532D01*
X1633369Y715798D01*
X1633635Y716265D01*
G01Y715465D02*
Y718132D01*
G01X1636169Y715465D02*
Y718132D01*
G01Y717598D02*
X1636502Y717865D01*
X1636835Y718065D01*
X1637302Y718132D01*
X1637635Y718065D01*
X1638035Y717865D01*
G01X1640702Y717265D02*
X1642835D01*
X1642635Y717732D01*
X1642302Y717998D01*
X1641835Y718132D01*
X1641369Y718065D01*
X1640969Y717865D01*
X1640702Y717398D01*
X1640569Y716998D01*
Y716598D01*
X1640702Y716198D01*
X1641035Y715798D01*
X1641435Y715532D01*
X1641902Y715465D01*
X1642369Y715598D01*
X1642835Y715998D01*
G01X1559882Y730599D02*
G03X1566807Y717468I37662J11471D01*
G01X1559882Y730599D02*
G03X1539921I-9980J-3040D01*
G01X1559882D02*
G03X1566807Y717468I37662J11471D01*
G01X1559882Y730599D02*
G03X1539921I-9980J-3040D01*
G01X1532996Y717468D02*
G03X1539921Y730599I-30737J24601D01*
G01X1532996Y717468D02*
G03X1539921Y730599I-30737J24601D01*
G01X1591498Y1126063D02*
Y1130063D01*
X1589031Y1127196D01*
X1592365D01*
G01X1593831Y1126863D02*
X1594231Y1126396D01*
X1594765Y1126130D01*
X1595365Y1126063D01*
X1595898Y1126130D01*
X1596431Y1126463D01*
X1596765Y1126863D01*
X1596831Y1127263D01*
X1596698Y1127730D01*
X1596231Y1128063D01*
X1595765Y1128196D01*
X1595165D01*
G01X1595765D02*
X1596165Y1128396D01*
X1596498Y1128730D01*
X1596631Y1129130D01*
X1596498Y1129530D01*
X1596165Y1129863D01*
X1595565Y1130063D01*
X1594965Y1129996D01*
X1594365Y1129730D01*
G01X1598431Y1126863D02*
X1598831Y1126396D01*
X1599365Y1126130D01*
X1599965Y1126063D01*
X1600498Y1126130D01*
X1601031Y1126463D01*
X1601365Y1126863D01*
X1601431Y1127263D01*
X1601298Y1127730D01*
X1600831Y1128063D01*
X1600365Y1128196D01*
X1599765D01*
G01X1600365D02*
X1600765Y1128396D01*
X1601098Y1128730D01*
X1601231Y1129130D01*
X1601098Y1129530D01*
X1600765Y1129863D01*
X1600165Y1130063D01*
X1599565Y1129996D01*
X1598965Y1129730D01*
G01X1604498Y1125930D02*
X1604365Y1125996D01*
Y1126130D01*
X1604498Y1126196D01*
X1604631Y1126130D01*
Y1125996D01*
X1604498Y1125930D01*
G01X1609098Y1130063D02*
X1608565Y1129930D01*
X1608165Y1129596D01*
X1607898Y1129196D01*
X1607698Y1128663D01*
X1607631Y1128063D01*
X1607698Y1127463D01*
X1607898Y1126930D01*
X1608165Y1126530D01*
X1608565Y1126196D01*
X1609098Y1126063D01*
X1609631Y1126196D01*
X1610031Y1126530D01*
X1610298Y1126930D01*
X1610498Y1127463D01*
X1610565Y1128063D01*
X1610498Y1128663D01*
X1610298Y1129196D01*
X1610031Y1129596D01*
X1609631Y1129930D01*
X1609098Y1130063D01*
G01X1613698Y1126063D02*
X1614165Y1126130D01*
X1614698Y1126330D01*
X1615031Y1126663D01*
X1615165Y1127130D01*
X1615031Y1127596D01*
X1614631Y1127996D01*
X1614031Y1128196D01*
X1613365D01*
X1612965Y1128330D01*
X1612631Y1128663D01*
X1612498Y1129130D01*
X1612698Y1129596D01*
X1613165Y1129930D01*
X1613698Y1130063D01*
X1614231Y1129930D01*
X1614698Y1129596D01*
X1614898Y1129130D01*
X1614765Y1128663D01*
X1614431Y1128330D01*
X1614031Y1128196D01*
X1613365D01*
X1612765Y1127996D01*
X1612365Y1127596D01*
X1612231Y1127130D01*
X1612365Y1126663D01*
X1612698Y1126330D01*
X1613231Y1126130D01*
X1613698Y1126063D01*
G01X1591590Y1210387D02*
X1591990Y1210787D01*
X1592457Y1210987D01*
X1592990Y1211054D01*
X1593657Y1210921D01*
X1594124Y1210587D01*
X1594257Y1210187D01*
X1594190Y1209787D01*
X1593924Y1209454D01*
X1592590Y1208787D01*
X1591990Y1208321D01*
X1591590Y1207654D01*
X1591457Y1207054D01*
X1594257D01*
G01X1597457Y1211054D02*
X1596924Y1210921D01*
X1596524Y1210587D01*
X1596257Y1210187D01*
X1596057Y1209654D01*
X1595990Y1209054D01*
X1596057Y1208454D01*
X1596257Y1207921D01*
X1596524Y1207521D01*
X1596924Y1207187D01*
X1597457Y1207054D01*
X1597990Y1207187D01*
X1598390Y1207521D01*
X1598657Y1207921D01*
X1598857Y1208454D01*
X1598924Y1209054D01*
X1598857Y1209654D01*
X1598657Y1210187D01*
X1598390Y1210587D01*
X1597990Y1210921D01*
X1597457Y1211054D01*
G01X1602057Y1207054D02*
X1602524Y1207121D01*
X1603057Y1207321D01*
X1603390Y1207654D01*
X1603524Y1208121D01*
X1603390Y1208587D01*
X1602990Y1208987D01*
X1602390Y1209187D01*
X1601724D01*
X1601324Y1209321D01*
X1600990Y1209654D01*
X1600857Y1210121D01*
X1601057Y1210587D01*
X1601524Y1210921D01*
X1602057Y1211054D01*
X1602590Y1210921D01*
X1603057Y1210587D01*
X1603257Y1210121D01*
X1603124Y1209654D01*
X1602790Y1209321D01*
X1602390Y1209187D01*
X1601724D01*
X1601124Y1208987D01*
X1600724Y1208587D01*
X1600590Y1208121D01*
X1600724Y1207654D01*
X1601057Y1207321D01*
X1601590Y1207121D01*
X1602057Y1207054D01*
G01X1606657Y1206921D02*
X1606524Y1206987D01*
Y1207121D01*
X1606657Y1207187D01*
X1606790Y1207121D01*
Y1206987D01*
X1606657Y1206921D01*
G01X1609990Y1208721D02*
X1610457Y1209187D01*
X1610857Y1209454D01*
X1611390Y1209587D01*
X1611857Y1209454D01*
X1612190Y1209187D01*
X1612457Y1208787D01*
X1612524Y1208321D01*
X1612457Y1207921D01*
X1612190Y1207521D01*
X1611790Y1207187D01*
X1611324Y1207054D01*
X1610790Y1207187D01*
X1610324Y1207587D01*
X1610057Y1208187D01*
X1609990Y1208854D01*
X1610124Y1209721D01*
X1610324Y1210187D01*
X1610657Y1210654D01*
X1611124Y1210987D01*
X1611590Y1211054D01*
X1612057Y1210921D01*
X1612390Y1210587D01*
G01X1614590Y1208721D02*
X1615057Y1209187D01*
X1615457Y1209454D01*
X1615990Y1209587D01*
X1616457Y1209454D01*
X1616790Y1209187D01*
X1617057Y1208787D01*
X1617124Y1208321D01*
X1617057Y1207921D01*
X1616790Y1207521D01*
X1616390Y1207187D01*
X1615924Y1207054D01*
X1615390Y1207187D01*
X1614924Y1207587D01*
X1614657Y1208187D01*
X1614590Y1208854D01*
X1614724Y1209721D01*
X1614924Y1210187D01*
X1615257Y1210654D01*
X1615724Y1210987D01*
X1616190Y1211054D01*
X1616657Y1210921D01*
X1616990Y1210587D01*
G01X1585035Y1168220D02*
Y1172220D01*
X1586369D01*
X1586902Y1172020D01*
X1587302Y1171753D01*
X1587635Y1171353D01*
X1587902Y1170887D01*
X1587969Y1170220D01*
X1587902Y1169553D01*
X1587635Y1169087D01*
X1587302Y1168687D01*
X1586902Y1168420D01*
X1586369Y1168220D01*
X1585035D01*
G01X1590169D02*
Y1170887D01*
G01Y1170353D02*
X1590502Y1170620D01*
X1590835Y1170820D01*
X1591302Y1170887D01*
X1591635Y1170820D01*
X1592035Y1170620D01*
G01X1595702Y1170887D02*
Y1168220D01*
G01Y1171953D02*
X1595569Y1172020D01*
Y1172153D01*
X1595702Y1172220D01*
X1595835Y1172153D01*
Y1172020D01*
X1595702Y1171953D01*
G01X1600302Y1168220D02*
Y1172220D01*
G01X1604902Y1168220D02*
Y1172220D01*
G01X1613702Y1168220D02*
Y1171620D01*
X1613835Y1171953D01*
X1614102Y1172153D01*
X1614502Y1172220D01*
X1614902Y1172087D01*
X1615102Y1171753D01*
G01X1614302Y1170620D02*
X1612969D01*
G01X1617702Y1170020D02*
X1619835D01*
X1619635Y1170487D01*
X1619302Y1170753D01*
X1618835Y1170887D01*
X1618369Y1170820D01*
X1617969Y1170620D01*
X1617702Y1170153D01*
X1617569Y1169753D01*
Y1169353D01*
X1617702Y1168953D01*
X1618035Y1168553D01*
X1618435Y1168287D01*
X1618902Y1168220D01*
X1619369Y1168353D01*
X1619835Y1168753D01*
G01X1624502Y1168220D02*
Y1170887D01*
G01Y1170420D02*
X1624235Y1170687D01*
X1623835Y1170820D01*
X1623369Y1170887D01*
X1622902Y1170753D01*
X1622502Y1170487D01*
X1622235Y1170087D01*
X1622102Y1169553D01*
X1622235Y1169020D01*
X1622502Y1168620D01*
X1622902Y1168353D01*
X1623369Y1168220D01*
X1623835Y1168287D01*
X1624235Y1168487D01*
X1624502Y1168753D01*
G01X1627902Y1172220D02*
Y1168220D01*
G01X1626969Y1170887D02*
X1628835D01*
G01X1631369D02*
Y1169020D01*
X1631635Y1168553D01*
X1632035Y1168287D01*
X1632502Y1168220D01*
X1632969Y1168287D01*
X1633369Y1168553D01*
X1633635Y1169020D01*
G01Y1168220D02*
Y1170887D01*
G01X1636169Y1168220D02*
Y1170887D01*
G01Y1170353D02*
X1636502Y1170620D01*
X1636835Y1170820D01*
X1637302Y1170887D01*
X1637635Y1170820D01*
X1638035Y1170620D01*
G01X1640702Y1170020D02*
X1642835D01*
X1642635Y1170487D01*
X1642302Y1170753D01*
X1641835Y1170887D01*
X1641369Y1170820D01*
X1640969Y1170620D01*
X1640702Y1170153D01*
X1640569Y1169753D01*
Y1169353D01*
X1640702Y1168953D01*
X1641035Y1168553D01*
X1641435Y1168287D01*
X1641902Y1168220D01*
X1642369Y1168353D01*
X1642835Y1168753D01*
G01X1559882Y1183355D02*
G03X1539921I-9980J-3040D01*
G01X1559882D02*
G03X1539921I-9980J-3040D01*
G01X1559882D02*
G03X1566807Y1170224I37662J11471D01*
G01X1559882Y1183355D02*
G03X1566807Y1170224I37662J11471D01*
G01X1532996D02*
G03X1539921Y1183355I-30737J24602D01*
G01X1532996Y1170224D02*
G03X1539921Y1183355I-30737J24601D01*
G01X1636614Y1503937D02*
X1624803D01*
G01X1636614D02*
X1624803D01*
G01D02*
G03Y1496063I0J-3937D01*
G01X1606693D02*
G03Y1503937I0J3937D01*
G01X1624803D02*
G03Y1496063I0J-3937D01*
G01X1606693D02*
G03Y1503937I0J3937D01*
G01X1721496Y253599D02*
X1721896Y253266D01*
X1722363Y253066D01*
X1722963Y252999D01*
X1723563Y253132D01*
X1724030Y253399D01*
X1724363Y253866D01*
X1724430Y254399D01*
X1724296Y254932D01*
X1723963Y255266D01*
X1723496Y255532D01*
X1723030Y255599D01*
X1722563Y255532D01*
X1721963Y255266D01*
X1722163Y256999D01*
X1723963D01*
G01X1726096Y253599D02*
X1726496Y253266D01*
X1726963Y253066D01*
X1727563Y252999D01*
X1728163Y253132D01*
X1728630Y253399D01*
X1728963Y253866D01*
X1729030Y254399D01*
X1728896Y254932D01*
X1728563Y255266D01*
X1728096Y255532D01*
X1727630Y255599D01*
X1727163Y255532D01*
X1726563Y255266D01*
X1726763Y256999D01*
X1728563D01*
G01X1732030Y252999D02*
X1732163Y253866D01*
X1732363Y254599D01*
X1732630Y255266D01*
X1732963Y255999D01*
X1733496Y256999D01*
X1730830D01*
G01X1736763Y252866D02*
X1736630Y252932D01*
Y253066D01*
X1736763Y253132D01*
X1736896Y253066D01*
Y252932D01*
X1736763Y252866D01*
G01X1741363Y256999D02*
X1740830Y256866D01*
X1740430Y256532D01*
X1740163Y256132D01*
X1739963Y255599D01*
X1739896Y254999D01*
X1739963Y254399D01*
X1740163Y253866D01*
X1740430Y253466D01*
X1740830Y253132D01*
X1741363Y252999D01*
X1741896Y253132D01*
X1742296Y253466D01*
X1742563Y253866D01*
X1742763Y254399D01*
X1742830Y254999D01*
X1742763Y255599D01*
X1742563Y256132D01*
X1742296Y256532D01*
X1741896Y256866D01*
X1741363Y256999D01*
G01X1744830Y253466D02*
X1745296Y253132D01*
X1745830Y252999D01*
X1746363Y253132D01*
X1746830Y253532D01*
X1747163Y254132D01*
X1747296Y254732D01*
Y255466D01*
X1747163Y256066D01*
X1746830Y256599D01*
X1746430Y256866D01*
X1745963Y256999D01*
X1745430Y256866D01*
X1745030Y256599D01*
X1744763Y256199D01*
X1744630Y255666D01*
X1744763Y255199D01*
X1745096Y254732D01*
X1745496Y254466D01*
X1745963Y254399D01*
X1746496Y254532D01*
X1746896Y254866D01*
X1747296Y255466D01*
G01X1721496Y706356D02*
X1721896Y706023D01*
X1722363Y705823D01*
X1722963Y705756D01*
X1723563Y705889D01*
X1724030Y706156D01*
X1724363Y706623D01*
X1724430Y707156D01*
X1724296Y707689D01*
X1723963Y708023D01*
X1723496Y708289D01*
X1723030Y708356D01*
X1722563Y708289D01*
X1721963Y708023D01*
X1722163Y709756D01*
X1723963D01*
G01X1726096Y706356D02*
X1726496Y706023D01*
X1726963Y705823D01*
X1727563Y705756D01*
X1728163Y705889D01*
X1728630Y706156D01*
X1728963Y706623D01*
X1729030Y707156D01*
X1728896Y707689D01*
X1728563Y708023D01*
X1728096Y708289D01*
X1727630Y708356D01*
X1727163Y708289D01*
X1726563Y708023D01*
X1726763Y709756D01*
X1728563D01*
G01X1732030Y705756D02*
X1732163Y706623D01*
X1732363Y707356D01*
X1732630Y708023D01*
X1732963Y708756D01*
X1733496Y709756D01*
X1730830D01*
G01X1736763Y705623D02*
X1736630Y705689D01*
Y705823D01*
X1736763Y705889D01*
X1736896Y705823D01*
Y705689D01*
X1736763Y705623D01*
G01X1741363Y709756D02*
X1740830Y709623D01*
X1740430Y709289D01*
X1740163Y708889D01*
X1739963Y708356D01*
X1739896Y707756D01*
X1739963Y707156D01*
X1740163Y706623D01*
X1740430Y706223D01*
X1740830Y705889D01*
X1741363Y705756D01*
X1741896Y705889D01*
X1742296Y706223D01*
X1742563Y706623D01*
X1742763Y707156D01*
X1742830Y707756D01*
X1742763Y708356D01*
X1742563Y708889D01*
X1742296Y709289D01*
X1741896Y709623D01*
X1741363Y709756D01*
G01X1744830Y706223D02*
X1745296Y705889D01*
X1745830Y705756D01*
X1746363Y705889D01*
X1746830Y706289D01*
X1747163Y706889D01*
X1747296Y707489D01*
Y708223D01*
X1747163Y708823D01*
X1746830Y709356D01*
X1746430Y709623D01*
X1745963Y709756D01*
X1745430Y709623D01*
X1745030Y709356D01*
X1744763Y708956D01*
X1744630Y708423D01*
X1744763Y707956D01*
X1745096Y707489D01*
X1745496Y707223D01*
X1745963Y707156D01*
X1746496Y707289D01*
X1746896Y707623D01*
X1747296Y708223D01*
G01X1721496Y1159111D02*
X1721896Y1158778D01*
X1722363Y1158578D01*
X1722963Y1158511D01*
X1723563Y1158644D01*
X1724030Y1158911D01*
X1724363Y1159378D01*
X1724430Y1159911D01*
X1724296Y1160444D01*
X1723963Y1160778D01*
X1723496Y1161044D01*
X1723030Y1161111D01*
X1722563Y1161044D01*
X1721963Y1160778D01*
X1722163Y1162511D01*
X1723963D01*
G01X1726096Y1159111D02*
X1726496Y1158778D01*
X1726963Y1158578D01*
X1727563Y1158511D01*
X1728163Y1158644D01*
X1728630Y1158911D01*
X1728963Y1159378D01*
X1729030Y1159911D01*
X1728896Y1160444D01*
X1728563Y1160778D01*
X1728096Y1161044D01*
X1727630Y1161111D01*
X1727163Y1161044D01*
X1726563Y1160778D01*
X1726763Y1162511D01*
X1728563D01*
G01X1732030Y1158511D02*
X1732163Y1159378D01*
X1732363Y1160111D01*
X1732630Y1160778D01*
X1732963Y1161511D01*
X1733496Y1162511D01*
X1730830D01*
G01X1736763Y1158378D02*
X1736630Y1158444D01*
Y1158578D01*
X1736763Y1158644D01*
X1736896Y1158578D01*
Y1158444D01*
X1736763Y1158378D01*
G01X1741363Y1162511D02*
X1740830Y1162378D01*
X1740430Y1162044D01*
X1740163Y1161644D01*
X1739963Y1161111D01*
X1739896Y1160511D01*
X1739963Y1159911D01*
X1740163Y1159378D01*
X1740430Y1158978D01*
X1740830Y1158644D01*
X1741363Y1158511D01*
X1741896Y1158644D01*
X1742296Y1158978D01*
X1742563Y1159378D01*
X1742763Y1159911D01*
X1742830Y1160511D01*
X1742763Y1161111D01*
X1742563Y1161644D01*
X1742296Y1162044D01*
X1741896Y1162378D01*
X1741363Y1162511D01*
G01X1744830Y1158978D02*
X1745296Y1158644D01*
X1745830Y1158511D01*
X1746363Y1158644D01*
X1746830Y1159044D01*
X1747163Y1159644D01*
X1747296Y1160244D01*
Y1160978D01*
X1747163Y1161578D01*
X1746830Y1162111D01*
X1746430Y1162378D01*
X1745963Y1162511D01*
X1745430Y1162378D01*
X1745030Y1162111D01*
X1744763Y1161711D01*
X1744630Y1161178D01*
X1744763Y1160711D01*
X1745096Y1160244D01*
X1745496Y1159978D01*
X1745963Y1159911D01*
X1746496Y1160044D01*
X1746896Y1160378D01*
X1747296Y1160978D01*
G01X1636614Y1515748D02*
G03X1632677Y1519685I-3937J0D01*
G01X1636614Y1515748D02*
G03X1632677Y1519685I-3937J0D01*
G01X1648425D02*
G03X1644488Y1515748I0J-3937D01*
G01X1827756Y1519685D02*
X1648425D01*
G01D02*
G03X1644488Y1515748I0J-3937D01*
G01X1827756Y1519685D02*
X1648425D01*
G01X1636614Y1515748D02*
Y1503937D01*
G01X1640551Y1496063D02*
G03X1644488Y1500000I0J3937D01*
G01Y1515748D02*
Y1500000D01*
G01X1636614Y1515748D02*
Y1503937D01*
G01X1640551Y1496063D02*
G03X1644488Y1500000I0J3937D01*
G01Y1515748D02*
Y1500000D01*
G01X1738835Y264145D02*
X1739235Y264545D01*
X1739702Y264745D01*
X1740235Y264812D01*
X1740902Y264679D01*
X1741369Y264345D01*
X1741502Y263945D01*
X1741435Y263545D01*
X1741169Y263212D01*
X1739835Y262545D01*
X1739235Y262079D01*
X1738835Y261412D01*
X1738702Y260812D01*
X1741502D01*
G01X1743235Y261612D02*
X1743635Y261145D01*
X1744169Y260879D01*
X1744769Y260812D01*
X1745302Y260879D01*
X1745835Y261212D01*
X1746169Y261612D01*
X1746235Y262012D01*
X1746102Y262479D01*
X1745635Y262812D01*
X1745169Y262945D01*
X1744569D01*
G01X1745169D02*
X1745569Y263145D01*
X1745902Y263479D01*
X1746035Y263879D01*
X1745902Y264279D01*
X1745569Y264612D01*
X1744969Y264812D01*
X1744369Y264745D01*
X1743769Y264479D01*
G01X1748035Y262479D02*
X1748502Y262945D01*
X1748902Y263212D01*
X1749435Y263345D01*
X1749902Y263212D01*
X1750235Y262945D01*
X1750502Y262545D01*
X1750569Y262079D01*
X1750502Y261679D01*
X1750235Y261279D01*
X1749835Y260945D01*
X1749369Y260812D01*
X1748835Y260945D01*
X1748369Y261345D01*
X1748102Y261945D01*
X1748035Y262612D01*
X1748169Y263479D01*
X1748369Y263945D01*
X1748702Y264412D01*
X1749169Y264745D01*
X1749635Y264812D01*
X1750102Y264679D01*
X1750435Y264345D01*
G01X1753902Y260679D02*
X1753769Y260745D01*
Y260879D01*
X1753902Y260945D01*
X1754035Y260879D01*
Y260745D01*
X1753902Y260679D01*
G01X1757235Y264145D02*
X1757635Y264545D01*
X1758102Y264745D01*
X1758635Y264812D01*
X1759302Y264679D01*
X1759769Y264345D01*
X1759902Y263945D01*
X1759835Y263545D01*
X1759569Y263212D01*
X1758235Y262545D01*
X1757635Y262079D01*
X1757235Y261412D01*
X1757102Y260812D01*
X1759902D01*
G01X1761835Y264145D02*
X1762235Y264545D01*
X1762702Y264745D01*
X1763235Y264812D01*
X1763902Y264679D01*
X1764369Y264345D01*
X1764502Y263945D01*
X1764435Y263545D01*
X1764169Y263212D01*
X1762835Y262545D01*
X1762235Y262079D01*
X1761835Y261412D01*
X1761702Y260812D01*
X1764502D01*
G01X1807914Y277843D02*
G03X1814838Y264712I37663J11469D01*
G01X1807913Y277843D02*
G03X1814839Y264712I37661J11473D01*
G01X1807914Y277843D02*
G03X1787953I-9980J-3040D01*
G01X1781028Y264712D02*
G03X1787953Y277843I-30737J24602D01*
G01X1807913D02*
G03X1787953I-9980J-3040D01*
G01X1781028Y264712D02*
G03X1787953Y277843I-30737J24602D01*
G01X1781028Y264712D02*
G03X1814839I16906J-13531D01*
G01X1781028D02*
G03X1814839I16906J-13531D01*
G01X1738835Y716902D02*
X1739235Y717302D01*
X1739702Y717502D01*
X1740235Y717569D01*
X1740902Y717436D01*
X1741369Y717102D01*
X1741502Y716702D01*
X1741435Y716302D01*
X1741169Y715969D01*
X1739835Y715302D01*
X1739235Y714836D01*
X1738835Y714169D01*
X1738702Y713569D01*
X1741502D01*
G01X1743235Y714369D02*
X1743635Y713902D01*
X1744169Y713636D01*
X1744769Y713569D01*
X1745302Y713636D01*
X1745835Y713969D01*
X1746169Y714369D01*
X1746235Y714769D01*
X1746102Y715236D01*
X1745635Y715569D01*
X1745169Y715702D01*
X1744569D01*
G01X1745169D02*
X1745569Y715902D01*
X1745902Y716236D01*
X1746035Y716636D01*
X1745902Y717036D01*
X1745569Y717369D01*
X1744969Y717569D01*
X1744369Y717502D01*
X1743769Y717236D01*
G01X1748035Y715236D02*
X1748502Y715702D01*
X1748902Y715969D01*
X1749435Y716102D01*
X1749902Y715969D01*
X1750235Y715702D01*
X1750502Y715302D01*
X1750569Y714836D01*
X1750502Y714436D01*
X1750235Y714036D01*
X1749835Y713702D01*
X1749369Y713569D01*
X1748835Y713702D01*
X1748369Y714102D01*
X1748102Y714702D01*
X1748035Y715369D01*
X1748169Y716236D01*
X1748369Y716702D01*
X1748702Y717169D01*
X1749169Y717502D01*
X1749635Y717569D01*
X1750102Y717436D01*
X1750435Y717102D01*
G01X1753902Y713436D02*
X1753769Y713502D01*
Y713636D01*
X1753902Y713702D01*
X1754035Y713636D01*
Y713502D01*
X1753902Y713436D01*
G01X1757235Y716902D02*
X1757635Y717302D01*
X1758102Y717502D01*
X1758635Y717569D01*
X1759302Y717436D01*
X1759769Y717102D01*
X1759902Y716702D01*
X1759835Y716302D01*
X1759569Y715969D01*
X1758235Y715302D01*
X1757635Y714836D01*
X1757235Y714169D01*
X1757102Y713569D01*
X1759902D01*
G01X1761835Y716902D02*
X1762235Y717302D01*
X1762702Y717502D01*
X1763235Y717569D01*
X1763902Y717436D01*
X1764369Y717102D01*
X1764502Y716702D01*
X1764435Y716302D01*
X1764169Y715969D01*
X1762835Y715302D01*
X1762235Y714836D01*
X1761835Y714169D01*
X1761702Y713569D01*
X1764502D01*
G01X1807914Y730599D02*
G03X1814838Y717468I37663J11469D01*
G01X1807913Y730599D02*
G03X1814839Y717468I37661J11473D01*
G01X1807914Y730599D02*
G03X1787953I-9980J-3040D01*
G01X1781028Y717468D02*
G03X1787954Y730599I-30736J24604D01*
G01X1807913D02*
G03X1787953I-9980J-3040D01*
G01X1781028Y717468D02*
G03X1787953Y730599I-30737J24602D01*
G01X1781028Y717468D02*
G03X1814838I16905J-13531D01*
G01X1781028D02*
G03X1814839I16906J-13531D01*
G01X1781028Y1170224D02*
G03X1814838I16905J-13531D01*
G01X1781028D02*
G03X1814839I16906J-13531D01*
G01X1738835Y1169657D02*
X1739235Y1170057D01*
X1739702Y1170257D01*
X1740235Y1170324D01*
X1740902Y1170191D01*
X1741369Y1169857D01*
X1741502Y1169457D01*
X1741435Y1169057D01*
X1741169Y1168724D01*
X1739835Y1168057D01*
X1739235Y1167591D01*
X1738835Y1166924D01*
X1738702Y1166324D01*
X1741502D01*
G01X1743235Y1167124D02*
X1743635Y1166657D01*
X1744169Y1166391D01*
X1744769Y1166324D01*
X1745302Y1166391D01*
X1745835Y1166724D01*
X1746169Y1167124D01*
X1746235Y1167524D01*
X1746102Y1167991D01*
X1745635Y1168324D01*
X1745169Y1168457D01*
X1744569D01*
G01X1745169D02*
X1745569Y1168657D01*
X1745902Y1168991D01*
X1746035Y1169391D01*
X1745902Y1169791D01*
X1745569Y1170124D01*
X1744969Y1170324D01*
X1744369Y1170257D01*
X1743769Y1169991D01*
G01X1748035Y1167991D02*
X1748502Y1168457D01*
X1748902Y1168724D01*
X1749435Y1168857D01*
X1749902Y1168724D01*
X1750235Y1168457D01*
X1750502Y1168057D01*
X1750569Y1167591D01*
X1750502Y1167191D01*
X1750235Y1166791D01*
X1749835Y1166457D01*
X1749369Y1166324D01*
X1748835Y1166457D01*
X1748369Y1166857D01*
X1748102Y1167457D01*
X1748035Y1168124D01*
X1748169Y1168991D01*
X1748369Y1169457D01*
X1748702Y1169924D01*
X1749169Y1170257D01*
X1749635Y1170324D01*
X1750102Y1170191D01*
X1750435Y1169857D01*
G01X1753902Y1166191D02*
X1753769Y1166257D01*
Y1166391D01*
X1753902Y1166457D01*
X1754035Y1166391D01*
Y1166257D01*
X1753902Y1166191D01*
G01X1757235Y1169657D02*
X1757635Y1170057D01*
X1758102Y1170257D01*
X1758635Y1170324D01*
X1759302Y1170191D01*
X1759769Y1169857D01*
X1759902Y1169457D01*
X1759835Y1169057D01*
X1759569Y1168724D01*
X1758235Y1168057D01*
X1757635Y1167591D01*
X1757235Y1166924D01*
X1757102Y1166324D01*
X1759902D01*
G01X1761835Y1169657D02*
X1762235Y1170057D01*
X1762702Y1170257D01*
X1763235Y1170324D01*
X1763902Y1170191D01*
X1764369Y1169857D01*
X1764502Y1169457D01*
X1764435Y1169057D01*
X1764169Y1168724D01*
X1762835Y1168057D01*
X1762235Y1167591D01*
X1761835Y1166924D01*
X1761702Y1166324D01*
X1764502D01*
G01X1807914Y1183355D02*
G03X1814838Y1170224I37662J11468D01*
G01X1807913Y1183355D02*
G03X1814839Y1170224I37661J11473D01*
G01X1807914Y1183355D02*
G03X1787953I-9980J-3040D01*
G01X1807913D02*
G03X1787953I-9980J-3040D01*
G01X1781028Y1170224D02*
G03X1787953Y1183355I-30737J24602D01*
G01X1781028Y1170224D02*
G03X1787953Y1183355I-30737J24602D01*
G01X1833067Y262708D02*
Y266708D01*
X1834401D01*
X1834934Y266508D01*
X1835334Y266241D01*
X1835667Y265841D01*
X1835934Y265375D01*
X1836001Y264708D01*
X1835934Y264041D01*
X1835667Y263575D01*
X1835334Y263175D01*
X1834934Y262908D01*
X1834401Y262708D01*
X1833067D01*
G01X1838201D02*
Y265375D01*
G01Y264841D02*
X1838534Y265108D01*
X1838867Y265308D01*
X1839334Y265375D01*
X1839667Y265308D01*
X1840067Y265108D01*
G01X1843734Y265375D02*
Y262708D01*
G01Y266441D02*
X1843601Y266508D01*
Y266641D01*
X1843734Y266708D01*
X1843867Y266641D01*
Y266508D01*
X1843734Y266441D01*
G01X1848334Y262708D02*
Y266708D01*
G01X1852934Y262708D02*
Y266708D01*
G01X1861734Y262708D02*
Y266108D01*
X1861867Y266441D01*
X1862134Y266641D01*
X1862534Y266708D01*
X1862934Y266575D01*
X1863134Y266241D01*
G01X1862334Y265108D02*
X1861001D01*
G01X1865734Y264508D02*
X1867867D01*
X1867667Y264975D01*
X1867334Y265241D01*
X1866867Y265375D01*
X1866401Y265308D01*
X1866001Y265108D01*
X1865734Y264641D01*
X1865601Y264241D01*
Y263841D01*
X1865734Y263441D01*
X1866067Y263041D01*
X1866467Y262775D01*
X1866934Y262708D01*
X1867401Y262841D01*
X1867867Y263241D01*
G01X1872534Y262708D02*
Y265375D01*
G01Y264908D02*
X1872267Y265175D01*
X1871867Y265308D01*
X1871401Y265375D01*
X1870934Y265241D01*
X1870534Y264975D01*
X1870267Y264575D01*
X1870134Y264041D01*
X1870267Y263508D01*
X1870534Y263108D01*
X1870934Y262841D01*
X1871401Y262708D01*
X1871867Y262775D01*
X1872267Y262975D01*
X1872534Y263241D01*
G01X1875934Y266708D02*
Y262708D01*
G01X1875001Y265375D02*
X1876867D01*
G01X1879401D02*
Y263508D01*
X1879667Y263041D01*
X1880067Y262775D01*
X1880534Y262708D01*
X1881001Y262775D01*
X1881401Y263041D01*
X1881667Y263508D01*
G01Y262708D02*
Y265375D01*
G01X1884201Y262708D02*
Y265375D01*
G01Y264841D02*
X1884534Y265108D01*
X1884867Y265308D01*
X1885334Y265375D01*
X1885667Y265308D01*
X1886067Y265108D01*
G01X1888734Y264508D02*
X1890867D01*
X1890667Y264975D01*
X1890334Y265241D01*
X1889867Y265375D01*
X1889401Y265308D01*
X1889001Y265108D01*
X1888734Y264641D01*
X1888601Y264241D01*
Y263841D01*
X1888734Y263441D01*
X1889067Y263041D01*
X1889467Y262775D01*
X1889934Y262708D01*
X1890401Y262841D01*
X1890867Y263241D01*
G01X1839530Y220551D02*
Y224551D01*
X1837063Y221684D01*
X1840397D01*
G01X1841863Y221351D02*
X1842263Y220884D01*
X1842797Y220618D01*
X1843397Y220551D01*
X1843930Y220618D01*
X1844463Y220951D01*
X1844797Y221351D01*
X1844863Y221751D01*
X1844730Y222218D01*
X1844263Y222551D01*
X1843797Y222684D01*
X1843197D01*
G01X1843797D02*
X1844197Y222884D01*
X1844530Y223218D01*
X1844663Y223618D01*
X1844530Y224018D01*
X1844197Y224351D01*
X1843597Y224551D01*
X1842997Y224484D01*
X1842397Y224218D01*
G01X1846463Y221351D02*
X1846863Y220884D01*
X1847397Y220618D01*
X1847997Y220551D01*
X1848530Y220618D01*
X1849063Y220951D01*
X1849397Y221351D01*
X1849463Y221751D01*
X1849330Y222218D01*
X1848863Y222551D01*
X1848397Y222684D01*
X1847797D01*
G01X1848397D02*
X1848797Y222884D01*
X1849130Y223218D01*
X1849263Y223618D01*
X1849130Y224018D01*
X1848797Y224351D01*
X1848197Y224551D01*
X1847597Y224484D01*
X1846997Y224218D01*
G01X1852530Y220418D02*
X1852397Y220484D01*
Y220618D01*
X1852530Y220684D01*
X1852663Y220618D01*
Y220484D01*
X1852530Y220418D01*
G01X1857130Y224551D02*
X1856597Y224418D01*
X1856197Y224084D01*
X1855930Y223684D01*
X1855730Y223151D01*
X1855663Y222551D01*
X1855730Y221951D01*
X1855930Y221418D01*
X1856197Y221018D01*
X1856597Y220684D01*
X1857130Y220551D01*
X1857663Y220684D01*
X1858063Y221018D01*
X1858330Y221418D01*
X1858530Y221951D01*
X1858597Y222551D01*
X1858530Y223151D01*
X1858330Y223684D01*
X1858063Y224084D01*
X1857663Y224418D01*
X1857130Y224551D01*
G01X1861730Y220551D02*
X1862197Y220618D01*
X1862730Y220818D01*
X1863063Y221151D01*
X1863197Y221618D01*
X1863063Y222084D01*
X1862663Y222484D01*
X1862063Y222684D01*
X1861397D01*
X1860997Y222818D01*
X1860663Y223151D01*
X1860530Y223618D01*
X1860730Y224084D01*
X1861197Y224418D01*
X1861730Y224551D01*
X1862263Y224418D01*
X1862730Y224084D01*
X1862930Y223618D01*
X1862797Y223151D01*
X1862463Y222818D01*
X1862063Y222684D01*
X1861397D01*
X1860797Y222484D01*
X1860397Y222084D01*
X1860263Y221618D01*
X1860397Y221151D01*
X1860730Y220818D01*
X1861263Y220618D01*
X1861730Y220551D01*
G01X1839622Y304875D02*
X1840022Y305275D01*
X1840489Y305475D01*
X1841022Y305542D01*
X1841689Y305409D01*
X1842156Y305075D01*
X1842289Y304675D01*
X1842222Y304275D01*
X1841956Y303942D01*
X1840622Y303275D01*
X1840022Y302809D01*
X1839622Y302142D01*
X1839489Y301542D01*
X1842289D01*
G01X1845489Y305542D02*
X1844956Y305409D01*
X1844556Y305075D01*
X1844289Y304675D01*
X1844089Y304142D01*
X1844022Y303542D01*
X1844089Y302942D01*
X1844289Y302409D01*
X1844556Y302009D01*
X1844956Y301675D01*
X1845489Y301542D01*
X1846022Y301675D01*
X1846422Y302009D01*
X1846689Y302409D01*
X1846889Y302942D01*
X1846956Y303542D01*
X1846889Y304142D01*
X1846689Y304675D01*
X1846422Y305075D01*
X1846022Y305409D01*
X1845489Y305542D01*
G01X1850089Y301542D02*
X1850556Y301609D01*
X1851089Y301809D01*
X1851422Y302142D01*
X1851556Y302609D01*
X1851422Y303075D01*
X1851022Y303475D01*
X1850422Y303675D01*
X1849756D01*
X1849356Y303809D01*
X1849022Y304142D01*
X1848889Y304609D01*
X1849089Y305075D01*
X1849556Y305409D01*
X1850089Y305542D01*
X1850622Y305409D01*
X1851089Y305075D01*
X1851289Y304609D01*
X1851156Y304142D01*
X1850822Y303809D01*
X1850422Y303675D01*
X1849756D01*
X1849156Y303475D01*
X1848756Y303075D01*
X1848622Y302609D01*
X1848756Y302142D01*
X1849089Y301809D01*
X1849622Y301609D01*
X1850089Y301542D01*
G01X1854689Y301409D02*
X1854556Y301475D01*
Y301609D01*
X1854689Y301675D01*
X1854822Y301609D01*
Y301475D01*
X1854689Y301409D01*
G01X1858022Y303209D02*
X1858489Y303675D01*
X1858889Y303942D01*
X1859422Y304075D01*
X1859889Y303942D01*
X1860222Y303675D01*
X1860489Y303275D01*
X1860556Y302809D01*
X1860489Y302409D01*
X1860222Y302009D01*
X1859822Y301675D01*
X1859356Y301542D01*
X1858822Y301675D01*
X1858356Y302075D01*
X1858089Y302675D01*
X1858022Y303342D01*
X1858156Y304209D01*
X1858356Y304675D01*
X1858689Y305142D01*
X1859156Y305475D01*
X1859622Y305542D01*
X1860089Y305409D01*
X1860422Y305075D01*
G01X1862622Y303209D02*
X1863089Y303675D01*
X1863489Y303942D01*
X1864022Y304075D01*
X1864489Y303942D01*
X1864822Y303675D01*
X1865089Y303275D01*
X1865156Y302809D01*
X1865089Y302409D01*
X1864822Y302009D01*
X1864422Y301675D01*
X1863956Y301542D01*
X1863422Y301675D01*
X1862956Y302075D01*
X1862689Y302675D01*
X1862622Y303342D01*
X1862756Y304209D01*
X1862956Y304675D01*
X1863289Y305142D01*
X1863756Y305475D01*
X1864222Y305542D01*
X1864689Y305409D01*
X1865022Y305075D01*
G01X1839530Y673308D02*
Y677308D01*
X1837063Y674441D01*
X1840397D01*
G01X1841863Y674108D02*
X1842263Y673641D01*
X1842797Y673375D01*
X1843397Y673308D01*
X1843930Y673375D01*
X1844463Y673708D01*
X1844797Y674108D01*
X1844863Y674508D01*
X1844730Y674975D01*
X1844263Y675308D01*
X1843797Y675441D01*
X1843197D01*
G01X1843797D02*
X1844197Y675641D01*
X1844530Y675975D01*
X1844663Y676375D01*
X1844530Y676775D01*
X1844197Y677108D01*
X1843597Y677308D01*
X1842997Y677241D01*
X1842397Y676975D01*
G01X1846463Y674108D02*
X1846863Y673641D01*
X1847397Y673375D01*
X1847997Y673308D01*
X1848530Y673375D01*
X1849063Y673708D01*
X1849397Y674108D01*
X1849463Y674508D01*
X1849330Y674975D01*
X1848863Y675308D01*
X1848397Y675441D01*
X1847797D01*
G01X1848397D02*
X1848797Y675641D01*
X1849130Y675975D01*
X1849263Y676375D01*
X1849130Y676775D01*
X1848797Y677108D01*
X1848197Y677308D01*
X1847597Y677241D01*
X1846997Y676975D01*
G01X1852530Y673175D02*
X1852397Y673241D01*
Y673375D01*
X1852530Y673441D01*
X1852663Y673375D01*
Y673241D01*
X1852530Y673175D01*
G01X1857130Y677308D02*
X1856597Y677175D01*
X1856197Y676841D01*
X1855930Y676441D01*
X1855730Y675908D01*
X1855663Y675308D01*
X1855730Y674708D01*
X1855930Y674175D01*
X1856197Y673775D01*
X1856597Y673441D01*
X1857130Y673308D01*
X1857663Y673441D01*
X1858063Y673775D01*
X1858330Y674175D01*
X1858530Y674708D01*
X1858597Y675308D01*
X1858530Y675908D01*
X1858330Y676441D01*
X1858063Y676841D01*
X1857663Y677175D01*
X1857130Y677308D01*
G01X1861730Y673308D02*
X1862197Y673375D01*
X1862730Y673575D01*
X1863063Y673908D01*
X1863197Y674375D01*
X1863063Y674841D01*
X1862663Y675241D01*
X1862063Y675441D01*
X1861397D01*
X1860997Y675575D01*
X1860663Y675908D01*
X1860530Y676375D01*
X1860730Y676841D01*
X1861197Y677175D01*
X1861730Y677308D01*
X1862263Y677175D01*
X1862730Y676841D01*
X1862930Y676375D01*
X1862797Y675908D01*
X1862463Y675575D01*
X1862063Y675441D01*
X1861397D01*
X1860797Y675241D01*
X1860397Y674841D01*
X1860263Y674375D01*
X1860397Y673908D01*
X1860730Y673575D01*
X1861263Y673375D01*
X1861730Y673308D01*
G01X1839622Y757632D02*
X1840022Y758032D01*
X1840489Y758232D01*
X1841022Y758299D01*
X1841689Y758166D01*
X1842156Y757832D01*
X1842289Y757432D01*
X1842222Y757032D01*
X1841956Y756699D01*
X1840622Y756032D01*
X1840022Y755566D01*
X1839622Y754899D01*
X1839489Y754299D01*
X1842289D01*
G01X1845489Y758299D02*
X1844956Y758166D01*
X1844556Y757832D01*
X1844289Y757432D01*
X1844089Y756899D01*
X1844022Y756299D01*
X1844089Y755699D01*
X1844289Y755166D01*
X1844556Y754766D01*
X1844956Y754432D01*
X1845489Y754299D01*
X1846022Y754432D01*
X1846422Y754766D01*
X1846689Y755166D01*
X1846889Y755699D01*
X1846956Y756299D01*
X1846889Y756899D01*
X1846689Y757432D01*
X1846422Y757832D01*
X1846022Y758166D01*
X1845489Y758299D01*
G01X1850089Y754299D02*
X1850556Y754366D01*
X1851089Y754566D01*
X1851422Y754899D01*
X1851556Y755366D01*
X1851422Y755832D01*
X1851022Y756232D01*
X1850422Y756432D01*
X1849756D01*
X1849356Y756566D01*
X1849022Y756899D01*
X1848889Y757366D01*
X1849089Y757832D01*
X1849556Y758166D01*
X1850089Y758299D01*
X1850622Y758166D01*
X1851089Y757832D01*
X1851289Y757366D01*
X1851156Y756899D01*
X1850822Y756566D01*
X1850422Y756432D01*
X1849756D01*
X1849156Y756232D01*
X1848756Y755832D01*
X1848622Y755366D01*
X1848756Y754899D01*
X1849089Y754566D01*
X1849622Y754366D01*
X1850089Y754299D01*
G01X1854689Y754166D02*
X1854556Y754232D01*
Y754366D01*
X1854689Y754432D01*
X1854822Y754366D01*
Y754232D01*
X1854689Y754166D01*
G01X1858022Y755966D02*
X1858489Y756432D01*
X1858889Y756699D01*
X1859422Y756832D01*
X1859889Y756699D01*
X1860222Y756432D01*
X1860489Y756032D01*
X1860556Y755566D01*
X1860489Y755166D01*
X1860222Y754766D01*
X1859822Y754432D01*
X1859356Y754299D01*
X1858822Y754432D01*
X1858356Y754832D01*
X1858089Y755432D01*
X1858022Y756099D01*
X1858156Y756966D01*
X1858356Y757432D01*
X1858689Y757899D01*
X1859156Y758232D01*
X1859622Y758299D01*
X1860089Y758166D01*
X1860422Y757832D01*
G01X1862622Y755966D02*
X1863089Y756432D01*
X1863489Y756699D01*
X1864022Y756832D01*
X1864489Y756699D01*
X1864822Y756432D01*
X1865089Y756032D01*
X1865156Y755566D01*
X1865089Y755166D01*
X1864822Y754766D01*
X1864422Y754432D01*
X1863956Y754299D01*
X1863422Y754432D01*
X1862956Y754832D01*
X1862689Y755432D01*
X1862622Y756099D01*
X1862756Y756966D01*
X1862956Y757432D01*
X1863289Y757899D01*
X1863756Y758232D01*
X1864222Y758299D01*
X1864689Y758166D01*
X1865022Y757832D01*
G01X1833067Y715465D02*
Y719465D01*
X1834401D01*
X1834934Y719265D01*
X1835334Y718998D01*
X1835667Y718598D01*
X1835934Y718132D01*
X1836001Y717465D01*
X1835934Y716798D01*
X1835667Y716332D01*
X1835334Y715932D01*
X1834934Y715665D01*
X1834401Y715465D01*
X1833067D01*
G01X1838201D02*
Y718132D01*
G01Y717598D02*
X1838534Y717865D01*
X1838867Y718065D01*
X1839334Y718132D01*
X1839667Y718065D01*
X1840067Y717865D01*
G01X1843734Y718132D02*
Y715465D01*
G01Y719198D02*
X1843601Y719265D01*
Y719398D01*
X1843734Y719465D01*
X1843867Y719398D01*
Y719265D01*
X1843734Y719198D01*
G01X1848334Y715465D02*
Y719465D01*
G01X1852934Y715465D02*
Y719465D01*
G01X1861734Y715465D02*
Y718865D01*
X1861867Y719198D01*
X1862134Y719398D01*
X1862534Y719465D01*
X1862934Y719332D01*
X1863134Y718998D01*
G01X1862334Y717865D02*
X1861001D01*
G01X1865734Y717265D02*
X1867867D01*
X1867667Y717732D01*
X1867334Y717998D01*
X1866867Y718132D01*
X1866401Y718065D01*
X1866001Y717865D01*
X1865734Y717398D01*
X1865601Y716998D01*
Y716598D01*
X1865734Y716198D01*
X1866067Y715798D01*
X1866467Y715532D01*
X1866934Y715465D01*
X1867401Y715598D01*
X1867867Y715998D01*
G01X1872534Y715465D02*
Y718132D01*
G01Y717665D02*
X1872267Y717932D01*
X1871867Y718065D01*
X1871401Y718132D01*
X1870934Y717998D01*
X1870534Y717732D01*
X1870267Y717332D01*
X1870134Y716798D01*
X1870267Y716265D01*
X1870534Y715865D01*
X1870934Y715598D01*
X1871401Y715465D01*
X1871867Y715532D01*
X1872267Y715732D01*
X1872534Y715998D01*
G01X1875934Y719465D02*
Y715465D01*
G01X1875001Y718132D02*
X1876867D01*
G01X1879401D02*
Y716265D01*
X1879667Y715798D01*
X1880067Y715532D01*
X1880534Y715465D01*
X1881001Y715532D01*
X1881401Y715798D01*
X1881667Y716265D01*
G01Y715465D02*
Y718132D01*
G01X1884201Y715465D02*
Y718132D01*
G01Y717598D02*
X1884534Y717865D01*
X1884867Y718065D01*
X1885334Y718132D01*
X1885667Y718065D01*
X1886067Y717865D01*
G01X1888734Y717265D02*
X1890867D01*
X1890667Y717732D01*
X1890334Y717998D01*
X1889867Y718132D01*
X1889401Y718065D01*
X1889001Y717865D01*
X1888734Y717398D01*
X1888601Y716998D01*
Y716598D01*
X1888734Y716198D01*
X1889067Y715798D01*
X1889467Y715532D01*
X1889934Y715465D01*
X1890401Y715598D01*
X1890867Y715998D01*
G01X1839530Y1126063D02*
Y1130063D01*
X1837063Y1127196D01*
X1840397D01*
G01X1841863Y1126863D02*
X1842263Y1126396D01*
X1842797Y1126130D01*
X1843397Y1126063D01*
X1843930Y1126130D01*
X1844463Y1126463D01*
X1844797Y1126863D01*
X1844863Y1127263D01*
X1844730Y1127730D01*
X1844263Y1128063D01*
X1843797Y1128196D01*
X1843197D01*
G01X1843797D02*
X1844197Y1128396D01*
X1844530Y1128730D01*
X1844663Y1129130D01*
X1844530Y1129530D01*
X1844197Y1129863D01*
X1843597Y1130063D01*
X1842997Y1129996D01*
X1842397Y1129730D01*
G01X1846463Y1126863D02*
X1846863Y1126396D01*
X1847397Y1126130D01*
X1847997Y1126063D01*
X1848530Y1126130D01*
X1849063Y1126463D01*
X1849397Y1126863D01*
X1849463Y1127263D01*
X1849330Y1127730D01*
X1848863Y1128063D01*
X1848397Y1128196D01*
X1847797D01*
G01X1848397D02*
X1848797Y1128396D01*
X1849130Y1128730D01*
X1849263Y1129130D01*
X1849130Y1129530D01*
X1848797Y1129863D01*
X1848197Y1130063D01*
X1847597Y1129996D01*
X1846997Y1129730D01*
G01X1852530Y1125930D02*
X1852397Y1125996D01*
Y1126130D01*
X1852530Y1126196D01*
X1852663Y1126130D01*
Y1125996D01*
X1852530Y1125930D01*
G01X1857130Y1130063D02*
X1856597Y1129930D01*
X1856197Y1129596D01*
X1855930Y1129196D01*
X1855730Y1128663D01*
X1855663Y1128063D01*
X1855730Y1127463D01*
X1855930Y1126930D01*
X1856197Y1126530D01*
X1856597Y1126196D01*
X1857130Y1126063D01*
X1857663Y1126196D01*
X1858063Y1126530D01*
X1858330Y1126930D01*
X1858530Y1127463D01*
X1858597Y1128063D01*
X1858530Y1128663D01*
X1858330Y1129196D01*
X1858063Y1129596D01*
X1857663Y1129930D01*
X1857130Y1130063D01*
G01X1861730Y1126063D02*
X1862197Y1126130D01*
X1862730Y1126330D01*
X1863063Y1126663D01*
X1863197Y1127130D01*
X1863063Y1127596D01*
X1862663Y1127996D01*
X1862063Y1128196D01*
X1861397D01*
X1860997Y1128330D01*
X1860663Y1128663D01*
X1860530Y1129130D01*
X1860730Y1129596D01*
X1861197Y1129930D01*
X1861730Y1130063D01*
X1862263Y1129930D01*
X1862730Y1129596D01*
X1862930Y1129130D01*
X1862797Y1128663D01*
X1862463Y1128330D01*
X1862063Y1128196D01*
X1861397D01*
X1860797Y1127996D01*
X1860397Y1127596D01*
X1860263Y1127130D01*
X1860397Y1126663D01*
X1860730Y1126330D01*
X1861263Y1126130D01*
X1861730Y1126063D01*
G01X1833067Y1168220D02*
Y1172220D01*
X1834401D01*
X1834934Y1172020D01*
X1835334Y1171753D01*
X1835667Y1171353D01*
X1835934Y1170887D01*
X1836001Y1170220D01*
X1835934Y1169553D01*
X1835667Y1169087D01*
X1835334Y1168687D01*
X1834934Y1168420D01*
X1834401Y1168220D01*
X1833067D01*
G01X1838201D02*
Y1170887D01*
G01Y1170353D02*
X1838534Y1170620D01*
X1838867Y1170820D01*
X1839334Y1170887D01*
X1839667Y1170820D01*
X1840067Y1170620D01*
G01X1843734Y1170887D02*
Y1168220D01*
G01Y1171953D02*
X1843601Y1172020D01*
Y1172153D01*
X1843734Y1172220D01*
X1843867Y1172153D01*
Y1172020D01*
X1843734Y1171953D01*
G01X1848334Y1168220D02*
Y1172220D01*
G01X1852934Y1168220D02*
Y1172220D01*
G01X1861734Y1168220D02*
Y1171620D01*
X1861867Y1171953D01*
X1862134Y1172153D01*
X1862534Y1172220D01*
X1862934Y1172087D01*
X1863134Y1171753D01*
G01X1862334Y1170620D02*
X1861001D01*
G01X1865734Y1170020D02*
X1867867D01*
X1867667Y1170487D01*
X1867334Y1170753D01*
X1866867Y1170887D01*
X1866401Y1170820D01*
X1866001Y1170620D01*
X1865734Y1170153D01*
X1865601Y1169753D01*
Y1169353D01*
X1865734Y1168953D01*
X1866067Y1168553D01*
X1866467Y1168287D01*
X1866934Y1168220D01*
X1867401Y1168353D01*
X1867867Y1168753D01*
G01X1872534Y1168220D02*
Y1170887D01*
G01Y1170420D02*
X1872267Y1170687D01*
X1871867Y1170820D01*
X1871401Y1170887D01*
X1870934Y1170753D01*
X1870534Y1170487D01*
X1870267Y1170087D01*
X1870134Y1169553D01*
X1870267Y1169020D01*
X1870534Y1168620D01*
X1870934Y1168353D01*
X1871401Y1168220D01*
X1871867Y1168287D01*
X1872267Y1168487D01*
X1872534Y1168753D01*
G01X1875934Y1172220D02*
Y1168220D01*
G01X1875001Y1170887D02*
X1876867D01*
G01X1879401D02*
Y1169020D01*
X1879667Y1168553D01*
X1880067Y1168287D01*
X1880534Y1168220D01*
X1881001Y1168287D01*
X1881401Y1168553D01*
X1881667Y1169020D01*
G01Y1168220D02*
Y1170887D01*
G01X1884201Y1168220D02*
Y1170887D01*
G01Y1170353D02*
X1884534Y1170620D01*
X1884867Y1170820D01*
X1885334Y1170887D01*
X1885667Y1170820D01*
X1886067Y1170620D01*
G01X1888734Y1170020D02*
X1890867D01*
X1890667Y1170487D01*
X1890334Y1170753D01*
X1889867Y1170887D01*
X1889401Y1170820D01*
X1889001Y1170620D01*
X1888734Y1170153D01*
X1888601Y1169753D01*
Y1169353D01*
X1888734Y1168953D01*
X1889067Y1168553D01*
X1889467Y1168287D01*
X1889934Y1168220D01*
X1890401Y1168353D01*
X1890867Y1168753D01*
G01X1839622Y1210387D02*
X1840022Y1210787D01*
X1840489Y1210987D01*
X1841022Y1211054D01*
X1841689Y1210921D01*
X1842156Y1210587D01*
X1842289Y1210187D01*
X1842222Y1209787D01*
X1841956Y1209454D01*
X1840622Y1208787D01*
X1840022Y1208321D01*
X1839622Y1207654D01*
X1839489Y1207054D01*
X1842289D01*
G01X1845489Y1211054D02*
X1844956Y1210921D01*
X1844556Y1210587D01*
X1844289Y1210187D01*
X1844089Y1209654D01*
X1844022Y1209054D01*
X1844089Y1208454D01*
X1844289Y1207921D01*
X1844556Y1207521D01*
X1844956Y1207187D01*
X1845489Y1207054D01*
X1846022Y1207187D01*
X1846422Y1207521D01*
X1846689Y1207921D01*
X1846889Y1208454D01*
X1846956Y1209054D01*
X1846889Y1209654D01*
X1846689Y1210187D01*
X1846422Y1210587D01*
X1846022Y1210921D01*
X1845489Y1211054D01*
G01X1850089Y1207054D02*
X1850556Y1207121D01*
X1851089Y1207321D01*
X1851422Y1207654D01*
X1851556Y1208121D01*
X1851422Y1208587D01*
X1851022Y1208987D01*
X1850422Y1209187D01*
X1849756D01*
X1849356Y1209321D01*
X1849022Y1209654D01*
X1848889Y1210121D01*
X1849089Y1210587D01*
X1849556Y1210921D01*
X1850089Y1211054D01*
X1850622Y1210921D01*
X1851089Y1210587D01*
X1851289Y1210121D01*
X1851156Y1209654D01*
X1850822Y1209321D01*
X1850422Y1209187D01*
X1849756D01*
X1849156Y1208987D01*
X1848756Y1208587D01*
X1848622Y1208121D01*
X1848756Y1207654D01*
X1849089Y1207321D01*
X1849622Y1207121D01*
X1850089Y1207054D01*
G01X1854689Y1206921D02*
X1854556Y1206987D01*
Y1207121D01*
X1854689Y1207187D01*
X1854822Y1207121D01*
Y1206987D01*
X1854689Y1206921D01*
G01X1858022Y1208721D02*
X1858489Y1209187D01*
X1858889Y1209454D01*
X1859422Y1209587D01*
X1859889Y1209454D01*
X1860222Y1209187D01*
X1860489Y1208787D01*
X1860556Y1208321D01*
X1860489Y1207921D01*
X1860222Y1207521D01*
X1859822Y1207187D01*
X1859356Y1207054D01*
X1858822Y1207187D01*
X1858356Y1207587D01*
X1858089Y1208187D01*
X1858022Y1208854D01*
X1858156Y1209721D01*
X1858356Y1210187D01*
X1858689Y1210654D01*
X1859156Y1210987D01*
X1859622Y1211054D01*
X1860089Y1210921D01*
X1860422Y1210587D01*
G01X1862622Y1208721D02*
X1863089Y1209187D01*
X1863489Y1209454D01*
X1864022Y1209587D01*
X1864489Y1209454D01*
X1864822Y1209187D01*
X1865089Y1208787D01*
X1865156Y1208321D01*
X1865089Y1207921D01*
X1864822Y1207521D01*
X1864422Y1207187D01*
X1863956Y1207054D01*
X1863422Y1207187D01*
X1862956Y1207587D01*
X1862689Y1208187D01*
X1862622Y1208854D01*
X1862756Y1209721D01*
X1862956Y1210187D01*
X1863289Y1210654D01*
X1863756Y1210987D01*
X1864222Y1211054D01*
X1864689Y1210921D01*
X1865022Y1210587D01*
G01X1869094Y1519685D02*
G03X1865157Y1515748I0J-3937D01*
G01X1919094Y1519685D02*
X1869094D01*
G01D02*
G03X1865157Y1515748I0J-3937D01*
G01X1919094Y1519685D02*
X1869094D01*
G01X1865157Y1515748D02*
Y1509055D01*
G01Y1515748D02*
Y1509055D01*
G01X1861220Y1505118D02*
X1835630D01*
G01X1861220D02*
G03X1865157Y1509055I0J3937D01*
G01X1861220Y1505118D02*
G03X1865157Y1509055I0J3937D01*
G01X1835630Y1505118D02*
X1861220D01*
G01X1831693Y1515748D02*
G03X1827756Y1519685I-3937J0D01*
G01X1831693Y1515748D02*
G03X1827756Y1519685I-3937J0D01*
G01X1831693Y1509055D02*
Y1515748D01*
G01Y1509055D02*
G03X1835630Y1505118I3937J0D01*
G01X1831693Y1509055D02*
G03X1835630Y1505118I3937J0D01*
G01X1831693Y1515748D02*
Y1509055D01*
G01X1930906Y0D02*
G03X1934843Y3937I0J3937D01*
G01X1930906Y0D02*
G03X1934843Y3937I0J3937D01*
G01D02*
Y1456693D01*
G01Y3937D02*
Y1456693D01*
G01X1930906Y1460630D02*
X1926969D01*
G01X1934843Y1456693D02*
G03X1930906Y1460630I-3937J0D01*
G01X1934843Y1456693D02*
G03X1930906Y1460630I-3937J0D01*
G01D02*
X1926969D01*
G01X1923031Y1515748D02*
G03X1919094Y1519685I-3937J0D01*
G01X1923031Y1515748D02*
G03X1919094Y1519685I-3937J0D01*
G01X1923031Y1464567D02*
Y1515748D01*
G01Y1464567D02*
G03X1926969Y1460630I3937J0D01*
G01X1923031Y1464567D02*
G03X1926969Y1460630I3937J0D01*
G01X1923031Y1515748D02*
Y1464567D01*
G54D23*
X266535Y1320472D03*
X511535D03*
X2261450Y437500D03*
G54D14*
X127988Y67319D03*
Y71319D03*
Y76319D03*
Y80319D03*
X134983Y65269D03*
Y61269D03*
Y56769D03*
Y52769D03*
X127988Y520075D03*
Y524075D03*
Y529075D03*
Y533075D03*
X134983Y518025D03*
Y514025D03*
Y509525D03*
Y505525D03*
X127988Y972831D03*
Y976831D03*
Y981831D03*
Y985831D03*
X134983Y970781D03*
Y966781D03*
Y962281D03*
Y958281D03*
X252200Y67319D03*
Y71319D03*
Y76319D03*
Y80319D03*
X259195Y65269D03*
Y61269D03*
Y56769D03*
Y52769D03*
X252200Y520075D03*
Y524075D03*
Y529075D03*
Y533075D03*
X259195Y518025D03*
Y514025D03*
Y509525D03*
Y505525D03*
X252200Y972831D03*
Y976831D03*
Y981831D03*
Y985831D03*
X259195Y970781D03*
Y966781D03*
Y962281D03*
Y958281D03*
X376413Y67319D03*
Y71319D03*
Y76319D03*
Y80319D03*
X383408Y65269D03*
Y61269D03*
Y56769D03*
Y52769D03*
X376413Y520075D03*
Y524075D03*
Y529075D03*
Y533075D03*
X383408Y518025D03*
Y514025D03*
Y509525D03*
Y505525D03*
X376413Y972831D03*
Y976831D03*
Y981831D03*
Y985831D03*
X383408Y970781D03*
Y966781D03*
Y962281D03*
Y958281D03*
X500625Y67319D03*
Y71319D03*
Y76319D03*
Y80319D03*
X507620Y65269D03*
Y61269D03*
Y56769D03*
Y52769D03*
X500625Y520075D03*
Y524075D03*
Y529075D03*
Y533075D03*
X507620Y518025D03*
Y514025D03*
Y509525D03*
Y505525D03*
X500625Y972831D03*
Y976831D03*
Y981831D03*
Y985831D03*
X507620Y970781D03*
Y966781D03*
Y962281D03*
Y958281D03*
X500000Y1472000D03*
X624838Y67319D03*
Y71319D03*
Y76319D03*
Y80319D03*
X631833Y65269D03*
Y61269D03*
Y56769D03*
Y52769D03*
X624838Y520075D03*
Y524075D03*
Y529075D03*
Y533075D03*
X631833Y518025D03*
Y514025D03*
Y509525D03*
Y505525D03*
X624838Y972831D03*
Y976831D03*
Y981831D03*
Y985831D03*
X631833Y970781D03*
Y966781D03*
Y962281D03*
Y958281D03*
X749051Y67319D03*
Y71319D03*
Y76319D03*
Y80319D03*
X756046Y65269D03*
Y61269D03*
Y56769D03*
Y52769D03*
X749051Y520075D03*
Y524075D03*
Y529075D03*
Y533075D03*
X756046Y518025D03*
Y514025D03*
Y509525D03*
Y505525D03*
X749051Y972831D03*
Y976831D03*
Y981831D03*
Y985831D03*
X756046Y970781D03*
Y966781D03*
Y962281D03*
Y958281D03*
X918400Y760750D03*
X1279400Y68650D03*
X1275400D03*
X1270400D03*
X1266400D03*
X1252750Y53650D03*
X1256750D03*
X1261250D03*
X1265250D03*
X1279400Y521406D03*
X1275400D03*
X1270400D03*
X1266400D03*
X1252750Y506406D03*
X1256750D03*
X1261250D03*
X1265250D03*
X1273975Y972831D03*
Y976831D03*
Y981831D03*
Y985831D03*
X1257490Y970361D03*
Y966361D03*
Y961861D03*
Y957861D03*
X1403613Y68650D03*
X1399613D03*
X1394613D03*
X1390613D03*
X1376963Y53650D03*
X1380963D03*
X1385463D03*
X1389463D03*
X1403613Y521406D03*
X1399613D03*
X1394613D03*
X1390613D03*
X1376963Y506406D03*
X1380963D03*
X1385463D03*
X1389463D03*
X1398188Y972831D03*
Y976831D03*
Y981831D03*
Y985831D03*
X1381663Y970381D03*
Y966381D03*
Y961881D03*
Y957881D03*
X1527825Y68650D03*
X1523825D03*
X1518825D03*
X1514825D03*
X1501175Y53650D03*
X1505175D03*
X1509675D03*
X1513675D03*
X1527825Y521406D03*
X1523825D03*
X1518825D03*
X1514825D03*
X1501175Y506406D03*
X1505175D03*
X1509675D03*
X1513675D03*
X1522400Y972831D03*
Y976831D03*
Y981831D03*
Y985831D03*
X1505875Y970321D03*
Y966321D03*
Y961821D03*
Y957821D03*
X1625388Y53650D03*
Y506406D03*
X1652038Y68650D03*
X1648038D03*
X1643038D03*
X1639038D03*
X1629388Y53650D03*
X1633888D03*
X1637888D03*
X1652038Y521406D03*
X1648038D03*
X1643038D03*
X1639038D03*
X1629388Y506406D03*
X1633888D03*
X1637888D03*
X1646613Y972831D03*
Y976831D03*
Y981831D03*
Y985831D03*
X1630088Y970881D03*
Y966881D03*
Y962381D03*
Y958381D03*
X1776250Y68650D03*
X1772250D03*
X1767250D03*
X1763250D03*
X1749600Y53650D03*
X1753600D03*
X1758100D03*
X1762100D03*
X1776250Y521406D03*
X1772250D03*
X1767250D03*
X1763250D03*
X1749600Y506406D03*
X1753600D03*
X1758100D03*
X1762100D03*
X1770825Y972831D03*
Y976831D03*
Y981831D03*
Y985831D03*
X1754340Y970361D03*
Y966361D03*
Y961861D03*
Y957861D03*
X1900463Y68650D03*
X1896463D03*
X1891463D03*
X1887463D03*
X1873813Y53650D03*
X1877813D03*
X1882313D03*
X1886313D03*
X1900463Y521406D03*
X1896463D03*
X1891463D03*
X1887463D03*
X1873813Y506406D03*
X1877813D03*
X1882313D03*
X1886313D03*
X1895038Y972831D03*
Y976831D03*
Y981831D03*
Y985831D03*
X1878553Y970361D03*
Y966361D03*
Y961861D03*
Y957861D03*
X2261450Y1285900D03*
G54D24*
X384055Y1330472D03*
Y1320472D03*
X354055Y1330472D03*
X364055D03*
X354055Y1320472D03*
X364055D03*
X324055Y1330472D03*
X334055D03*
X324055Y1320472D03*
X334055D03*
X304055Y1330472D03*
Y1320472D03*
X294055Y1330472D03*
Y1320472D03*
X384055Y1340472D03*
Y1350472D03*
X354055Y1340472D03*
Y1350472D03*
X364055Y1340472D03*
Y1350472D03*
X324055Y1340472D03*
Y1350472D03*
X334055Y1340472D03*
Y1350472D03*
X304055D03*
Y1340472D03*
X294055Y1350472D03*
Y1340472D03*
X474055Y1330472D03*
X484055D03*
X474055Y1320472D03*
X484055D03*
X444055Y1330472D03*
X454055D03*
X444055Y1320472D03*
X454055D03*
X414055Y1330472D03*
X424055D03*
X414055Y1320472D03*
X424055D03*
X394055Y1330472D03*
Y1320472D03*
X474055Y1340472D03*
Y1350472D03*
X484055Y1340472D03*
Y1350472D03*
X444055Y1340472D03*
Y1350472D03*
X454055Y1340472D03*
Y1350472D03*
X414055Y1340472D03*
Y1350472D03*
X424055Y1340472D03*
Y1350472D03*
X394055Y1340472D03*
Y1350472D03*
X2261450Y801100D03*
G54D15*
X111024Y39508D03*
Y492264D03*
Y945020D03*
X235236Y39508D03*
Y492264D03*
Y945020D03*
X359449Y39508D03*
Y492264D03*
Y945020D03*
X483661Y39508D03*
Y492264D03*
Y945020D03*
X607874Y39508D03*
Y492264D03*
Y945020D03*
X732087Y39508D03*
Y492264D03*
Y945020D03*
X1281693Y39508D03*
Y492264D03*
Y945020D03*
X1405906Y39508D03*
Y492264D03*
Y945020D03*
X1530118Y39508D03*
Y492264D03*
Y945020D03*
X1654331Y39508D03*
Y492264D03*
Y945020D03*
X1778543Y39508D03*
Y492264D03*
Y945020D03*
X1902756Y39508D03*
Y492264D03*
Y945020D03*
X2261450Y619300D03*
G54D25*
X462000Y1382985D03*
Y1372985D03*
Y1362985D03*
X474000Y1382985D03*
Y1372985D03*
Y1362985D03*
X426000D03*
X450000Y1372985D03*
Y1382985D03*
X414000Y1372985D03*
X450000Y1362985D03*
X438000Y1372985D03*
X414000Y1362985D03*
X438000D03*
X426000Y1372985D03*
X438000Y1382985D03*
X414000D03*
X426000D03*
X498000Y1332985D03*
X510000Y1344485D03*
X498000Y1352985D03*
X522000Y1344485D03*
X498000Y1342985D03*
X510000Y1354485D03*
X522000D03*
X510000Y1364485D03*
X522000D03*
X510000Y1374485D03*
Y1384485D03*
X522000Y1374485D03*
Y1384485D03*
X498000Y1382985D03*
Y1372985D03*
X486000Y1382985D03*
Y1372985D03*
X498000Y1362985D03*
X486000D03*
X658200Y1329200D03*
X666100D03*
X581800Y1321200D03*
Y1329100D03*
X589700D03*
Y1321200D03*
X594800Y1313500D03*
X597600Y1321200D03*
Y1329100D03*
X610600Y1313500D03*
Y1305600D03*
Y1297600D03*
X602700Y1313500D03*
Y1305600D03*
Y1297600D03*
X629200Y1329100D03*
X605500Y1321200D03*
X613400D03*
X605500Y1329100D03*
X613400D03*
X621300D03*
X666100Y1360800D03*
Y1368700D03*
Y1376600D03*
Y1352900D03*
X658200Y1360800D03*
Y1368700D03*
Y1376600D03*
Y1352900D03*
X666100Y1337100D03*
Y1345000D03*
X658200Y1337100D03*
Y1345000D03*
X581800Y1376500D03*
Y1384400D03*
Y1392300D03*
Y1360700D03*
Y1368600D03*
Y1352800D03*
Y1344900D03*
Y1337000D03*
X589700Y1392300D03*
Y1400200D03*
Y1344900D03*
Y1352800D03*
Y1384400D03*
Y1376500D03*
Y1368600D03*
Y1360700D03*
Y1337000D03*
X597600Y1400200D03*
Y1408100D03*
Y1360700D03*
Y1368600D03*
Y1392300D03*
Y1376500D03*
Y1384400D03*
Y1352800D03*
Y1337000D03*
Y1344900D03*
X629200D03*
X621300D03*
X613400D03*
X605500D03*
Y1360700D03*
X613400D03*
X621300D03*
X629200D03*
X605500Y1352800D03*
X613400D03*
X621300D03*
X629200D03*
Y1368600D03*
Y1376500D03*
X605500Y1408100D03*
Y1400200D03*
Y1392300D03*
Y1384400D03*
Y1376500D03*
Y1368600D03*
X613400Y1400200D03*
Y1392300D03*
Y1384400D03*
Y1376500D03*
Y1368600D03*
X621300Y1376500D03*
Y1368600D03*
X629200Y1337000D03*
X613400D03*
X621300D03*
X605500D03*
X613400Y1408100D03*
X705600Y1329200D03*
X697700Y1321300D03*
Y1329200D03*
X689800D03*
Y1321300D03*
X693800Y1313900D03*
Y1306000D03*
X685900D03*
X678000D03*
Y1313900D03*
X685900D03*
X681900Y1321300D03*
X674000D03*
Y1329200D03*
X681900D03*
X693800Y1298000D03*
X685900D03*
X678000D03*
X768867Y1311110D03*
Y1335110D03*
Y1327110D03*
Y1319110D03*
X705600Y1337100D03*
Y1360800D03*
Y1352900D03*
Y1345000D03*
Y1376600D03*
Y1368700D03*
X699600Y1408200D03*
Y1392400D03*
Y1400300D03*
X697700Y1345000D03*
Y1360800D03*
Y1368700D03*
Y1376600D03*
X697100Y1384600D03*
X697700Y1352900D03*
Y1337100D03*
X691700Y1408200D03*
Y1400300D03*
X675900D03*
X683800D03*
Y1408200D03*
X675900D03*
X689800Y1352900D03*
Y1384500D03*
Y1376600D03*
X691700Y1392400D03*
X689800Y1368700D03*
Y1360800D03*
X674000D03*
X681900D03*
Y1368700D03*
X674000D03*
X675900Y1392400D03*
X683800D03*
X674000Y1376600D03*
X681900D03*
Y1384500D03*
X674000D03*
Y1352900D03*
X681900D03*
X689800Y1345000D03*
Y1337100D03*
X681900D03*
X674000D03*
X681900Y1345000D03*
X674000D03*
X768867Y1383110D03*
Y1359110D03*
Y1367110D03*
Y1351110D03*
Y1343110D03*
Y1391110D03*
Y1399110D03*
Y1375110D03*
X786200Y1334100D03*
X794200D03*
X801000Y1333800D03*
X786200Y1326100D03*
X794200D03*
X776867Y1311110D03*
Y1335110D03*
Y1327110D03*
Y1319110D03*
X775600Y1302400D03*
X801000Y1325800D03*
X790056Y1297863D03*
X798056D03*
X782056D03*
X834000Y1324500D03*
Y1317500D03*
Y1310500D03*
Y1303500D03*
X827000D03*
X820000D03*
X827000Y1310500D03*
X820000D03*
X827000Y1317500D03*
X820000D03*
X827000Y1324500D03*
X820000D03*
X776867Y1399110D03*
X790330Y1407929D03*
X782330D03*
X798330D03*
X795000Y1377900D03*
X786600Y1378100D03*
X790950Y1372703D03*
X776867Y1383110D03*
Y1359110D03*
X782950Y1372703D03*
X776867Y1367110D03*
Y1375110D03*
X798950Y1372703D03*
X776867Y1391110D03*
X790223Y1339930D03*
X782223Y1339430D03*
X798223Y1339930D03*
X776867Y1351110D03*
Y1343110D03*
X834000Y1386000D03*
Y1379000D03*
Y1363000D03*
Y1356000D03*
Y1349000D03*
Y1342000D03*
X827000D03*
X820000D03*
X827000Y1349000D03*
X820000D03*
X827000Y1356000D03*
X820000D03*
X827000Y1363000D03*
X820000D03*
X827000Y1379000D03*
X820000D03*
X827000Y1386000D03*
X820000D03*
X827000Y1393000D03*
X820000D03*
X958200Y1303900D03*
X942400D03*
X950300D03*
X934500D03*
X926600D03*
X958200Y1311800D03*
X926600D03*
X934500D03*
X950300D03*
X942400D03*
X903500Y1319400D03*
X950300Y1319700D03*
X958200D03*
X934500D03*
X942400D03*
X926600D03*
X918700D03*
X910800D03*
X887800Y1327100D03*
X934700Y1327500D03*
X895200D03*
X903100D03*
X911000D03*
X926800D03*
X918900D03*
X887800Y1335000D03*
X886400Y1368100D03*
Y1376000D03*
X894300D03*
Y1368100D03*
X934700Y1335400D03*
X926800D03*
X918900D03*
X895200D03*
X903100D03*
X911000D03*
X890400Y1358900D03*
X887800Y1350800D03*
Y1342900D03*
X937300Y1359300D03*
X934700Y1343300D03*
Y1351200D03*
X926800Y1343300D03*
Y1351200D03*
X929400Y1359300D03*
X918900Y1343300D03*
Y1351200D03*
X921500Y1359300D03*
X918000Y1368100D03*
Y1376000D03*
X910100Y1368100D03*
Y1376000D03*
X911000Y1343300D03*
Y1351200D03*
X913600Y1359300D03*
X903100Y1343300D03*
Y1351200D03*
X905700Y1359300D03*
X902200Y1376000D03*
Y1368100D03*
X897800Y1359300D03*
X895200Y1351200D03*
Y1343300D03*
X998600Y1300900D03*
X991500Y1312100D03*
X1020800Y1300400D03*
X991455Y1320416D03*
X996400Y1315900D03*
X996200Y1307800D03*
X1014000Y1300600D03*
X991755Y1327716D03*
X996055Y1324116D03*
X1007100Y1301100D03*
X1011100Y1305300D03*
X1019829Y1306139D03*
X1002700Y1305700D03*
X991800Y1303400D03*
X1000200Y1311700D03*
Y1320500D03*
X1016429Y1333939D03*
X1021829D03*
X1011029D03*
X1005629D03*
X986755Y1323816D03*
X986700Y1307600D03*
X1000200Y1328100D03*
X1050818Y1311189D03*
Y1316589D03*
X1045418Y1321989D03*
X1050818D03*
X1034618Y1311189D03*
X1040018D03*
X1045418D03*
X1040018Y1316589D03*
X1034618D03*
X1040018Y1321989D03*
X1031600Y1335100D03*
X1037200Y1335000D03*
X1034618Y1321989D03*
X997900Y1335800D03*
X992500D03*
X997900Y1341200D03*
X992500D03*
X997900Y1346600D03*
X992500D03*
X997900Y1352000D03*
X992500D03*
Y1357400D03*
X997900D03*
X989083Y1387764D03*
X989509Y1393422D03*
X994700Y1385000D03*
X999700Y1374500D03*
X989100Y1381700D03*
X994200Y1362700D03*
X1019829Y1389539D03*
X1013692Y1389688D03*
X1019829Y1361739D03*
X1014306Y1361710D03*
X1008870Y1361681D03*
X1003367Y1361655D03*
X1004217Y1389394D03*
X1008298Y1393071D03*
X994400Y1377300D03*
X999930Y1393070D03*
X999800Y1381600D03*
X999900Y1366800D03*
X994300Y1370100D03*
X989200Y1374800D03*
X988900Y1366900D03*
X1034600Y1349600D03*
X1042400Y1349500D03*
X1037540Y1344964D03*
X1034799Y1340183D03*
X1044700Y1335500D03*
X1043300Y1342500D03*
X1048000Y1346100D03*
X1037111Y1372380D03*
X1039988Y1367352D03*
X1044400Y1363100D03*
X1036900Y1362600D03*
X1034380Y1367469D03*
X1031300Y1362700D03*
X1042100Y1377100D03*
X1034300Y1377200D03*
X1047401Y1375084D03*
X1066481Y1327759D03*
X1061081D03*
X1066481Y1333159D03*
X1061081D03*
X1061618Y1316589D03*
X1056218Y1311189D03*
X1061618D03*
X1056218Y1316589D03*
X1060218Y1321989D03*
X1066491Y1319983D03*
X1066407Y1313972D03*
X1066481Y1338559D03*
X1061081D03*
X1066481Y1343959D03*
X1061081D03*
X1066481Y1376359D03*
Y1349359D03*
Y1354759D03*
Y1360159D03*
Y1365559D03*
Y1370959D03*
X1061081Y1376359D03*
Y1370959D03*
Y1365559D03*
Y1360159D03*
Y1354759D03*
Y1349359D03*
X2261450Y982900D03*
G54D16*
X173228Y55118D03*
X421653Y94488D03*
X670078Y55118D03*
X1343701D03*
X1592126Y94488D03*
X1840551Y55118D03*
X2261450Y679900D03*
G54D26*
X503248Y715748D03*
X1673917Y262992D03*
X2261450Y134500D03*
G54D17*
X111024Y188130D03*
Y640886D03*
Y1093642D03*
X235236Y188130D03*
Y640886D03*
Y1093642D03*
X359449Y188130D03*
Y640886D03*
Y1093642D03*
X483661Y188130D03*
Y640886D03*
Y1093642D03*
X607874Y188130D03*
Y640886D03*
Y1093642D03*
X732087Y188130D03*
Y640886D03*
Y1093642D03*
X1281693Y188130D03*
Y640886D03*
Y1093642D03*
X1405906Y188130D03*
Y640886D03*
Y1093642D03*
X1530118Y188130D03*
Y640886D03*
Y1093642D03*
X1654331Y188130D03*
Y640886D03*
Y1093642D03*
X1778543Y188130D03*
Y640886D03*
Y1093642D03*
X1902756Y188130D03*
Y640886D03*
Y1093642D03*
X2261450Y558700D03*
G54D27*
X862205Y277953D03*
X848032D03*
X833859D03*
X862205Y272441D03*
X848032D03*
X833859D03*
X862205Y263779D03*
X848032D03*
X833859D03*
X862205Y258268D03*
X848032D03*
X833859D03*
X862205Y282283D03*
X848032D03*
X833859D03*
X862205Y268110D03*
X848032D03*
X833859D03*
X862205Y253937D03*
X848032D03*
X833859D03*
X855118Y282677D03*
X840945D03*
X826772D03*
X855118Y277165D03*
X840945D03*
X826772D03*
X855118Y272835D03*
X840945D03*
X826772D03*
X855118Y268504D03*
X840945D03*
X826772D03*
X855118Y262992D03*
X840945D03*
X826772D03*
X862205Y306299D03*
X848032D03*
X833859D03*
X862205Y300787D03*
X848032D03*
X833859D03*
X862205Y292126D03*
X848032D03*
X833859D03*
X862205Y286614D03*
X848032D03*
X833859D03*
X862205Y310630D03*
X848032D03*
X833859D03*
X862205Y296457D03*
X848032D03*
X833859D03*
X855118Y311023D03*
X840945D03*
X826772D03*
X855118Y305512D03*
X840945D03*
X826772D03*
X855118Y296850D03*
X840945D03*
X826772D03*
X855118Y291338D03*
X840945D03*
X826772D03*
X855118Y315354D03*
X840945D03*
X826772D03*
X855118Y301181D03*
X840945D03*
X826772D03*
X855118Y287008D03*
X840945D03*
X826772D03*
X904725Y272835D03*
Y277165D03*
Y282677D03*
X911811Y272441D03*
Y277953D03*
Y282283D03*
X904725Y262992D03*
Y268504D03*
X911811Y253937D03*
Y258268D03*
Y263779D03*
Y268110D03*
X897638Y282283D03*
Y272441D03*
Y277953D03*
Y253937D03*
Y268110D03*
Y258268D03*
Y263779D03*
X890552Y272835D03*
Y277165D03*
Y282677D03*
Y262992D03*
Y268504D03*
X876378Y277953D03*
Y272441D03*
Y263779D03*
Y258268D03*
Y282283D03*
Y268110D03*
Y253937D03*
X869292Y282677D03*
Y277165D03*
Y272835D03*
Y268504D03*
Y262992D03*
X904725Y305512D03*
Y311023D03*
Y315354D03*
X911811Y306299D03*
Y310630D03*
X904725Y301181D03*
X911811Y300787D03*
X904725Y287008D03*
Y291338D03*
Y296850D03*
X911811Y286614D03*
Y292126D03*
Y296457D03*
X897638Y310630D03*
Y306299D03*
Y296457D03*
Y286614D03*
Y292126D03*
Y300787D03*
X890552Y315354D03*
Y305512D03*
Y311023D03*
Y287008D03*
Y301181D03*
Y291338D03*
Y296850D03*
X876378Y306299D03*
Y300787D03*
Y292126D03*
Y286614D03*
Y310630D03*
Y296457D03*
X869292Y311023D03*
Y305512D03*
Y296850D03*
Y291338D03*
Y315354D03*
Y301181D03*
Y287008D03*
X1091089Y520057D03*
X1095420D03*
X1100932D03*
X1105262D03*
X1109593D03*
X1115105D03*
X1119435D03*
X1123766D03*
X1129278D03*
X1133609D03*
X1095026Y527143D03*
X1099357D03*
X1104869D03*
X1109199D03*
X1113530D03*
X1119042D03*
X1123372D03*
X1127703D03*
X1133215D03*
X1091089Y534230D03*
X1095420D03*
X1100932D03*
X1105262D03*
X1109593D03*
X1115105D03*
X1119435D03*
X1123766D03*
X1129278D03*
X1133609D03*
X1095026Y541317D03*
X1099357D03*
X1104869D03*
X1109199D03*
X1113530D03*
X1119042D03*
X1123372D03*
X1127703D03*
X1133215D03*
X1091089Y548403D03*
X1095420D03*
X1100932D03*
X1105262D03*
X1109593D03*
X1115105D03*
X1119435D03*
X1123766D03*
X1129278D03*
X1133609D03*
X1095026Y555490D03*
X1099357D03*
X1104869D03*
X1109199D03*
X1113530D03*
X1119042D03*
X1123372D03*
X1127703D03*
X1133215D03*
X1091089Y562576D03*
X1095420D03*
X1100932D03*
X1105262D03*
X1109593D03*
X1115105D03*
X1119435D03*
X1123766D03*
X1129278D03*
X1133609D03*
X1095026Y569663D03*
X1099357D03*
X1104869D03*
X1109199D03*
X1113530D03*
X1119042D03*
X1123372D03*
X1127703D03*
X1133215D03*
X1091089Y691711D03*
Y705884D03*
Y720057D03*
Y734230D03*
Y748403D03*
Y762577D03*
X1095420Y691711D03*
Y705884D03*
Y720057D03*
Y734230D03*
Y748403D03*
Y762577D03*
X1100932Y691711D03*
Y705884D03*
Y720057D03*
Y734230D03*
Y748403D03*
Y762577D03*
X1105262Y691711D03*
Y705884D03*
Y720057D03*
Y734230D03*
Y748403D03*
Y762577D03*
X1109593Y691711D03*
Y705884D03*
Y720057D03*
Y734230D03*
Y748403D03*
Y762577D03*
X1115105Y691711D03*
Y705884D03*
Y720057D03*
Y734230D03*
Y748403D03*
Y762577D03*
X1119435Y691711D03*
Y705884D03*
Y720057D03*
Y734230D03*
Y748403D03*
Y762577D03*
X1123766Y691711D03*
Y705884D03*
Y720057D03*
Y734230D03*
Y748403D03*
Y762577D03*
X1129278Y691711D03*
Y705884D03*
Y720057D03*
Y734230D03*
Y748403D03*
Y762577D03*
X1133609Y691711D03*
Y705884D03*
Y720057D03*
Y734230D03*
Y748403D03*
Y762577D03*
X1095026Y698797D03*
Y712970D03*
Y727144D03*
Y741317D03*
Y755490D03*
X1099357Y698797D03*
Y712970D03*
Y727144D03*
Y741317D03*
Y755490D03*
X1104869Y698797D03*
Y712970D03*
Y727144D03*
Y741317D03*
Y755490D03*
X1109199Y698797D03*
Y712970D03*
Y727144D03*
Y741317D03*
Y755490D03*
X1113530Y698797D03*
Y712970D03*
Y727144D03*
Y741317D03*
Y755490D03*
X1119042Y698797D03*
Y712970D03*
Y727144D03*
Y741317D03*
Y755490D03*
X1123372Y698797D03*
Y712970D03*
Y727144D03*
Y741317D03*
Y755490D03*
X1127703Y698797D03*
Y712970D03*
Y727144D03*
Y741317D03*
Y755490D03*
X1133215Y698797D03*
Y712970D03*
Y727144D03*
Y741317D03*
Y755490D03*
X1091089Y776750D03*
Y790923D03*
Y805096D03*
Y819270D03*
Y833443D03*
Y847616D03*
X1095420Y776750D03*
Y790923D03*
Y805096D03*
Y819270D03*
Y833443D03*
Y847616D03*
X1100932Y776750D03*
Y790923D03*
Y805096D03*
Y819270D03*
Y833443D03*
Y847616D03*
X1105262Y776750D03*
Y790923D03*
Y805096D03*
Y819270D03*
Y833443D03*
Y847616D03*
X1109593Y776750D03*
Y790923D03*
Y805096D03*
Y819270D03*
Y833443D03*
Y847616D03*
X1115105Y776750D03*
Y790923D03*
Y805096D03*
Y819270D03*
Y833443D03*
Y847616D03*
X1119435Y776750D03*
Y790923D03*
Y805096D03*
Y819270D03*
Y833443D03*
Y847616D03*
X1123766Y776750D03*
Y790923D03*
Y805096D03*
Y819270D03*
Y833443D03*
Y847616D03*
X1129278Y776750D03*
Y790923D03*
Y805096D03*
Y819270D03*
Y833443D03*
Y847616D03*
X1133609Y776750D03*
Y790923D03*
Y805096D03*
Y819270D03*
Y833443D03*
Y847616D03*
X1095026Y769663D03*
Y783836D03*
Y798010D03*
Y812183D03*
Y826356D03*
Y840529D03*
Y854703D03*
X1099357Y769663D03*
Y783836D03*
Y798010D03*
Y812183D03*
Y826356D03*
Y840529D03*
Y854703D03*
X1104869Y769663D03*
Y783836D03*
Y798010D03*
Y812183D03*
Y826356D03*
Y840529D03*
Y854703D03*
X1109199Y769663D03*
Y783836D03*
Y798010D03*
Y812183D03*
Y826356D03*
Y840529D03*
Y854703D03*
X1113530Y769663D03*
Y783836D03*
Y798010D03*
Y812183D03*
Y826356D03*
Y840529D03*
Y854703D03*
X1119042Y769663D03*
Y783836D03*
Y798010D03*
Y812183D03*
Y826356D03*
Y840529D03*
Y854703D03*
X1123372Y769663D03*
Y783836D03*
Y798010D03*
Y812183D03*
Y826356D03*
Y840529D03*
Y854703D03*
X1127703Y769663D03*
Y783836D03*
Y798010D03*
Y812183D03*
Y826356D03*
Y840529D03*
Y854703D03*
X1133215Y769663D03*
Y783836D03*
Y798010D03*
Y812183D03*
Y826356D03*
Y840529D03*
Y854703D03*
X1091089Y861789D03*
Y875962D03*
Y890136D03*
Y904309D03*
Y918482D03*
Y932655D03*
X1095420Y861789D03*
Y875962D03*
Y890136D03*
Y904309D03*
Y918482D03*
Y932655D03*
X1100932Y861789D03*
Y875962D03*
Y890136D03*
Y904309D03*
Y918482D03*
Y932655D03*
X1105262Y861789D03*
Y875962D03*
Y890136D03*
Y904309D03*
Y918482D03*
Y932655D03*
X1109593Y861789D03*
Y875962D03*
Y890136D03*
Y904309D03*
Y918482D03*
Y932655D03*
X1115105Y861789D03*
Y875962D03*
Y890136D03*
Y904309D03*
Y918482D03*
Y932655D03*
X1119435Y861789D03*
Y875962D03*
Y890136D03*
Y904309D03*
Y918482D03*
Y932655D03*
X1123766Y861789D03*
Y875962D03*
Y890136D03*
Y904309D03*
Y918482D03*
Y932655D03*
X1129278Y861789D03*
Y875962D03*
Y890136D03*
Y904309D03*
Y918482D03*
Y932655D03*
X1133609Y861789D03*
Y875962D03*
Y890136D03*
Y904309D03*
Y918482D03*
Y932655D03*
X1095026Y868876D03*
Y883049D03*
Y897222D03*
Y911396D03*
Y925569D03*
Y939742D03*
X1099357Y868876D03*
Y883049D03*
Y897222D03*
Y911396D03*
Y925569D03*
Y939742D03*
X1104869Y868876D03*
Y883049D03*
Y897222D03*
Y911396D03*
Y925569D03*
Y939742D03*
X1109199Y868876D03*
Y883049D03*
Y897222D03*
Y911396D03*
Y925569D03*
Y939742D03*
X1113530Y868876D03*
Y883049D03*
Y897222D03*
Y911396D03*
Y925569D03*
Y939742D03*
X1119042Y868876D03*
Y883049D03*
Y897222D03*
Y911396D03*
Y925569D03*
Y939742D03*
X1123372Y868876D03*
Y883049D03*
Y897222D03*
Y911396D03*
Y925569D03*
Y939742D03*
X1127703Y868876D03*
Y883049D03*
Y897222D03*
Y911396D03*
Y925569D03*
Y939742D03*
X1133215Y868876D03*
Y883049D03*
Y897222D03*
Y911396D03*
Y925569D03*
Y939742D03*
X2261450Y1104100D03*
G54D18*
X173228Y122047D03*
X670079D03*
X1343701Y122046D03*
X1840551D03*
X2261450Y376900D03*
G54D28*
X855100Y258531D03*
X841000D03*
X826700D03*
X869300D03*
X1137600Y527100D03*
X1137446Y541317D03*
Y555490D03*
Y569663D03*
Y698798D03*
Y712971D03*
Y727144D03*
Y741317D03*
Y755490D03*
Y769663D03*
Y783836D03*
Y798010D03*
Y812183D03*
Y826356D03*
Y840529D03*
Y854703D03*
Y868876D03*
Y883049D03*
Y897222D03*
Y911396D03*
Y925569D03*
Y939742D03*
X2261450Y1164700D03*
G54D19*
X131200Y251181D03*
Y703937D03*
Y1156692D03*
X379232Y251181D03*
Y703937D03*
Y1156692D03*
X627263Y251181D03*
Y703937D03*
Y1156692D03*
X747244Y370078D03*
Y803149D03*
X961417Y692125D03*
Y960629D03*
X1181889Y370078D03*
Y960629D03*
X1301870Y251180D03*
Y703937D03*
Y1156692D03*
X1549901Y251181D03*
Y703937D03*
Y1156692D03*
X1797933Y251180D03*
Y703937D03*
Y1156692D03*
X2261450Y1346500D03*
G54D29*
X974015Y284449D03*
X986614D03*
X1002362D03*
X1014960D03*
X1030709D03*
X1043307D03*
X974015Y261812D03*
X986614D03*
X1002362D03*
X1014960D03*
X1030709D03*
X1043307D03*
X974015Y278544D03*
X1002362D03*
X1030709D03*
X974015Y267717D03*
X1002362D03*
X1030709D03*
X974015Y255906D03*
X1002362D03*
X1030709D03*
X986614Y278544D03*
X1014960D03*
X1043307D03*
X986614Y267717D03*
X1014960D03*
X1043307D03*
X986614Y255906D03*
X1014960D03*
X1043307D03*
X974015Y307087D03*
X986614D03*
X1002362D03*
X1014960D03*
X1030709D03*
X1043307D03*
X974015Y312993D03*
X1002362D03*
X1030709D03*
X974015Y301182D03*
X1002362D03*
X1030709D03*
X974015Y290355D03*
X1002362D03*
X1030709D03*
X986614Y312993D03*
X1014960D03*
X1043307D03*
X986614Y301182D03*
X1014960D03*
X1043307D03*
X986614Y290355D03*
X1014960D03*
X1043307D03*
X1101405Y1120040D03*
X1119633D03*
X1101405Y1132638D03*
X1119633D03*
X1108098Y1120040D03*
X1126326D03*
X1108098Y1132638D03*
X1126326D03*
X2261450Y922300D03*
M02*
